(kicad_pcb
	(version 20240108)
	(generator "pcbnew")
	(generator_version "8.0")
	(general
		(thickness 1.62)
		(legacy_teardrops no)
	)
	(paper "A4")
	(title_block
		(title "Jetson Orin Baseboard")
		(date "2025-03-12")
		(rev "1.3.4")
		(company "Antmicro Ltd")
		(comment 1 "www.antmicro.com")
	)
	(layers
		(0 "F.Cu" signal)
		(1 "In1.Cu" signal)
		(2 "In2.Cu" signal)
		(3 "In3.Cu" signal)
		(4 "In4.Cu" jumper)
		(5 "In5.Cu" signal)
		(6 "In6.Cu" signal)
		(31 "B.Cu" signal)
		(32 "B.Adhes" user "B.Adhesive")
		(33 "F.Adhes" user "F.Adhesive")
		(34 "B.Paste" user)
		(35 "F.Paste" user)
		(36 "B.SilkS" user "B.Silkscreen")
		(37 "F.SilkS" user "F.Silkscreen")
		(38 "B.Mask" user)
		(39 "F.Mask" user)
		(40 "Dwgs.User" user "User.Drawings")
		(41 "Cmts.User" user "User.Comments")
		(42 "Eco1.User" user "User.Eco1")
		(43 "Eco2.User" user "User.Eco2")
		(44 "Edge.Cuts" user)
		(45 "Margin" user)
		(46 "B.CrtYd" user "B.Courtyard")
		(47 "F.CrtYd" user "F.Courtyard")
		(48 "B.Fab" user)
		(49 "F.Fab" user)
	)
	(setup
		(stackup
			(layer "F.SilkS"
				(type "Top Silk Screen")
				(color "White")
			)
			(layer "F.Paste"
				(type "Top Solder Paste")
			)
			(layer "F.Mask"
				(type "Top Solder Mask")
				(color "Black")
				(thickness 0.01)
			)
			(layer "F.Cu"
				(type "copper")
				(thickness 0.035)
			)
			(layer "dielectric 1"
				(type "prepreg")
				(thickness 0.12)
				(material "PR2116")
				(epsilon_r 4.3)
				(loss_tangent 0.02)
			)
			(layer "In1.Cu"
				(type "copper")
				(thickness 0.035)
			)
			(layer "dielectric 2"
				(type "core")
				(thickness 0.2)
				(material "FR4")
				(epsilon_r 4.39)
				(loss_tangent 0.02)
			)
			(layer "In2.Cu"
				(type "copper")
				(thickness 0.035)
			)
			(layer "dielectric 3"
				(type "prepreg")
				(thickness 0.12)
				(material "PR2116")
				(epsilon_r 4.39)
				(loss_tangent 0.02) addsublayer
				(thickness 0.12)
				(material "PR2116")
				(epsilon_r 4.39)
				(loss_tangent 0)
			)
			(layer "In3.Cu"
				(type "copper")
				(thickness 0.035)
			)
			(layer "dielectric 4"
				(type "core")
				(thickness 0.2)
				(material "FR4")
				(epsilon_r 4.39)
				(loss_tangent 0.02)
			)
			(layer "In4.Cu"
				(type "copper")
				(thickness 0.035)
			)
			(layer "dielectric 5"
				(type "prepreg")
				(thickness 0.12)
				(material "PR2116")
				(epsilon_r 4.39)
				(loss_tangent 0.02) addsublayer
				(thickness 0.12)
				(material "PR2116")
				(epsilon_r 4.39)
				(loss_tangent 0)
			)
			(layer "In5.Cu"
				(type "copper")
				(thickness 0.035)
			)
			(layer "dielectric 6"
				(type "core")
				(thickness 0.2)
				(material "FR4")
				(epsilon_r 4.39)
				(loss_tangent 0.02)
			)
			(layer "In6.Cu"
				(type "copper")
				(thickness 0.035)
			)
			(layer "dielectric 7"
				(type "prepreg")
				(thickness 0.12)
				(material "PR2116")
				(epsilon_r 4.3)
				(loss_tangent 0.02)
			)
			(layer "B.Cu"
				(type "copper")
				(thickness 0.035)
			)
			(layer "B.Mask"
				(type "Bottom Solder Mask")
				(color "Black")
				(thickness 0.01)
			)
			(layer "B.Paste"
				(type "Bottom Solder Paste")
			)
			(layer "B.SilkS"
				(type "Bottom Silk Screen")
				(color "White")
			)
			(copper_finish "ENIG")
			(dielectric_constraints no)
		)
		(pad_to_mask_clearance 0)
		(allow_soldermask_bridges_in_footprints no)
		(aux_axis_origin 29.75 128.75)
		(pcbplotparams
			(layerselection 0x00010fc_ffffffff)
			(plot_on_all_layers_selection 0x0000000_00000000)
			(disableapertmacros no)
			(usegerberextensions no)
			(usegerberattributes yes)
			(usegerberadvancedattributes yes)
			(creategerberjobfile yes)
			(dashed_line_dash_ratio 12.000000)
			(dashed_line_gap_ratio 3.000000)
			(svgprecision 6)
			(plotframeref no)
			(viasonmask no)
			(mode 1)
			(useauxorigin no)
			(hpglpennumber 1)
			(hpglpenspeed 20)
			(hpglpendiameter 15.000000)
			(pdf_front_fp_property_popups yes)
			(pdf_back_fp_property_popups yes)
			(dxfpolygonmode yes)
			(dxfimperialunits yes)
			(dxfusepcbnewfont yes)
			(psnegative no)
			(psa4output no)
			(plotreference yes)
			(plotvalue yes)
			(plotfptext yes)
			(plotinvisibletext no)
			(sketchpadsonfab no)
			(subtractmaskfromsilk no)
			(outputformat 1)
			(mirror no)
			(drillshape 1)
			(scaleselection 1)
			(outputdirectory "")
		)
	)
	(net 0 "")
	(net 1 "GND")
	(net 2 "CSI1_D0_N")
	(net 3 "CSI0_D0_N")
	(net 4 "CSI1_D0_P")
	(net 5 "CSI0_D0_P")
	(net 6 "CSI1_CLK_N")
	(net 7 "CSI0_CLK_N")
	(net 8 "CSI1_CLK_P")
	(net 9 "CSI0_CLK_P")
	(net 10 "CSI1_D1_N")
	(net 11 "CSI0_D1_N")
	(net 12 "CSI1_D1_P")
	(net 13 "CSI0_D1_P")
	(net 14 "CSI3_D0_N")
	(net 15 "CSI2_D0_N")
	(net 16 "CSI3_D0_P")
	(net 17 "CSI2_D0_P")
	(net 18 "CSI3_CLK_N")
	(net 19 "CSI2_CLK_N")
	(net 20 "CSI3_CLK_P")
	(net 21 "CSI2_CLK_P")
	(net 22 "CSI3_D1_N")
	(net 23 "CSI2_D1_N")
	(net 24 "CSI3_D1_P")
	(net 25 "CSI2_D1_P")
	(net 26 "DP1_TXD0_N")
	(net 27 "DP1_TXD1_P")
	(net 28 "DP1_TXD3_N")
	(net 29 "DP1_TXD3_P")
	(net 30 "SPIO_MOSI")
	(net 31 "SPIO_SCK")
	(net 32 "SPIO_MISO")
	(net 33 "~{SPI0_CS0}")
	(net 34 "~{SPI0_CS1}")
	(net 35 "DP1_AUX_N")
	(net 36 "DP1_AUX_P")
	(net 37 "SPI1_MOSI")
	(net 38 "SPI1_SCK")
	(net 39 "SPI1_MISO")
	(net 40 "USB0_D_N")
	(net 41 "~{SPI1_CS0}")
	(net 42 "~{SPI1_CS1}")
	(net 43 "GPIO01")
	(net 44 "USER_LED1")
	(net 45 "USER_BTN0")
	(net 46 "USER_BTN1")
	(net 47 "PCIE0_RX0_N")
	(net 48 "PCIE0_RX0_P")
	(net 49 "PCIE0_RX1_N")
	(net 50 "PCIE0_RX1_P")
	(net 51 "PCIE0_RX2_N")
	(net 52 "PCIE0_RX2_P")
	(net 53 "PCIE0_RX3_N")
	(net 54 "PCIE0_RX3_P")
	(net 55 "PCIE0_CLK_N")
	(net 56 "USBSS0_RX_N")
	(net 57 "PCIE0_CLK_P")
	(net 58 "USBSS0_RX_P")
	(net 59 "USBSS0_TX_N")
	(net 60 "PCIE1_RX0_N")
	(net 61 "PCIE1_RX0_P")
	(net 62 "PCIE1_CLK_N")
	(net 63 "PCIE1_CLK_P")
	(net 64 "PCIE1_CLKREQ*")
	(net 65 "PCIE1_RST*")
	(net 66 "GBE_MDI0_N")
	(net 67 "GBE_MDI0_P")
	(net 68 "GBE_MDI1_N")
	(net 69 "GBE_MDI1_P")
	(net 70 "I2S0_SDOUT")
	(net 71 "I2S0_SDIN")
	(net 72 "GBE_MDI2_N")
	(net 73 "I2S0_LRCK")
	(net 74 "GBE_MDI2_P")
	(net 75 "I2S0_SCLK")
	(net 76 "GBE_MDI3_N")
	(net 77 "GBE_MDI3_P")
	(net 78 "GPIO09")
	(net 79 "SDA_CAM")
	(net 80 "/SoM/~{FORCE_RECOVERY}")
	(net 81 "SCL_CAM")
	(net 82 "GPIO11")
	(net 83 "GPIO12")
	(net 84 "GPIO13")
	(net 85 "/SoM/PMIC_BBAT")
	(net 86 "~{RESET}")
	(net 87 "+3V3")
	(net 88 "/M.2/C_PCIE0_TX0_P")
	(net 89 "/M.2/C_PCIE0_TX0_N")
	(net 90 "/M.2/C_PCIE0_TX1_P")
	(net 91 "/M.2/C_PCIE0_TX1_N")
	(net 92 "/M.2/C_PCIE0_TX2_P")
	(net 93 "/M.2/C_PCIE0_TX2_N")
	(net 94 "/M.2/C_PCIE0_TX3_P")
	(net 95 "/M.2/C_PCIE0_TX3_N")
	(net 96 "/M.2/C_PCIE1_TX0_P")
	(net 97 "/M.2/C_PCIE1_TX0_N")
	(net 98 "EEPROM_PWR")
	(net 99 "+5V")
	(net 100 "CAN_RX")
	(net 101 "CAN_TX")
	(net 102 "GPIO07")
	(net 103 "PCIE2_RST*")
	(net 104 "PCIE2_CLKREQ*")
	(net 105 "/Ethernet/VDD")
	(net 106 "GNDD")
	(net 107 "USBSS1_RX_N")
	(net 108 "/CSI/CSIA_3V3")
	(net 109 "/CSI/CSIA_5V")
	(net 110 "/CSI/CSIB_3V3")
	(net 111 "/CSI/CSIB_5V")
	(net 112 "+1V8")
	(net 113 "PCIE2_RX0_N")
	(net 114 "USBSS1_RX_P")
	(net 115 "VCC")
	(net 116 "USB_FLASH_ID")
	(net 117 "3V3_STDB")
	(net 118 "UART0_RTS")
	(net 119 "UART0_CTS")
	(net 120 "PCIE3_RST*")
	(net 121 "/Ethernet/PAIR_12")
	(net 122 "/Ethernet/PAIR_36")
	(net 123 "/Ethernet/PAIR_78")
	(net 124 "/Ethernet/PAIR_910")
	(net 125 "/USB Debug, DP/USBC0_RX2_N")
	(net 126 "Net-(U5-~{RESET})")
	(net 127 "/Ethernet/POE_ACTIVE")
	(net 128 "PCIE3_CLKREQ*")
	(net 129 "I2C2_SCL")
	(net 130 "I2C2_SDA")
	(net 131 "PCIE2_RX0_P")
	(net 132 "USBSS1_TX_N")
	(net 133 "/USB Debug, DP/PDC_LDO_1V8")
	(net 134 "/USB Debug, DP/PDC_LDO_3V3")
	(net 135 "Net-(Q18-G)")
	(net 136 "Net-(J6-P4)")
	(net 137 "Net-(D36-A)")
	(net 138 "/Supply/3V3_LDO")
	(net 139 "/Supply/1V8_LDO")
	(net 140 "Net-(D1-C)")
	(net 141 "Net-(D1-A)")
	(net 142 "Net-(D2-A)")
	(net 143 "Net-(D3-A)")
	(net 144 "Net-(D4-A)")
	(net 145 "Net-(D5-A)")
	(net 146 "Net-(D8-A)")
	(net 147 "Net-(D9-A)")
	(net 148 "Net-(D12-Pad1)")
	(net 149 "Net-(D12-Pad2)")
	(net 150 "Net-(D11-A)")
	(net 151 "/USB Debug, DP/USBC0_RX2_P")
	(net 152 "/USB Debug, DP/USBC0_RX1_N")
	(net 153 "Net-(D15-A)")
	(net 154 "/USB Debug, DP/USBC0_RX1_P")
	(net 155 "Net-(D18-A)")
	(net 156 "PCIE2_TX0_N")
	(net 157 "USBSS1_TX_P")
	(net 158 "PCIE2_TX0_P")
	(net 159 "USBSS2_RX_N")
	(net 160 "Net-(D20-A)")
	(net 161 "Net-(D24-A)")
	(net 162 "Net-(D25-A)")
	(net 163 "PCIE2_CLK_N")
	(net 164 "Net-(D26-C)")
	(net 165 "USBSS2_RX_P")
	(net 166 "PCIE2_CLK_P")
	(net 167 "USBSS2_TX_N")
	(net 168 "/SoM/DEBUG_TXD_1V8")
	(net 169 "/M.2/~{LED1}")
	(net 170 "/M.2/M2_E_PCM_CLK")
	(net 171 "/M.2/PCIE_WAKE_SEL1")
	(net 172 "PCIE2_RX1_N")
	(net 173 "USBSS2_TX_P")
	(net 174 "Net-(D36-C)")
	(net 175 "PCIE2_RX1_P")
	(net 176 "/M.2/M2_E_PCM_SYNC")
	(net 177 "/Supply/3V3_VDD")
	(net 178 "/M.2/M2_E_PCM_OUT")
	(net 179 "Net-(D61-A)")
	(net 180 "Net-(D26-A)")
	(net 181 "Net-(D27-C)")
	(net 182 "Net-(D27-A)")
	(net 183 "/M.2/~{M2_E_UART_WAKE}")
	(net 184 "Net-(D51-A)")
	(net 185 "/USB Debug, DP/FTDI_3V3")
	(net 186 "/USB Debug, DP/USBSS0_RX_C_N")
	(net 187 "/USB Debug, DP/USBSS0_TX_C_N")
	(net 188 "/M.2/M2_E_UART_TX")
	(net 189 "Net-(D28-C)")
	(net 190 "unconnected-(J1-SDIO_CLK-Pad9)")
	(net 191 "unconnected-(J1-SDIO_CMD-Pad11)")
	(net 192 "/M.2/M2_E_UART_RX")
	(net 193 "/USB Debug, DP/USBSS0_RX_C_P")
	(net 194 "/USB Debug, DP/USBSS0_TX_C_P")
	(net 195 "/M.2/M2_E_UART_RTS")
	(net 196 "/USB Debug, DP/USBC3_VBUS")
	(net 197 "/USB Debug, DP/USBC0_TX1_N")
	(net 198 "/USB Debug, DP/USBC0_CONN_TX1_N")
	(net 199 "/M.2/M2_E_UART_CTS")
	(net 200 "/USB Debug, DP/USBC0_TX2_N")
	(net 201 "/USB Debug, DP/USBC0_CONN_TX2_N")
	(net 202 "unconnected-(J1-SDIO_D0-Pad13)")
	(net 203 "unconnected-(J1-SDIO_D1-Pad15)")
	(net 204 "/CSI/CSI1_0_D1_N")
	(net 205 "/CSI/CSI1_0_D1_P")
	(net 206 "/CSI/CSI1_0_D0_N")
	(net 207 "/CSI/CSI1_0_D0_P")
	(net 208 "unconnected-(J1-SDIO_D2-Pad17)")
	(net 209 "unconnected-(J1-SDIO_D3-Pad19)")
	(net 210 "unconnected-(J1-SDIO_~{WAKE}-Pad21)")
	(net 211 "unconnected-(J1-SDIO_~{RESET}-Pad23)")
	(net 212 "/CSI/CSI3_0_D1_N")
	(net 213 "/CSI/CSI3_0_D1_P")
	(net 214 "/CSI/CSI3_0_D0_N")
	(net 215 "/CSI/CSI3_0_D0_P")
	(net 216 "/M.2/M2_E_SUSCLK")
	(net 217 "VSYNC_CAM0")
	(net 218 "/M.2/M2_E_W_DIS_2")
	(net 219 "VSYNC_CAM1")
	(net 220 "/M.2/M2_E_W_DIS_1")
	(net 221 "/M.2/M2_E_I2C_DAT")
	(net 222 "unconnected-(J1-VENDOR_1-Pad38)")
	(net 223 "/M.2/M2_E_I2C_CLK")
	(net 224 "unconnected-(J1-VENDOR_2-Pad40)")
	(net 225 "/M.2/~{M2_E_ALERT}")
	(net 226 "unconnected-(J1-VENDOR_3-Pad42)")
	(net 227 "unconnected-(J1-COEX3-Pad44)")
	(net 228 "unconnected-(J1-COEX_TXD-Pad46)")
	(net 229 "unconnected-(J1-COEX_RXD-Pad48)")
	(net 230 "unconnected-(J1-PET1_P-Pad59)")
	(net 231 "unconnected-(J1-PET1_N-Pad61)")
	(net 232 "unconnected-(J1-RFU-Pad64)")
	(net 233 "unconnected-(J1-PER1_P-Pad65)")
	(net 234 "/CSI/CSI1_1_D0_N")
	(net 235 "/CSI/CSI1_1_D0_P")
	(net 236 "/CSI/CSI1_1_D1_N")
	(net 237 "/CSI/CSI1_1_D1_P")
	(net 238 "/CSI/CSI3_1_D1_N")
	(net 239 "/CSI/CSI3_1_D1_P")
	(net 240 "/CSI/CSI3_1_D0_N")
	(net 241 "/CSI/CSI3_1_D0_P")
	(net 242 "VSYNC_CAM2")
	(net 243 "VSYNC_CAM3")
	(net 244 "/M.2/M2_M_SMB_CLK")
	(net 245 "/M.2/M2_M_SMB_DATA")
	(net 246 "/M.2/~{M2_M_ALERT}")
	(net 247 "/M.2/~{M2_M_PERST}")
	(net 248 "/M.2/~{M2_M_CLKREQ0}")
	(net 249 "/M.2/~{M2_M_PEWAKE0}")
	(net 250 "/M.2/M2_M_SUSCLK")
	(net 251 "SYS_SDA")
	(net 252 "SYS_SCL")
	(net 253 "~{PDC_CS}")
	(net 254 "PDC_SCLK")
	(net 255 "PDC_MISO")
	(net 256 "PDC_MOSI")
	(net 257 "/USB Debug, DP/USBC0_TX1_P")
	(net 258 "/USB Debug, DP/USBC0_CONN_TX1_P")
	(net 259 "/USB Debug, DP/USBC0_TX2_P")
	(net 260 "/USB Debug, DP/USBC0_CONN_TX2_P")
	(net 261 "/USB Debug, DP/USBC0_VBUS")
	(net 262 "/USB3/USBC1_TX2_N")
	(net 263 "/USB3/USBC1_CONN_TX2_N")
	(net 264 "/USB3/USBC1_TX1_N")
	(net 265 "/USB3/USBC1_CONN_TX1_N")
	(net 266 "/USB3/USBC1_TX1_P")
	(net 267 "/USB3/USBC1_CONN_TX1_P")
	(net 268 "/USB3/USBC1_TX2_P")
	(net 269 "/USB3/USBC1_CONN_TX2_P")
	(net 270 "/USB3/USBC1_VBUS")
	(net 271 "/USB Debug, DP/FTDI_LED_TX")
	(net 272 "/USB Debug, DP/FTDI_LED_RX")
	(net 273 "/USB Debug, DP/USBC3_CC1")
	(net 274 "DP1_TXD0_HDMI_TX2_N")
	(net 275 "/USB Debug, DP/USBC3_D_N")
	(net 276 "/USB Debug, DP/USBC3_CC2")
	(net 277 "/USB Debug, DP/USBC0_CC1")
	(net 278 "/USB Debug, DP/USBC0_CC2")
	(net 279 "PWR_SOFT")
	(net 280 "unconnected-(J1-UIM_SWP-Pad66)")
	(net 281 "~{GPIO_INT}")
	(net 282 "/USB3/USBC1_CC1")
	(net 283 "/USB3/USBC1_CC2")
	(net 284 "/USB3/USBC1_ID")
	(net 285 "/USB Debug, DP/PDC_RESET")
	(net 286 "/USB Debug, DP/PDC_ADCIN1")
	(net 287 "/USB Debug, DP/PDC_ADCIN2")
	(net 288 "unconnected-(J1-PER1_N-Pad67)")
	(net 289 "unconnected-(J1-UIM_POWER_SNK-Pad68)")
	(net 290 "unconnected-(J1-UIM_POWER_SRC-Pad70)")
	(net 291 "unconnected-(J1-REFCLK1_P-Pad71)")
	(net 292 "unconnected-(J1-REFCLK1_N-Pad73)")
	(net 293 "/USB Debug, DP/USBC0_FLIP")
	(net 294 "/USB Debug, DP/PDC_CTL1")
	(net 295 "/USB Debug, DP/USBC0_CTL0")
	(net 296 "/USB Debug, DP/PDC_FLIP")
	(net 297 "/USB Debug, DP/USBC0_CTL1")
	(net 298 "/USB Debug, DP/PDC_CTL0")
	(net 299 "/USB Debug, DP/PDC_I2C3_SDA")
	(net 300 "/USB Debug, DP/PDC_GPIO14")
	(net 301 "/USB Debug, DP/PDC_GPIO15")
	(net 302 "/USB Debug, DP/PDC_I2C1_SCL")
	(net 303 "/USB Debug, DP/PDC_I2C1_SDA")
	(net 304 "/USB Debug, DP/USBC0_I2C_EN")
	(net 305 "/USB Debug, DP/USBC0_SSEQ0")
	(net 306 "/USB Debug, DP/USBC0_SSEQ1")
	(net 307 "/USB Debug, DP/USBC0_DPEQ0")
	(net 308 "/USB Debug, DP/USBC0_DPEQ1")
	(net 309 "/USB Debug, DP/USBC0_EQ0")
	(net 310 "/USB Debug, DP/USBC0_EQ1")
	(net 311 "CSIA_FLG")
	(net 312 "/USB Debug, DP/USB_FTDI_N")
	(net 313 "/USB Debug, DP/USB_FTDI_P")
	(net 314 "/USB3/USBC1_ADDR")
	(net 315 "/USB3/USBC1_PORT")
	(net 316 "/USB3/USBC1_I_MODE")
	(net 317 "/USB3/~{USBC1_INT}")
	(net 318 "/USB3/~{USBC1_EN_MUX}")
	(net 319 "/USB3/~{USBC1_EN_CC}")
	(net 320 "/CSI/SDA_CAM0")
	(net 321 "/CSI/CSIA_I2C_VCC")
	(net 322 "CSIA_PEN")
	(net 323 "/CSI/SCL_CAM0")
	(net 324 "/CSI/I2C_MUX_RESET")
	(net 325 "/CSI/I2C_MUX_A0")
	(net 326 "unconnected-(J7-Pad13)")
	(net 327 "/SoM/DEBUG_RXD_1V8")
	(net 328 "/Supply/VCC_IN")
	(net 329 "/CSI/SDA_CAM1")
	(net 330 "/CSI/SCL_CAM1")
	(net 331 "/CSI/SDA_CAM2")
	(net 332 "unconnected-(J2-NC-Pad6)")
	(net 333 "/CSI/SCL_CAM2")
	(net 334 "/CSI/CSIA_5V_ISET")
	(net 335 "/CSI/CSIA_3V3_ISET")
	(net 336 "/CSI/SDA_CAM3")
	(net 337 "/CSI/SCL_CAM3")
	(net 338 "CSIB_PEN")
	(net 339 "unconnected-(J7-Pad14)")
	(net 340 "unconnected-(J7-Pad16)")
	(net 341 "unconnected-(J2-NC-Pad8)")
	(net 342 "Net-(D37-C)")
	(net 343 "/CSI/CSIB_5V_ISET")
	(net 344 "/CSI/CSIB_3V3_ISET")
	(net 345 "/Peripherals/PCIE2_RST_CONN*")
	(net 346 "/Peripherals/PCIE2_CLKREQ_CONN*")
	(net 347 "/Peripherals/PCIE3_RST_CONN*")
	(net 348 "/Peripherals/GPIO01_CONN")
	(net 349 "/Peripherals/GPIOEX_I2C_SDA")
	(net 350 "/Peripherals/GPIOEX_I2C_SCL")
	(net 351 "/Peripherals/GPIOEX_RESET")
	(net 352 "/Peripherals/GPIOEX_ADDR")
	(net 353 "/Peripherals/GPIOEX_P0_0")
	(net 354 "/Peripherals/GPIOEX_P0_1")
	(net 355 "/Peripherals/GPIOEX_P0_2")
	(net 356 "/Peripherals/GPIOEX_P0_3")
	(net 357 "PCIE2_TX1_N")
	(net 358 "/Supply/3V3_BOOT")
	(net 359 "unconnected-(J2-NC-Pad20)")
	(net 360 "/CSI/VSYNC_CAM0_3V3")
	(net 361 "unconnected-(J7-Pad33)")
	(net 362 "/USB3/USBC1_I2C_SDA")
	(net 363 "/USB3/USBC1_ISC_SCL")
	(net 364 "/USB3/USBC1_DIR")
	(net 365 "/USB3/USBC1_VBUS_DET")
	(net 366 "/USB3/USBC1_RX1_N")
	(net 367 "DP1_TXD0_HDMI_TX2_P")
	(net 368 "/USB3/USBC1_RX1_P")
	(net 369 "/USB3/USBC1_RX2_N")
	(net 370 "PCIE2_TX1_P")
	(net 371 "/CSI/VSYNC_CAM1_3V3")
	(net 372 "unconnected-(J7-Pad35)")
	(net 373 "unconnected-(J7-Pad36)")
	(net 374 "unconnected-(J7-Pad37)")
	(net 375 "DP1_TXD1_HDMI_TX1_N")
	(net 376 "unconnected-(J7-Pad38)")
	(net 377 "unconnected-(J7-Pad43)")
	(net 378 "unconnected-(J7-Pad44)")
	(net 379 "unconnected-(J7-Pad45)")
	(net 380 "unconnected-(J7-Pad46)")
	(net 381 "unconnected-(J8-Pad1)")
	(net 382 "unconnected-(J8-Pad2)")
	(net 383 "unconnected-(J8-Pad3)")
	(net 384 "unconnected-(J8-Pad4)")
	(net 385 "unconnected-(J8-Pad13)")
	(net 386 "unconnected-(J8-Pad14)")
	(net 387 "unconnected-(J8-Pad16)")
	(net 388 "unconnected-(J8-Pad17)")
	(net 389 "unconnected-(J8-Pad19)")
	(net 390 "/USB3/USBC1_RX2_P")
	(net 391 "/USB3/USBC1_FAULT_N")
	(net 392 "unconnected-(J8-Pad20)")
	(net 393 "CSIB_FLG")
	(net 394 "/USB Debug, DP/PDC_I2C2_IRQn")
	(net 395 "/USB Debug, DP/PDC_I2C2_SCL")
	(net 396 "/USB Debug, DP/PDC_I2C2_SDA")
	(net 397 "/USB Debug, DP/FTDI_CBUS_EN")
	(net 398 "/USB Debug, DP/FTDI_CBUS3{slash}SCL")
	(net 399 "unconnected-(J8-Pad21)")
	(net 400 "unconnected-(J8-Pad22)")
	(net 401 "unconnected-(J8-Pad31)")
	(net 402 "/CSI/VSYNC_CAM3_3V3")
	(net 403 "/USB Debug, DP/DRAIN2")
	(net 404 "/USB Debug, DP/DRAIN1")
	(net 405 "unconnected-(J8-Pad33)")
	(net 406 "/CSI/VSYNC_CAM2_3V3")
	(net 407 "unconnected-(J8-Pad35)")
	(net 408 "unconnected-(J8-Pad36)")
	(net 409 "unconnected-(J8-Pad37)")
	(net 410 "unconnected-(J8-Pad38)")
	(net 411 "/Peripherals/PCIE2_TX0_CONN_N")
	(net 412 "/Peripherals/PCIE2_TX0_CONN_P")
	(net 413 "/Peripherals/PCIE2_TX1_CONN_P")
	(net 414 "/Peripherals/USBSS2_TX_CONN_P")
	(net 415 "/Peripherals/PCIE2_TX1_CONN_N")
	(net 416 "/Peripherals/USBSS2_TX_CONN_N")
	(net 417 "DP1_TXD1_HDMI_TX1_P")
	(net 418 "DP1_TXD2_HDMI_TX0_N")
	(net 419 "DP1_TXD2_HDMI_TX0_P")
	(net 420 "DP1_TXD3_HDMI_TXC_N")
	(net 421 "unconnected-(J8-Pad43)")
	(net 422 "DP1_TXD3_HDMI_TXC_P")
	(net 423 "unconnected-(J8-Pad44)")
	(net 424 "Net-(D38-A)")
	(net 425 "unconnected-(J8-Pad45)")
	(net 426 "unconnected-(J8-Pad46)")
	(net 427 "PCIE_WAKE_SEL_EXT")
	(net 428 "DP1_HPD")
	(net 429 "DP1_HDMI_AUX_P")
	(net 430 "DP1_HDMI_AUX_N")
	(net 431 "unconnected-(J2-NC-Pad22)")
	(net 432 "unconnected-(J2-NC-Pad24)")
	(net 433 "USB0_D_P")
	(net 434 "USB1_D_N")
	(net 435 "unconnected-(J2-NC-Pad26)")
	(net 436 "USB1_D_P")
	(net 437 "USB2_D_N")
	(net 438 "/SoM/SoM_VIN")
	(net 439 "USB2_D_P")
	(net 440 "USER_LED0")
	(net 441 "PCIE0_TX0_N")
	(net 442 "PCIE0_TX0_P")
	(net 443 "PCIE0_TX1_N")
	(net 444 "PCIE0_TX1_P")
	(net 445 "PCIE0_TX2_N")
	(net 446 "PCIE0_TX2_P")
	(net 447 "PCIE0_TX3_N")
	(net 448 "PCIE0_TX3_P")
	(net 449 "USBSS0_TX_P")
	(net 450 "PCIE1_TX0_N")
	(net 451 "PCIE1_TX0_P")
	(net 452 "/SoM/~{MOD_SLEEP}")
	(net 453 "PCIE_WAKE*")
	(net 454 "PCIE0_CLKREQ*")
	(net 455 "PCIE0_RST*")
	(net 456 "/M.2/32.7KHZ_OUT")
	(net 457 "GBE_LED_LINK")
	(net 458 "unconnected-(J2-NC-Pad28)")
	(net 459 "GBE_LED_ACT")
	(net 460 "UART1_TXD")
	(net 461 "UART1_RXD")
	(net 462 "unconnected-(J2-NC-Pad30)")
	(net 463 "FAN_TACH")
	(net 464 "unconnected-(J2-NC-Pad32)")
	(net 465 "unconnected-(R59-Pad1)")
	(net 466 "unconnected-(J2-NC-Pad34)")
	(net 467 "I2S1_SDOUT")
	(net 468 "I2S1_SDIN")
	(net 469 "I2S1_LRCK")
	(net 470 "I2S1_SCLK")
	(net 471 "PCIE3_CLK_N")
	(net 472 "PCIE3_CLK_P")
	(net 473 "FAN_PWM")
	(net 474 "~{SHUTDOWN_REQ}")
	(net 475 "DEBUG_TXD")
	(net 476 "POWER_EN")
	(net 477 "DEBUG_RXD")
	(net 478 "/SoM/SLEEP{slash}~{WAKE}")
	(net 479 "/Peripherals/5V_CONN")
	(net 480 "USBPD1_HV")
	(net 481 "USBPD2_HV")
	(net 482 "/Peripherals/3V3_CONN")
	(net 483 "/Peripherals/1V8_CONN")
	(net 484 "/Peripherals/3V3_STDB_CONN")
	(net 485 "/Peripherals/VCC_CONN")
	(net 486 "/HDMI/HDMI_D2_N")
	(net 487 "/HDMI/HDMI_D1_N")
	(net 488 "/HDMI/HDMI_D0_N")
	(net 489 "/HDMI/HDMI_CLK_N")
	(net 490 "DP1_TXD1_N")
	(net 491 "DP1_TXD2_N")
	(net 492 "/HDMI/HDMI_D2_P")
	(net 493 "/HDMI/HDMI_D1_P")
	(net 494 "/HDMI/HDMI_D0_P")
	(net 495 "/HDMI/HDMI_CLK_P")
	(net 496 "DP1_TXD0_P")
	(net 497 "DP1_TXD2_P")
	(net 498 "/HDMI/5V_HDMI")
	(net 499 "/Ethernet/VSS")
	(net 500 "POE_OUTPUT")
	(net 501 "/USB Debug, DP/USBC3_FLG")
	(net 502 "/USB Debug, DP/HPDIN")
	(net 503 "unconnected-(J2-NC-Pad36)")
	(net 504 "unconnected-(J2-NC-Pad38)")
	(net 505 "USBC0_FLG")
	(net 506 "unconnected-(J2-NC-Pad46)")
	(net 507 "unconnected-(J2-NC-Pad48)")
	(net 508 "USBC1_FLG")
	(net 509 "unconnected-(J2-NC-Pad56)")
	(net 510 "unconnected-(J2-NC-Pad58)")
	(net 511 "/CSI/I2C_MUX_SDA")
	(net 512 "/CSI/I2C_MUX_SCL")
	(net 513 "/Peripherals/PCIE3_CLKREQ_CONN*")
	(net 514 "DISABLE_POE_DCDC")
	(net 515 "/Peripherals/GPIO07_CONN")
	(net 516 "UART0_RXD")
	(net 517 "UART0_TXD")
	(net 518 "/HDMI/HDMI_SDA_5V")
	(net 519 "/HDMI/HDMI_SCL_5V")
	(net 520 "/HDMI/HDMI_CEC_5V")
	(net 521 "/HDMI/HDMI_CLK_CONN_N")
	(net 522 "/HDMI/HDMI_CLK_CONN_P")
	(net 523 "/HDMI/HDMI_D0_CONN_N")
	(net 524 "/HDMI/HDMI_D0_CONN_P")
	(net 525 "/HDMI/HDMI_D1_CONN_N")
	(net 526 "/HDMI/HDMI_D1_CONN_P")
	(net 527 "/HDMI/HDMI_D2_CONN_N")
	(net 528 "/HDMI/HDMI_D2_CONN_P")
	(net 529 "/HDMI/HDMI_HPD_5V")
	(net 530 "Net-(R256-Pad1)")
	(net 531 "unconnected-(J2-NC-Pad67)")
	(net 532 "unconnected-(J2-NC-Pad69)")
	(net 533 "unconnected-(J3-SBU_{1}-PadA8)")
	(net 534 "unconnected-(SW1-Pad1)")
	(net 535 "/CSI/MUX_I2C_4_SDA")
	(net 536 "/CSI/MUX_I2C_4_SCL")
	(net 537 "/CSI/MUX_I2C_5_SDA")
	(net 538 "/CSI/MUX_I2C_5_SCL")
	(net 539 "/CSI/MUX_I2C_6_SDA")
	(net 540 "/Peripherals/FAN_PWM_5V")
	(net 541 "/Peripherals/FAN_TACH_5V")
	(net 542 "/CSI/MUX_I2C_6_SCL")
	(net 543 "/CSI/MUX_I2C_7_SDA")
	(net 544 "/CSI/MUX_I2C_7_SCL")
	(net 545 "/Peripherals/GPIOEX_P0_7")
	(net 546 "/Peripherals/GPIOEX_P0_6")
	(net 547 "unconnected-(J3-SBU_{2}-PadB8)")
	(net 548 "unconnected-(J5-SBU_{1}-PadA8)")
	(net 549 "/USB Debug, DP/USBC3_5V_PEN")
	(net 550 "unconnected-(J5-SBU_{2}-PadB8)")
	(net 551 "Net-(J6-LED_GRN-)")
	(net 552 "Net-(J6-LED_YEL-)")
	(net 553 "/USB Debug, DP/USBC0_5V_PEN")
	(net 554 "Net-(R50-R1.2)")
	(net 555 "/HDMI/HDMI_SCL_3V3")
	(net 556 "/HDMI/DP_MUX_D0-")
	(net 557 "unconnected-(U13-Pad4)")
	(net 558 "unconnected-(U13-Pad5)")
	(net 559 "Net-(R50-R2.2)")
	(net 560 "Net-(R50-R3.2)")
	(net 561 "/M.2/PCIE_WAKE_SEL0")
	(net 562 "USBC1_PEN")
	(net 563 "Net-(R50-R4.2)")
	(net 564 "/USB3/USBC1_ISET")
	(net 565 "/Ethernet/AMPS_CTL")
	(net 566 "/Ethernet/REF")
	(net 567 "/Ethernet/MPS_DUTY")
	(net 568 "/Ethernet/CLSA")
	(net 569 "/Ethernet/CLSB")
	(net 570 "/Ethernet/DEN")
	(net 571 "/Ethernet/PG")
	(net 572 "/Ethernet/TPH")
	(net 573 "/Ethernet/TPL")
	(net 574 "/Ethernet/~{BT}")
	(net 575 "Net-(R51-R1.2)")
	(net 576 "/HDMI/HDMI_HPD_5V_R")
	(net 577 "Net-(R51-R2.2)")
	(net 578 "/Peripherals/PCIE_WAKE_SEL_EXT_CONN")
	(net 579 "/Peripherals/GPIO09_CONN")
	(net 580 "/Peripherals/GPIO13_CONN")
	(net 581 "/Peripherals/GPIO12_CONN")
	(net 582 "/Peripherals/UART1_TXD_CONN")
	(net 583 "/Peripherals/GPIO11_CONN")
	(net 584 "/Peripherals/UART1_RXD_CONN")
	(net 585 "/Peripherals/I2S0_SDIN_CONN")
	(net 586 "/Peripherals/I2S0_SCLK_CONN")
	(net 587 "/Peripherals/I2S0_LRCK_CONN")
	(net 588 "/Peripherals/I2S0_SDOUT_CONN")
	(net 589 "/Peripherals/SPIO_SCK_CONN")
	(net 590 "/Peripherals/SPI1_SCK_CONN")
	(net 591 "/Peripherals/SPIO_MOSI_CONN")
	(net 592 "/Peripherals/SPI1_MOSI_CONN")
	(net 593 "/Peripherals/SPIO_MISO_CONN")
	(net 594 "/Peripherals/SPI1_MISO_CONN")
	(net 595 "/Peripherals/~{SPI0_CS0_CONN}")
	(net 596 "Net-(J11-Pad63)")
	(net 597 "Net-(J11-Pad64)")
	(net 598 "Net-(J11-Pad65)")
	(net 599 "Net-(J11-Pad66)")
	(net 600 "Net-(J11-Pad68)")
	(net 601 "Net-(J11-Pad70)")
	(net 602 "Net-(R51-R3.2)")
	(net 603 "Net-(R51-R4.2)")
	(net 604 "/Peripherals/GPIOEX_P0_5")
	(net 605 "/Peripherals/GPIOEX_P0_4")
	(net 606 "/Peripherals/~{SPI1_CS0_CONN}")
	(net 607 "/Peripherals/~{SPI0_CS1_CONN}")
	(net 608 "/Peripherals/~{SPI1_CS1_CONN}")
	(net 609 "/USB3/USBSS1_C_RX_N")
	(net 610 "/USB3/USBSS1_C_TX_N")
	(net 611 "/USB3/USBSS1_C_RX_P")
	(net 612 "/USB3/USBSS1_C_TX_P")
	(net 613 "/USB Debug, DP/USBC3_D_P")
	(net 614 "/USB Debug, DP/USBC0_SBU_P")
	(net 615 "/USB Debug, DP/USBC0_SBU_N")
	(net 616 "/M.2/USB_E_P")
	(net 617 "/M.2/USB_E_N")
	(net 618 "/Peripherals/USB_CONN_N")
	(net 619 "/Peripherals/USB_CONN_P")
	(net 620 "unconnected-(J13-UTIL{slash}HEAC+-Pad17)")
	(net 621 "Net-(Q1-S)")
	(net 622 "Net-(Q1-D)")
	(net 623 "Net-(Q2-D)")
	(net 624 "Net-(Q3-D)")
	(net 625 "Net-(Q4-D)")
	(net 626 "unconnected-(J7-Pad17)")
	(net 627 "unconnected-(J7-Pad31)")
	(net 628 "Net-(Q11-G)")
	(net 629 "Net-(D37-A)")
	(net 630 "Net-(Q15-G)")
	(net 631 "Net-(Q16-G)")
	(net 632 "Net-(Q19-G)")
	(net 633 "unconnected-(R33-R4.1-Pad4)")
	(net 634 "unconnected-(R33-R4.2-Pad5)")
	(net 635 "/M.2/3V3_M2")
	(net 636 "/CSI/CSIB_I2C_VCC")
	(net 637 "unconnected-(R53-R3.1-Pad3)")
	(net 638 "unconnected-(R53-R4.1-Pad4)")
	(net 639 "/USB Debug, DP/PDC_I2C3_SCL")
	(net 640 "unconnected-(R53-R4.2-Pad5)")
	(net 641 "/Supply/3V3_OUT")
	(net 642 "/Supply/3V3_VDRV")
	(net 643 "/Supply/3V3_SW")
	(net 644 "Net-(U48-DVDT)")
	(net 645 "unconnected-(R53-R3.2-Pad6)")
	(net 646 "Net-(U5-TXD)")
	(net 647 "Net-(U5-RXD)")
	(net 648 "Net-(U5-~{RTS})")
	(net 649 "Net-(U5-~{CTS})")
	(net 650 "/Ethernet/ULS-12_CTRL")
	(net 651 "/M.2/M2_E_PCM_IN")
	(net 652 "/M.2/~{LED2}")
	(net 653 "Net-(D52-A)")
	(net 654 "Net-(D53-A)")
	(net 655 "unconnected-(R63-R4.1-Pad4)")
	(net 656 "unconnected-(R63-R4.2-Pad5)")
	(net 657 "Net-(U9-EN)")
	(net 658 "/Peripherals/I2C_CONN_PEN")
	(net 659 "I2C1_SCL")
	(net 660 "I2C1_SDA")
	(net 661 "Net-(D54-A)")
	(net 662 "/Peripherals/I2C_CONN_3V3")
	(net 663 "/HDMI/DP_MUX_D1-")
	(net 664 "/HDMI/DP_MUX_D2-")
	(net 665 "/HDMI/DP_MUX_D0+")
	(net 666 "/HDMI/DP_MUX_D1+")
	(net 667 "/HDMI/DP_MUX_D2+")
	(net 668 "/HDMI/DP_MUX_AUX_B-")
	(net 669 "/HDMI/DP_MUX_AUX_B+")
	(net 670 "/USB Debug, DP/PDC_HPD2")
	(net 671 "/Peripherals/SCK")
	(net 672 "Net-(U9-ISET)")
	(net 673 "Net-(U12-EN)")
	(net 674 "unconnected-(R102-R1.1-Pad1)")
	(net 675 "unconnected-(R102-R2.1-Pad2)")
	(net 676 "unconnected-(R102-R2.2-Pad7)")
	(net 677 "USBC_HPD")
	(net 678 "/HDMI/DP_MUX_EN")
	(net 679 "/HDMI/DP_MUX_AUX_A+")
	(net 680 "/HDMI/DP_MUX_AUX_A-")
	(net 681 "unconnected-(R102-R1.2-Pad8)")
	(net 682 "Net-(U12-ISET)")
	(net 683 "Net-(U23-TRIM)")
	(net 684 "/Supply/3V3_MODE2")
	(net 685 "Net-(U35-ISET)")
	(net 686 "Net-(U36-SEL1)")
	(net 687 "/Supply/3V3_MODE1")
	(net 688 "Net-(U38-CLK)")
	(net 689 "Net-(U38-Q)")
	(net 690 "Net-(U42-EN)")
	(net 691 "Net-(U6A-GPIO3{slash}HPD1)")
	(net 692 "Net-(U10-CAD_SNK{slash}RSVD1)")
	(net 693 "unconnected-(U6A-GPIO12-Pad40)")
	(net 694 "unconnected-(U6A-GPIO13-Pad41)")
	(net 695 "unconnected-(U6B-C1_USB_P{slash}GPIO18-Pad50)")
	(net 696 "unconnected-(U6B-C1_USB_N{slash}GPIO19-Pad53)")
	(net 697 "unconnected-(U6C-C2_USB_P{slash}GPIO20-Pad54)")
	(net 698 "unconnected-(U6C-C2_USB_N{slash}GPIO21-Pad55)")
	(net 699 "/HDMI/DP_MUX_D3-")
	(net 700 "/HDMI/DP_MUX_D3+")
	(net 701 "/HDMI/HDMI_SDA_3V3")
	(net 702 "unconnected-(U8-NC-Pad2)")
	(net 703 "/HDMI/HDMI_HPD")
	(net 704 "unconnected-(U22-~{AUTCLS}-Pad10)")
	(net 705 "unconnected-(U22-NC-Pad14)")
	(net 706 "unconnected-(U22-NC-Pad15)")
	(net 707 "unconnected-(U22-IRSHDL_EN-Pad16)")
	(net 708 "/USB Debug, DP/~{PDC_I2C3_IRQ}")
	(net 709 "unconnected-(U22-NC-Pad20)")
	(net 710 "unconnected-(U26-EP-Pad25)")
	(net 711 "/Supply/3V3_FB")
	(net 712 "/Supply/5V_EN")
	(net 713 "/USB Debug, DP/PDC_I2C1_IRQn")
	(net 714 "GPIO010")
	(net 715 "Net-(C78-Pad1)")
	(net 716 "unconnected-(U34-EP-Pad17)")
	(net 717 "Net-(Q13-Pad2)")
	(net 718 "Net-(Q14-Pad2)")
	(net 719 "unconnected-(U35-FLG-Pad3)")
	(net 720 "unconnected-(U36-NC-Pad9)")
	(net 721 "unconnected-(U36-CEC-Pad15)")
	(net 722 "unconnected-(U36-CEC_A-Pad18)")
	(net 723 "unconnected-(U36-CEC_B-Pad20)")
	(net 724 "unconnected-(U36-NC-Pad30)")
	(net 725 "unconnected-(U41-NC-Pad2)")
	(net 726 "unconnected-(J10-PadMP1)")
	(net 727 "unconnected-(J10-PadMP2)")
	(net 728 "unconnected-(U7-PadEP)")
	(net 729 "unconnected-(U42-NC-Pad4)")
	(net 730 "Net-(R155-Pad2)")
	(net 731 "Net-(R156-Pad1)")
	(net 732 "Net-(BT1-+)")
	(net 733 "unconnected-(J15B-DSI_D0_N-Pad70)")
	(net 734 "unconnected-(J15B-DSI_D0_P-Pad72)")
	(net 735 "unconnected-(J15B-DSI_CLK_N-Pad76)")
	(net 736 "unconnected-(J15B-DSI_CLK_P-Pad78)")
	(net 737 "unconnected-(J15B-DSI_D1_N-Pad82)")
	(net 738 "unconnected-(J15B-DSI_D1_P-Pad84)")
	(net 739 "unconnected-(J15E-DP0_HPD-Pad88)")
	(net 740 "unconnected-(J15E-DP0_AUX_N-Pad90)")
	(net 741 "unconnected-(J15E-DP0_AUX_P-Pad92)")
	(net 742 "Net-(J15E-HDMI_CEC)")
	(net 743 "Net-(J15B-CAM0_PWDN)")
	(net 744 "Net-(J15B-CAM0_MCLK)")
	(net 745 "Net-(J15B-CAM1_PWDN)")
	(net 746 "Net-(J15B-CAM1_MCLK)")
	(net 747 "Net-(J15H-GPIO02)")
	(net 748 "unconnected-(J15C-~{UART1_RTS}-Pad207)")
	(net 749 "unconnected-(J15C-~{UART1_CTS}-Pad209)")
	(net 750 "Net-(J15A-CLK_32K_OUT)")
	(net 751 "Net-(U29-DVDT)")
	(net 752 "Net-(J15H-GPIO12{slash}PWM)")
	(net 753 "Net-(J15H-GPIO13{slash}PWM)")
	(net 754 "unconnected-(J15A-MP-Pad261)")
	(net 755 "unconnected-(J15A-MP-Pad262)")
	(net 756 "unconnected-(U40-GL-Pad10)")
	(net 757 "unconnected-(U40-P_{GOOD}-Pad14)")
	(net 758 "/Supply/3V3_PHASE")
	(net 759 "/Supply/5V_VDD")
	(net 760 "/Supply/5V_BOOT")
	(net 761 "/Supply/5V_OUT")
	(net 762 "/Supply/5V_VDRV")
	(net 763 "/Supply/5V_SW")
	(net 764 "/Supply/5V_MODE1")
	(net 765 "/Supply/5V_PHASE")
	(net 766 "/Supply/5V_FB")
	(net 767 "/Supply/5V_MODE2")
	(net 768 "/Supply/5V_GATE")
	(net 769 "unconnected-(U1-GL-Pad10)")
	(net 770 "unconnected-(U1-P_{GOOD}-Pad14)")
	(net 771 "/Supply/3V3_EN")
	(net 772 "/Peripherals/~{CS}")
	(net 773 "/Peripherals/MISO")
	(net 774 "/Peripherals/MOSI")
	(net 775 "unconnected-(J9-Pad7)")
	(net 776 "unconnected-(J9-Pad10)")
	(net 777 "unconnected-(R112-R4.1-Pad4)")
	(net 778 "unconnected-(R112-R4.2-Pad5)")
	(net 779 "Net-(D63-A)")
	(net 780 "/USB Debug, DP/FTDI_CBUS0{slash}SDA")
	(net 781 "unconnected-(U1-GL-Pad10)_1")
	(net 782 "unconnected-(U1-GL-Pad10)_2")
	(net 783 "unconnected-(U13-Pad5)_1")
	(net 784 "unconnected-(U13-Pad4)_1")
	(net 785 "unconnected-(U40-GL-Pad10)_1")
	(net 786 "unconnected-(U40-GL-Pad10)_2")
	(net 787 "+5V_SoM")
	(net 788 "VDD_SoM")
	(net 789 "MODULE_ID")
	(net 790 "Net-(U29-ILIM)")
	(net 791 "Net-(U48-ILIM)")
	(net 792 "Net-(U29-PG)")
	(net 793 "Net-(D62-C)")
	(net 794 "unconnected-(U29-ITIMER-Pad10)")
	(net 795 "unconnected-(U29-ITIMER-Pad10)_1")
	(net 796 "unconnected-(U48-ITIMER-Pad10)")
	(net 797 "unconnected-(U48-ITIMER-Pad10)_1")
	(net 798 "Net-(D62-A)")
	(net 799 "/Supply/PG_{HP}")
	(footprint "antmicro-footprints:R_0603_1608Metric"
		(layer "F.Cu")
		(at 57.3 87.5)
		(descr "Resistor SMD 0603")
		(tags "resistor SMD 0603")
		(property "Reference" "R287"
			(at -3.8 0 0)
			(layer "F.SilkS")
			(effects
				(font
					(size 0.7 0.7)
					(thickness 0.15)
				)
				(justify left bottom)
			)
		)
		(property "Value" "R_0R_22.4A_0603"
			(at 0 1.6 0)
			(layer "F.Fab")
			(effects
				(font
					(size 0.7 0.7)
					(thickness 0.15)
				)
				(justify left bottom)
			)
		)
		(property "Footprint" "antmicro-footprints:R_0603_1608Metric"
			(at 0 0 0)
			(layer "F.Fab")
			(hide yes)
			(effects
				(font
					(size 1.27 1.27)
					(thickness 0.15)
				)
			)
		)
		(property "Datasheet" "https://fscdn.rohm.com/en/products/databook/datasheet/passive/resistor/chip_resistor/pmr-jpw-e.pdf"
			(at 0 0 0)
			(layer "F.Fab")
			(hide yes)
			(effects
				(font
					(size 1.27 1.27)
					(thickness 0.15)
				)
			)
		)
		(property "Manufacturer" "ROHM Semiconductor"
			(at 0 0 0)
			(unlocked yes)
			(layer "F.Fab")
			(hide yes)
			(effects
				(font
					(size 1 1)
					(thickness 0.15)
				)
			)
		)
		(property "MPN" "PMR03EZPJ000"
			(at 0 0 0)
			(unlocked yes)
			(layer "F.Fab")
			(hide yes)
			(effects
				(font
					(size 1 1)
					(thickness 0.15)
				)
			)
		)
		(property "Val" "0R"
			(at 0 0 0)
			(unlocked yes)
			(layer "F.Fab")
			(hide yes)
			(effects
				(font
					(size 1 1)
					(thickness 0.15)
				)
			)
		)
		(property "Author" "Antmicro"
			(at 0 0 0)
			(unlocked yes)
			(layer "F.Fab")
			(hide yes)
			(effects
				(font
					(size 1 1)
					(thickness 0.15)
				)
			)
		)
		(property "License" "Apache-2.0"
			(at 0 0 0)
			(unlocked yes)
			(layer "F.Fab")
			(hide yes)
			(effects
				(font
					(size 1 1)
					(thickness 0.15)
				)
			)
		)
		(property "Max. Curr." "22.4A"
			(at 0 0 0)
			(unlocked yes)
			(layer "F.Fab")
			(hide yes)
			(effects
				(font
					(size 1 1)
					(thickness 0.15)
				)
			)
		)
		(property "Tolerance" "template_tolerance"
			(at 0 0 0)
			(unlocked yes)
			(layer "F.Fab")
			(hide yes)
			(effects
				(font
					(size 1 1)
					(thickness 0.15)
				)
			)
		)
		(sheetname "SoM")
		(sheetfile "som.kicad_sch")
		(attr smd)
		(fp_line
			(start -0.15 -0.4)
			(end 0.15 -0.4)
			(stroke
				(width 0.15)
				(type solid)
			)
			(layer "F.SilkS")
		)
		(fp_line
			(start -0.15 0.4)
			(end 0.15 0.4)
			(stroke
				(width 0.15)
				(type solid)
			)
			(layer "F.SilkS")
		)
		(fp_rect
			(start -1.25 -0.65)
			(end 1.25 0.65)
			(stroke
				(width 0.05)
				(type solid)
			)
			(fill none)
			(layer "F.CrtYd")
		)
		(fp_rect
			(start -0.8 -0.4)
			(end 0.8 0.4)
			(stroke
				(width 0.15)
				(type solid)
			)
			(fill none)
			(layer "F.Fab")
		)
		(fp_text user "Author: Antmicro"
			(at -1.25 4.9 0)
			(layer "F.Fab")
			(hide yes)
			(effects
				(font
					(size 0.7 0.7)
					(thickness 0.15)
				)
				(justify left bottom)
			)
		)
		(fp_text user "License: Apache-2.0"
			(at -1.25 5.9 0)
			(layer "F.Fab")
			(hide yes)
			(effects
				(font
					(size 0.7 0.7)
					(thickness 0.15)
				)
				(justify left bottom)
			)
		)
		(fp_text user "${REFERENCE}"
			(at -1.25 3.898 0)
			(layer "F.Fab")
			(hide yes)
			(effects
				(font
					(size 0.7 0.7)
					(thickness 0.15)
				)
				(justify left bottom)
			)
		)
		(pad "1" smd roundrect
			(at -0.7 0)
			(size 0.8 1)
			(layers "F.Cu" "F.Paste" "F.Mask")
			(roundrect_rratio 0.2)
			(net 788 "VDD_SoM")
			(pintype "passive")
		)
		(pad "2" smd roundrect
			(at 0.7 0)
			(size 0.8 1)
			(layers "F.Cu" "F.Paste" "F.Mask")
			(roundrect_rratio 0.2)
			(net 438 "/SoM/SoM_VIN")
			(pintype "passive")
		)
	)
	(footprint "antmicro-footprints:R_0402_1005Metric"
		(layer "F.Cu")
		(at 32.15 105.2 90)
		(descr "Resistor SMD 0402")
		(tags "resistor SMD 0402")
		(property "Reference" "R154"
			(at -1.4 1.3 90)
			(layer "F.SilkS")
			(effects
				(font
					(size 0.7 0.7)
					(thickness 0.15)
				)
				(justify left bottom)
			)
		)
		(property "Value" "R_24k9_0402"
			(at 0 1.4 90)
			(layer "F.Fab")
			(effects
				(font
					(size 0.7 0.7)
					(thickness 0.15)
				)
				(justify left bottom)
			)
		)
		(property "Footprint" "antmicro-footprints:R_0402_1005Metric"
			(at 0 0 90)
			(layer "F.Fab")
			(hide yes)
			(effects
				(font
					(size 1.27 1.27)
					(thickness 0.15)
				)
			)
		)
		(property "Datasheet" "https://www.bourns.com/docs/product-datasheets/cr.pdf"
			(at 0 0 90)
			(layer "F.Fab")
			(hide yes)
			(effects
				(font
					(size 1.27 1.27)
					(thickness 0.15)
				)
			)
		)
		(property "Author" "Antmicro"
			(at 137.35 73.05 0)
			(layer "F.Fab")
			(hide yes)
			(effects
				(font
					(size 1 1)
					(thickness 0.15)
				)
			)
		)
		(property "License" "Apache-2.0"
			(at 137.35 73.05 0)
			(layer "F.Fab")
			(hide yes)
			(effects
				(font
					(size 1 1)
					(thickness 0.15)
				)
			)
		)
		(property "MPN" "CR0402-FX-2492GLF"
			(at 137.35 73.05 0)
			(layer "F.Fab")
			(hide yes)
			(effects
				(font
					(size 1 1)
					(thickness 0.15)
				)
			)
		)
		(property "Manufacturer" "Bourns"
			(at 137.35 73.05 0)
			(layer "F.Fab")
			(hide yes)
			(effects
				(font
					(size 1 1)
					(thickness 0.15)
				)
			)
		)
		(property "Tolerance" "1%"
			(at 137.35 73.05 0)
			(layer "F.Fab")
			(hide yes)
			(effects
				(font
					(size 1 1)
					(thickness 0.15)
				)
			)
		)
		(property "Val" "24k9"
			(at 137.35 73.05 0)
			(layer "F.Fab")
			(hide yes)
			(effects
				(font
					(size 1 1)
					(thickness 0.15)
				)
			)
		)
		(sheetname "Ethernet")
		(sheetfile "ethernet.kicad_sch")
		(attr smd)
		(fp_rect
			(start -0.925 -0.47)
			(end 0.925 0.47)
			(stroke
				(width 0.05)
				(type default)
			)
			(fill none)
			(layer "F.CrtYd")
		)
		(fp_rect
			(start -0.5 -0.25)
			(end 0.5 0.25)
			(stroke
				(width 0.15)
				(type solid)
			)
			(fill none)
			(layer "F.Fab")
		)
		(fp_text user "${REFERENCE}"
			(at -0.95 3.168 90)
			(layer "F.Fab")
			(hide yes)
			(effects
				(font
					(size 0.7 0.7)
					(thickness 0.15)
				)
				(justify left bottom)
			)
		)
		(fp_text user "Author: Antmicro"
			(at -0.95 4.169 90)
			(layer "F.Fab")
			(hide yes)
			(effects
				(font
					(size 0.7 0.7)
					(thickness 0.15)
				)
				(justify left bottom)
			)
		)
		(fp_text user "License: Apache-2.0"
			(at -0.95 5.169 90)
			(layer "F.Fab")
			(hide yes)
			(effects
				(font
					(size 0.7 0.7)
					(thickness 0.15)
				)
				(justify left bottom)
			)
		)
		(pad "1" smd roundrect
			(at -0.48 0 90)
			(size 0.59 0.64)
			(layers "F.Cu" "F.Paste" "F.Mask")
			(roundrect_rratio 0.25)
			(net 153 "Net-(D15-A)")
			(pintype "passive")
		)
		(pad "2" smd roundrect
			(at 0.48 0 90)
			(size 0.59 0.64)
			(layers "F.Cu" "F.Paste" "F.Mask")
			(roundrect_rratio 0.25)
			(net 105 "/Ethernet/VDD")
			(pintype "passive")
		)
	)
	(footprint "antmicro-footprints:R_0402_1005Metric"
		(layer "F.Cu")
		(at 105.15 105.05)
		(descr "Resistor SMD 0402")
		(tags "resistor SMD 0402")
		(property "Reference" "R115"
			(at -3.65 0.4 0)
			(layer "F.SilkS")
			(effects
				(font
					(size 0.7 0.7)
					(thickness 0.15)
				)
				(justify left bottom)
			)
		)
		(property "Value" "R_10k_0402"
			(at 0 1.4 0)
			(layer "F.Fab")
			(effects
				(font
					(size 0.7 0.7)
					(thickness 0.15)
				)
				(justify left bottom)
			)
		)
		(property "Footprint" "antmicro-footprints:R_0402_1005Metric"
			(at 0 0 0)
			(layer "F.Fab")
			(hide yes)
			(effects
				(font
					(size 1.27 1.27)
					(thickness 0.15)
				)
			)
		)
		(property "Datasheet" "https://www.bourns.com/docs/product-datasheets/cr.pdf"
			(at 0 0 0)
			(layer "F.Fab")
			(hide yes)
			(effects
				(font
					(size 1.27 1.27)
					(thickness 0.15)
				)
			)
		)
		(property "Author" "Antmicro"
			(at 0 0 0)
			(layer "F.Fab")
			(hide yes)
			(effects
				(font
					(size 1 1)
					(thickness 0.15)
				)
			)
		)
		(property "License" "Apache-2.0"
			(at 0 0 0)
			(layer "F.Fab")
			(hide yes)
			(effects
				(font
					(size 1 1)
					(thickness 0.15)
				)
			)
		)
		(property "MPN" "CR0402-FX-1002GLF"
			(at 0 0 0)
			(layer "F.Fab")
			(hide yes)
			(effects
				(font
					(size 1 1)
					(thickness 0.15)
				)
			)
		)
		(property "Manufacturer" "Bourns"
			(at 0 0 0)
			(layer "F.Fab")
			(hide yes)
			(effects
				(font
					(size 1 1)
					(thickness 0.15)
				)
			)
		)
		(property "Tolerance" "1%"
			(at 0 0 0)
			(layer "F.Fab")
			(hide yes)
			(effects
				(font
					(size 1 1)
					(thickness 0.15)
				)
			)
		)
		(property "Val" "10k"
			(at 0 0 0)
			(layer "F.Fab")
			(hide yes)
			(effects
				(font
					(size 1 1)
					(thickness 0.15)
				)
			)
		)
		(sheetname "USB3")
		(sheetfile "usb3.kicad_sch")
		(attr smd exclude_from_pos_files exclude_from_bom dnp)
		(fp_rect
			(start -0.925 -0.47)
			(end 0.925 0.47)
			(stroke
				(width 0.05)
				(type default)
			)
			(fill none)
			(layer "F.CrtYd")
		)
		(fp_rect
			(start -0.5 -0.25)
			(end 0.5 0.25)
			(stroke
				(width 0.15)
				(type solid)
			)
			(fill none)
			(layer "F.Fab")
		)
		(fp_text user "License: Apache-2.0"
			(at -0.95 5.169 0)
			(layer "F.Fab")
			(hide yes)
			(effects
				(font
					(size 0.7 0.7)
					(thickness 0.15)
				)
				(justify left bottom)
			)
		)
		(fp_text user "Author: Antmicro"
			(at -0.95 4.169 0)
			(layer "F.Fab")
			(hide yes)
			(effects
				(font
					(size 0.7 0.7)
					(thickness 0.15)
				)
				(justify left bottom)
			)
		)
		(fp_text user "${REFERENCE}"
			(at -0.95 3.168 0)
			(layer "F.Fab")
			(hide yes)
			(effects
				(font
					(size 0.7 0.7)
					(thickness 0.15)
				)
				(justify left bottom)
			)
		)
		(pad "1" smd roundrect
			(at -0.48 0)
			(size 0.59 0.64)
			(layers "F.Cu" "F.Paste" "F.Mask")
			(roundrect_rratio 0.25)
			(net 99 "+5V")
			(pintype "passive")
		)
		(pad "2" smd roundrect
			(at 0.48 0)
			(size 0.59 0.64)
			(layers "F.Cu" "F.Paste" "F.Mask")
			(roundrect_rratio 0.25)
			(net 315 "/USB3/USBC1_PORT")
			(pintype "passive")
		)
	)
	(footprint "antmicro-footprints:R_0402_1005Metric"
		(layer "F.Cu")
		(at 81.23 89.13 -90)
		(descr "Resistor SMD 0402")
		(tags "resistor SMD 0402")
		(property "Reference" "R240"
			(at -1.75 -2.4 90)
			(layer "F.SilkS")
			(effects
				(font
					(size 0.7 0.7)
					(thickness 0.15)
				)
				(justify right bottom)
			)
		)
		(property "Value" "R_499k_0402"
			(at -1.011843 1.772047 90)
			(layer "F.Fab")
			(effects
				(font
					(size 0.7 0.7)
					(thickness 0.15)
				)
				(justify right bottom)
			)
		)
		(property "Footprint" "antmicro-footprints:R_0402_1005Metric"
			(at 0 0 -90)
			(layer "F.Fab")
			(hide yes)
			(effects
				(font
					(size 1.27 1.27)
					(thickness 0.15)
				)
			)
		)
		(property "Datasheet" "https://www.mouser.com/datasheet/2/54/cr-1858361.pdf"
			(at 0 0 -90)
			(layer "F.Fab")
			(hide yes)
			(effects
				(font
					(size 1.27 1.27)
					(thickness 0.15)
				)
			)
		)
		(property "Author" "Antmicro"
			(at -7.9 170.36 0)
			(layer "F.Fab")
			(hide yes)
			(effects
				(font
					(size 1 1)
					(thickness 0.15)
				)
			)
		)
		(property "License" "Apache-2.0"
			(at -7.9 170.36 0)
			(layer "F.Fab")
			(hide yes)
			(effects
				(font
					(size 1 1)
					(thickness 0.15)
				)
			)
		)
		(property "MPN" "CR0402-FX-4993GLF"
			(at -7.9 170.36 0)
			(layer "F.Fab")
			(hide yes)
			(effects
				(font
					(size 1 1)
					(thickness 0.15)
				)
			)
		)
		(property "Manufacturer" "Bourns"
			(at -7.9 170.36 0)
			(layer "F.Fab")
			(hide yes)
			(effects
				(font
					(size 1 1)
					(thickness 0.15)
				)
			)
		)
		(property "Tolerance" "1%"
			(at -7.9 170.36 0)
			(layer "F.Fab")
			(hide yes)
			(effects
				(font
					(size 1 1)
					(thickness 0.15)
				)
			)
		)
		(property "Val" "499k"
			(at -7.9 170.36 0)
			(layer "F.Fab")
			(hide yes)
			(effects
				(font
					(size 1 1)
					(thickness 0.15)
				)
			)
		)
		(sheetname "Supply")
		(sheetfile "supply.kicad_sch")
		(attr smd exclude_from_pos_files exclude_from_bom dnp)
		(fp_rect
			(start -0.925 -0.47)
			(end 0.925 0.47)
			(stroke
				(width 0.05)
				(type default)
			)
			(fill none)
			(layer "F.CrtYd")
		)
		(fp_rect
			(start -0.5 -0.25)
			(end 0.5 0.25)
			(stroke
				(width 0.15)
				(type solid)
			)
			(fill none)
			(layer "F.Fab")
		)
		(fp_text user "${REFERENCE}"
			(at -0.95 3.168 90)
			(layer "F.Fab")
			(hide yes)
			(effects
				(font
					(size 0.7 0.7)
					(thickness 0.15)
				)
				(justify right bottom)
			)
		)
		(fp_text user "License: Apache-2.0"
			(at -0.95 5.169 90)
			(layer "F.Fab")
			(hide yes)
			(effects
				(font
					(size 0.7 0.7)
					(thickness 0.15)
				)
				(justify right bottom)
			)
		)
		(fp_text user "Author: Antmicro"
			(at -0.95 4.169 90)
			(layer "F.Fab")
			(hide yes)
			(effects
				(font
					(size 0.7 0.7)
					(thickness 0.15)
				)
				(justify right bottom)
			)
		)
		(pad "1" smd roundrect
			(at -0.48 0 270)
			(size 0.59 0.64)
			(layers "F.Cu" "F.Paste" "F.Mask")
			(roundrect_rratio 0.25)
			(net 687 "/Supply/3V3_MODE1")
			(pintype "passive")
		)
		(pad "2" smd roundrect
			(at 0.48 0 270)
			(size 0.59 0.64)
			(layers "F.Cu" "F.Paste" "F.Mask")
			(roundrect_rratio 0.25)
			(net 177 "/Supply/3V3_VDD")
			(pintype "passive")
		)
	)
	(footprint "antmicro-footprints:C_0603_1608Metric"
		(layer "F.Cu")
		(at 102.95 122.95 180)
		(descr "Capacitor SMD 0603")
		(tags "capacitor 0603")
		(property "Reference" "C74"
			(at -1.075 -0.5 180)
			(layer "F.SilkS")
			(effects
				(font
					(size 0.7 0.7)
					(thickness 0.15)
				)
				(justify left bottom)
			)
		)
		(property "Value" "C_10u_0603"
			(at 0 1.6 180)
			(layer "F.Fab")
			(effects
				(font
					(size 0.7 0.7)
					(thickness 0.15)
				)
				(justify left bottom)
			)
		)
		(property "Footprint" "antmicro-footprints:C_0603_1608Metric"
			(at 0 0 180)
			(layer "F.Fab")
			(hide yes)
			(effects
				(font
					(size 1.27 1.27)
					(thickness 0.15)
				)
			)
		)
		(property "Datasheet" "https://www.murata.com/products/productdetail?partno=GRM188R61A106KE69%23"
			(at 0 0 180)
			(layer "F.Fab")
			(hide yes)
			(effects
				(font
					(size 1.27 1.27)
					(thickness 0.15)
				)
			)
		)
		(property "Author" "Antmicro"
			(at 205.9 245.9 0)
			(layer "F.Fab")
			(hide yes)
			(effects
				(font
					(size 1 1)
					(thickness 0.15)
				)
			)
		)
		(property "Dielectric" "template_dielectric"
			(at 205.9 245.9 0)
			(layer "F.Fab")
			(hide yes)
			(effects
				(font
					(size 1 1)
					(thickness 0.15)
				)
			)
		)
		(property "License" "Apache-2.0"
			(at 205.9 245.9 0)
			(layer "F.Fab")
			(hide yes)
			(effects
				(font
					(size 1 1)
					(thickness 0.15)
				)
			)
		)
		(property "MPN" "GRM188R61A106KE69D"
			(at 205.9 245.9 0)
			(layer "F.Fab")
			(hide yes)
			(effects
				(font
					(size 1 1)
					(thickness 0.15)
				)
			)
		)
		(property "Manufacturer" "Murata"
			(at 205.9 245.9 0)
			(layer "F.Fab")
			(hide yes)
			(effects
				(font
					(size 1 1)
					(thickness 0.15)
				)
			)
		)
		(property "Val" "10u"
			(at 205.9 245.9 0)
			(layer "F.Fab")
			(hide yes)
			(effects
				(font
					(size 1 1)
					(thickness 0.15)
				)
			)
		)
		(property "Voltage" ""
			(at 205.9 245.9 0)
			(layer "F.Fab")
			(hide yes)
			(effects
				(font
					(size 1 1)
					(thickness 0.15)
				)
			)
		)
		(sheetname "USB3")
		(sheetfile "usb3.kicad_sch")
		(attr smd)
		(fp_line
			(start -0.15 0.4)
			(end 0.15 0.4)
			(stroke
				(width 0.15)
				(type solid)
			)
			(layer "F.SilkS")
		)
		(fp_line
			(start -0.15 -0.4)
			(end 0.15 -0.4)
			(stroke
				(width 0.15)
				(type solid)
			)
			(layer "F.SilkS")
		)
		(fp_rect
			(start -1.25 -0.65)
			(end 1.25 0.65)
			(stroke
				(width 0.05)
				(type solid)
			)
			(fill none)
			(layer "F.CrtYd")
		)
		(fp_rect
			(start -0.8 -0.4)
			(end 0.8 0.4)
			(stroke
				(width 0.15)
				(type solid)
			)
			(fill none)
			(layer "F.Fab")
		)
		(fp_text user "${REFERENCE}"
			(at -1.682 3.895 180)
			(layer "F.Fab")
			(hide yes)
			(effects
				(font
					(size 0.7 0.7)
					(thickness 0.15)
				)
				(justify left bottom)
			)
		)
		(fp_text user "License: Apache-2.0"
			(at -1.682 5.895 180)
			(layer "F.Fab")
			(hide yes)
			(effects
				(font
					(size 0.7 0.7)
					(thickness 0.15)
				)
				(justify left bottom)
			)
		)
		(fp_text user "Author: Antmicro"
			(at -1.682 4.894 180)
			(layer "F.Fab")
			(hide yes)
			(effects
				(font
					(size 0.7 0.7)
					(thickness 0.15)
				)
				(justify left bottom)
			)
		)
		(pad "1" smd roundrect
			(at -0.7 0 180)
			(size 0.8 1)
			(layers "F.Cu" "F.Paste" "F.Mask")
			(roundrect_rratio 0.2)
			(net 270 "/USB3/USBC1_VBUS")
			(pintype "passive")
		)
		(pad "2" smd roundrect
			(at 0.7 0 180)
			(size 0.8 1)
			(layers "F.Cu" "F.Paste" "F.Mask")
			(roundrect_rratio 0.2)
			(net 1 "GND")
			(pintype "passive")
		)
	)
	(footprint "antmicro-footprints:R_0402_1005Metric"
		(layer "F.Cu")
		(at 134.7 121.1 90)
		(descr "Resistor SMD 0402")
		(tags "resistor SMD 0402")
		(property "Reference" "R223"
			(at 0.75 0.45 90)
			(layer "F.SilkS")
			(effects
				(font
					(size 0.7 0.7)
					(thickness 0.15)
				)
				(justify left bottom)
			)
		)
		(property "Value" "R_200R_0402"
			(at 0 1.4 90)
			(layer "F.Fab")
			(effects
				(font
					(size 0.7 0.7)
					(thickness 0.15)
				)
				(justify left bottom)
			)
		)
		(property "Footprint" "antmicro-footprints:R_0402_1005Metric"
			(at 0 0 90)
			(layer "F.Fab")
			(hide yes)
			(effects
				(font
					(size 1.27 1.27)
					(thickness 0.15)
				)
			)
		)
		(property "Datasheet" "https://www.bourns.com/docs/product-datasheets/cr.pdf"
			(at 0 0 90)
			(layer "F.Fab")
			(hide yes)
			(effects
				(font
					(size 1.27 1.27)
					(thickness 0.15)
				)
			)
		)
		(property "Author" "Antmicro"
			(at 255.8 -13.6 0)
			(layer "F.Fab")
			(hide yes)
			(effects
				(font
					(size 1 1)
					(thickness 0.15)
				)
			)
		)
		(property "License" "Apache-2.0"
			(at 255.8 -13.6 0)
			(layer "F.Fab")
			(hide yes)
			(effects
				(font
					(size 1 1)
					(thickness 0.15)
				)
			)
		)
		(property "MPN" "CR0402-FX-2000GLF"
			(at 255.8 -13.6 0)
			(layer "F.Fab")
			(hide yes)
			(effects
				(font
					(size 1 1)
					(thickness 0.15)
				)
			)
		)
		(property "Manufacturer" "Bourns"
			(at 255.8 -13.6 0)
			(layer "F.Fab")
			(hide yes)
			(effects
				(font
					(size 1 1)
					(thickness 0.15)
				)
			)
		)
		(property "Tolerance" "1%"
			(at 255.8 -13.6 0)
			(layer "F.Fab")
			(hide yes)
			(effects
				(font
					(size 1 1)
					(thickness 0.15)
				)
			)
		)
		(property "Val" "200R"
			(at 255.8 -13.6 0)
			(layer "F.Fab")
			(hide yes)
			(effects
				(font
					(size 1 1)
					(thickness 0.15)
				)
			)
		)
		(sheetname "Peripherals")
		(sheetfile "peripherals.kicad_sch")
		(attr smd)
		(fp_rect
			(start -0.925 -0.47)
			(end 0.925 0.47)
			(stroke
				(width 0.05)
				(type default)
			)
			(fill none)
			(layer "F.CrtYd")
		)
		(fp_rect
			(start -0.5 -0.25)
			(end 0.5 0.25)
			(stroke
				(width 0.15)
				(type solid)
			)
			(fill none)
			(layer "F.Fab")
		)
		(fp_text user "License: Apache-2.0"
			(at -0.95 5.169 90)
			(layer "F.Fab")
			(hide yes)
			(effects
				(font
					(size 0.7 0.7)
					(thickness 0.15)
				)
				(justify left bottom)
			)
		)
		(fp_text user "Author: Antmicro"
			(at -0.95 4.169 90)
			(layer "F.Fab")
			(hide yes)
			(effects
				(font
					(size 0.7 0.7)
					(thickness 0.15)
				)
				(justify left bottom)
			)
		)
		(fp_text user "${REFERENCE}"
			(at -0.95 3.168 90)
			(layer "F.Fab")
			(hide yes)
			(effects
				(font
					(size 0.7 0.7)
					(thickness 0.15)
				)
				(justify left bottom)
			)
		)
		(pad "1" smd roundrect
			(at -0.48 0 90)
			(size 0.59 0.64)
			(layers "F.Cu" "F.Paste" "F.Mask")
			(roundrect_rratio 0.25)
			(net 180 "Net-(D26-A)")
			(pintype "passive")
		)
		(pad "2" smd roundrect
			(at 0.48 0 90)
			(size 0.59 0.64)
			(layers "F.Cu" "F.Paste" "F.Mask")
			(roundrect_rratio 0.25)
			(net 87 "+3V3")
			(pintype "passive")
		)
	)
	(footprint "antmicro-footprints:R_0603_1608Metric"
		(layer "F.Cu")
		(at 137.2 110.3)
		(descr "Resistor SMD 0603")
		(tags "resistor SMD 0603")
		(property "Reference" "R233"
			(at -3.94 0.43 0)
			(layer "F.SilkS")
			(effects
				(font
					(size 0.7 0.7)
					(thickness 0.15)
				)
				(justify left bottom)
			)
		)
		(property "Value" "R_0R_22.4A_0603"
			(at 0 1.6 0)
			(layer "F.Fab")
			(effects
				(font
					(size 0.7 0.7)
					(thickness 0.15)
				)
				(justify left bottom)
			)
		)
		(property "Footprint" "antmicro-footprints:R_0603_1608Metric"
			(at 0 0 0)
			(layer "F.Fab")
			(hide yes)
			(effects
				(font
					(size 1.27 1.27)
					(thickness 0.15)
				)
			)
		)
		(property "Datasheet" "https://fscdn.rohm.com/en/products/databook/datasheet/passive/resistor/chip_resistor/pmr-jpw-e.pdf"
			(at 0 0 0)
			(layer "F.Fab")
			(hide yes)
			(effects
				(font
					(size 1.27 1.27)
					(thickness 0.15)
				)
			)
		)
		(property "Author" "Antmicro"
			(at 0 0 0)
			(layer "F.Fab")
			(hide yes)
			(effects
				(font
					(size 1 1)
					(thickness 0.15)
				)
			)
		)
		(property "License" "Apache-2.0"
			(at 0 0 0)
			(layer "F.Fab")
			(hide yes)
			(effects
				(font
					(size 1 1)
					(thickness 0.15)
				)
			)
		)
		(property "MPN" "PMR03EZPJ000"
			(at 0 0 0)
			(layer "F.Fab")
			(hide yes)
			(effects
				(font
					(size 1 1)
					(thickness 0.15)
				)
			)
		)
		(property "Manufacturer" "ROHM Semiconductor"
			(at 0 0 0)
			(layer "F.Fab")
			(hide yes)
			(effects
				(font
					(size 1 1)
					(thickness 0.15)
				)
			)
		)
		(property "Max. Curr." "22.4A"
			(at 0 0 0)
			(layer "F.Fab")
			(hide yes)
			(effects
				(font
					(size 1 1)
					(thickness 0.15)
				)
			)
		)
		(property "Tolerance" "template_tolerance"
			(at 0 0 0)
			(layer "F.Fab")
			(hide yes)
			(effects
				(font
					(size 1 1)
					(thickness 0.15)
				)
			)
		)
		(property "Val" "0R"
			(at 0 0 0)
			(layer "F.Fab")
			(hide yes)
			(effects
				(font
					(size 1 1)
					(thickness 0.15)
				)
			)
		)
		(sheetname "Peripherals")
		(sheetfile "peripherals.kicad_sch")
		(attr smd)
		(fp_line
			(start -0.15 -0.4)
			(end 0.15 -0.4)
			(stroke
				(width 0.15)
				(type solid)
			)
			(layer "F.SilkS")
		)
		(fp_line
			(start -0.15 0.4)
			(end 0.15 0.4)
			(stroke
				(width 0.15)
				(type solid)
			)
			(layer "F.SilkS")
		)
		(fp_rect
			(start -1.25 -0.65)
			(end 1.25 0.65)
			(stroke
				(width 0.05)
				(type solid)
			)
			(fill none)
			(layer "F.CrtYd")
		)
		(fp_rect
			(start -0.8 -0.4)
			(end 0.8 0.4)
			(stroke
				(width 0.15)
				(type solid)
			)
			(fill none)
			(layer "F.Fab")
		)
		(fp_text user "${REFERENCE}"
			(at -1.25 3.898 0)
			(layer "F.Fab")
			(hide yes)
			(effects
				(font
					(size 0.7 0.7)
					(thickness 0.15)
				)
				(justify left bottom)
			)
		)
		(fp_text user "Author: Antmicro"
			(at -1.25 4.9 0)
			(layer "F.Fab")
			(hide yes)
			(effects
				(font
					(size 0.7 0.7)
					(thickness 0.15)
				)
				(justify left bottom)
			)
		)
		(fp_text user "License: Apache-2.0"
			(at -1.25 5.9 0)
			(layer "F.Fab")
			(hide yes)
			(effects
				(font
					(size 0.7 0.7)
					(thickness 0.15)
				)
				(justify left bottom)
			)
		)
		(pad "1" smd roundrect
			(at -0.7 0)
			(size 0.8 1)
			(layers "F.Cu" "F.Paste" "F.Mask")
			(roundrect_rratio 0.2)
			(net 87 "+3V3")
			(pintype "passive")
		)
		(pad "2" smd roundrect
			(at 0.7 0)
			(size 0.8 1)
			(layers "F.Cu" "F.Paste" "F.Mask")
			(roundrect_rratio 0.2)
			(net 482 "/Peripherals/3V3_CONN")
			(pintype "passive")
		)
	)
	(footprint "antmicro-footprints:C_0402_1005Metric"
		(layer "F.Cu")
		(at 68.6 119 -90)
		(descr "Capacitor SMD 0402")
		(tags "capacitor SMD 0402")
		(property "Reference" "C57"
			(at 1.2 -1.28 -90)
			(layer "F.SilkS")
			(effects
				(font
					(size 0.7 0.7)
					(thickness 0.15)
				)
				(justify left bottom)
			)
		)
		(property "Value" "C_100n_0402"
			(at 0 1.4 -90)
			(layer "F.Fab")
			(effects
				(font
					(size 0.7 0.7)
					(thickness 0.15)
				)
				(justify left bottom)
			)
		)
		(property "Footprint" "antmicro-footprints:C_0402_1005Metric"
			(at 0 0 -90)
			(layer "F.Fab")
			(hide yes)
			(effects
				(font
					(size 1.27 1.27)
					(thickness 0.15)
				)
			)
		)
		(property "Datasheet" "https://www.murata.com/products/productdetail?partno=GRM155R61H104KE14%23"
			(at 0 0 -90)
			(layer "F.Fab")
			(hide yes)
			(effects
				(font
					(size 1.27 1.27)
					(thickness 0.15)
				)
			)
		)
		(property "Author" "Antmicro"
			(at -50.4 187.6 0)
			(layer "F.Fab")
			(hide yes)
			(effects
				(font
					(size 1 1)
					(thickness 0.15)
				)
			)
		)
		(property "Dielectric" "X5R"
			(at -50.4 187.6 0)
			(layer "F.Fab")
			(hide yes)
			(effects
				(font
					(size 1 1)
					(thickness 0.15)
				)
			)
		)
		(property "License" "Apache-2.0"
			(at -50.4 187.6 0)
			(layer "F.Fab")
			(hide yes)
			(effects
				(font
					(size 1 1)
					(thickness 0.15)
				)
			)
		)
		(property "MPN" "GRM155R61H104KE14D"
			(at -50.4 187.6 0)
			(layer "F.Fab")
			(hide yes)
			(effects
				(font
					(size 1 1)
					(thickness 0.15)
				)
			)
		)
		(property "Manufacturer" "Murata"
			(at -50.4 187.6 0)
			(layer "F.Fab")
			(hide yes)
			(effects
				(font
					(size 1 1)
					(thickness 0.15)
				)
			)
		)
		(property "Val" "100n"
			(at -50.4 187.6 0)
			(layer "F.Fab")
			(hide yes)
			(effects
				(font
					(size 1 1)
					(thickness 0.15)
				)
			)
		)
		(property "Voltage" "50V"
			(at -50.4 187.6 0)
			(layer "F.Fab")
			(hide yes)
			(effects
				(font
					(size 1 1)
					(thickness 0.15)
				)
			)
		)
		(sheetname "USB Debug, DP")
		(sheetfile "usb.kicad_sch")
		(attr smd)
		(fp_rect
			(start -0.925 -0.47)
			(end 0.925 0.47)
			(stroke
				(width 0.05)
				(type default)
			)
			(fill none)
			(layer "F.CrtYd")
		)
		(fp_line
			(start -0.494 0.248)
			(end -0.494 -0.25)
			(stroke
				(width 0.15)
				(type solid)
			)
			(layer "F.Fab")
		)
		(fp_line
			(start 0.504 0.248)
			(end -0.494 0.248)
			(stroke
				(width 0.15)
				(type solid)
			)
			(layer "F.Fab")
		)
		(fp_line
			(start -0.494 -0.25)
			(end 0.504 -0.25)
			(stroke
				(width 0.15)
				(type solid)
			)
			(layer "F.Fab")
		)
		(fp_line
			(start 0.504 -0.25)
			(end 0.504 0.248)
			(stroke
				(width 0.15)
				(type solid)
			)
			(layer "F.Fab")
		)
		(fp_text user "${REFERENCE}"
			(at -0.932 3.168 -90)
			(layer "F.Fab")
			(hide yes)
			(effects
				(font
					(size 0.7 0.7)
					(thickness 0.15)
				)
				(justify left bottom)
			)
		)
		(fp_text user "Author: Antmicro"
			(at -0.932 4.17 -90)
			(layer "F.Fab")
			(hide yes)
			(effects
				(font
					(size 0.7 0.7)
					(thickness 0.15)
				)
				(justify left bottom)
			)
		)
		(fp_text user "License: Apache-2.0"
			(at -0.932 5.17 -90)
			(layer "F.Fab")
			(hide yes)
			(effects
				(font
					(size 0.7 0.7)
					(thickness 0.15)
				)
				(justify left bottom)
			)
		)
		(pad "1" smd roundrect
			(at -0.48 0 270)
			(size 0.59 0.64)
			(layers "F.Cu" "F.Paste" "F.Mask")
			(roundrect_rratio 0.25)
			(net 99 "+5V")
			(pintype "passive")
		)
		(pad "2" smd roundrect
			(at 0.48 0 270)
			(size 0.59 0.64)
			(layers "F.Cu" "F.Paste" "F.Mask")
			(roundrect_rratio 0.25)
			(net 1 "GND")
			(pintype "passive")
		)
	)
	(footprint "antmicro-footprints:R_0603_1608Metric"
		(layer "F.Cu")
		(at 137.2 114.4 180)
		(descr "Resistor SMD 0603")
		(tags "resistor SMD 0603")
		(property "Reference" "R235"
			(at 1.15 -0.5 0)
			(layer "F.SilkS")
			(effects
				(font
					(size 0.7 0.7)
					(thickness 0.15)
				)
				(justify right bottom)
			)
		)
		(property "Value" "R_0R_22.4A_0603"
			(at 0 1.6 0)
			(layer "F.Fab")
			(effects
				(font
					(size 0.7 0.7)
					(thickness 0.15)
				)
				(justify right bottom)
			)
		)
		(property "Footprint" "antmicro-footprints:R_0603_1608Metric"
			(at 0 0 180)
			(layer "F.Fab")
			(hide yes)
			(effects
				(font
					(size 1.27 1.27)
					(thickness 0.15)
				)
			)
		)
		(property "Datasheet" "https://fscdn.rohm.com/en/products/databook/datasheet/passive/resistor/chip_resistor/pmr-jpw-e.pdf"
			(at 0 0 180)
			(layer "F.Fab")
			(hide yes)
			(effects
				(font
					(size 1.27 1.27)
					(thickness 0.15)
				)
			)
		)
		(property "Author" "Antmicro"
			(at 274.4 228.8 0)
			(layer "F.Fab")
			(hide yes)
			(effects
				(font
					(size 1 1)
					(thickness 0.15)
				)
			)
		)
		(property "License" "Apache-2.0"
			(at 274.4 228.8 0)
			(layer "F.Fab")
			(hide yes)
			(effects
				(font
					(size 1 1)
					(thickness 0.15)
				)
			)
		)
		(property "MPN" "PMR03EZPJ000"
			(at 274.4 228.8 0)
			(layer "F.Fab")
			(hide yes)
			(effects
				(font
					(size 1 1)
					(thickness 0.15)
				)
			)
		)
		(property "Manufacturer" "ROHM Semiconductor"
			(at 274.4 228.8 0)
			(layer "F.Fab")
			(hide yes)
			(effects
				(font
					(size 1 1)
					(thickness 0.15)
				)
			)
		)
		(property "Max. Curr." "22.4A"
			(at 274.4 228.8 0)
			(layer "F.Fab")
			(hide yes)
			(effects
				(font
					(size 1 1)
					(thickness 0.15)
				)
			)
		)
		(property "Tolerance" "template_tolerance"
			(at 274.4 228.8 0)
			(layer "F.Fab")
			(hide yes)
			(effects
				(font
					(size 1 1)
					(thickness 0.15)
				)
			)
		)
		(property "Val" "0R"
			(at 274.4 228.8 0)
			(layer "F.Fab")
			(hide yes)
			(effects
				(font
					(size 1 1)
					(thickness 0.15)
				)
			)
		)
		(sheetname "Peripherals")
		(sheetfile "peripherals.kicad_sch")
		(attr smd)
		(fp_line
			(start -0.15 0.4)
			(end 0.15 0.4)
			(stroke
				(width 0.15)
				(type solid)
			)
			(layer "F.SilkS")
		)
		(fp_line
			(start -0.15 -0.4)
			(end 0.15 -0.4)
			(stroke
				(width 0.15)
				(type solid)
			)
			(layer "F.SilkS")
		)
		(fp_rect
			(start -1.25 -0.65)
			(end 1.25 0.65)
			(stroke
				(width 0.05)
				(type solid)
			)
			(fill none)
			(layer "F.CrtYd")
		)
		(fp_rect
			(start -0.8 -0.4)
			(end 0.8 0.4)
			(stroke
				(width 0.15)
				(type solid)
			)
			(fill none)
			(layer "F.Fab")
		)
		(fp_text user "License: Apache-2.0"
			(at -1.25 5.9 0)
			(layer "F.Fab")
			(hide yes)
			(effects
				(font
					(size 0.7 0.7)
					(thickness 0.15)
				)
				(justify right bottom)
			)
		)
		(fp_text user "Author: Antmicro"
			(at -1.25 4.9 0)
			(layer "F.Fab")
			(hide yes)
			(effects
				(font
					(size 0.7 0.7)
					(thickness 0.15)
				)
				(justify right bottom)
			)
		)
		(fp_text user "${REFERENCE}"
			(at -1.25 3.898 0)
			(layer "F.Fab")
			(hide yes)
			(effects
				(font
					(size 0.7 0.7)
					(thickness 0.15)
				)
				(justify right bottom)
			)
		)
		(pad "1" smd roundrect
			(at -0.7 0 180)
			(size 0.8 1)
			(layers "F.Cu" "F.Paste" "F.Mask")
			(roundrect_rratio 0.2)
			(net 479 "/Peripherals/5V_CONN")
			(pintype "passive")
		)
		(pad "2" smd roundrect
			(at 0.7 0 180)
			(size 0.8 1)
			(layers "F.Cu" "F.Paste" "F.Mask")
			(roundrect_rratio 0.2)
			(net 99 "+5V")
			(pintype "passive")
		)
	)
	(footprint "antmicro-footprints:USON-10_2.5x1mm_P0.5mm"
		(layer "F.Cu")
		(at 70 111.367469 90)
		(descr "USON-10 2.5x1mm_ Pitch 0.5mm")
		(tags "USON-10 2.5x1mm Pitch 0.5mm")
		(property "Reference" "U13"
			(at -1.182531 -1.65 90)
			(layer "F.SilkS")
			(effects
				(font
					(size 0.7 0.7)
					(thickness 0.15)
				)
				(justify left bottom)
			)
		)
		(property "Value" "TPD4E05U06QDQARQ1"
			(at 0.018 2.499 90)
			(layer "F.Fab")
			(effects
				(font
					(size 0.7 0.7)
					(thickness 0.15)
				)
				(justify left bottom)
			)
		)
		(property "Footprint" "antmicro-footprints:USON-10_2.5x1mm_P0.5mm"
			(at 0 0 90)
			(layer "F.Fab")
			(hide yes)
			(effects
				(font
					(size 1.27 1.27)
					(thickness 0.15)
				)
			)
		)
		(property "Datasheet" "https://www.ti.com/lit/ds/symlink/tpd4e05u06-q1.pdf?HQS=dis-mous-null-mousermode-dsf-pf-null-wwe&ts=1663591265741&ref_url=https%253A%252F%252Fwww.mouser.com%252F"
			(at 0 0 90)
			(layer "F.Fab")
			(hide yes)
			(effects
				(font
					(size 1.27 1.27)
					(thickness 0.15)
				)
			)
		)
		(property "Author" "Antmicro"
			(at 181.367469 41.367469 0)
			(layer "F.Fab")
			(hide yes)
			(effects
				(font
					(size 1 1)
					(thickness 0.15)
				)
			)
		)
		(property "License" "Apache-2.0"
			(at 181.367469 41.367469 0)
			(layer "F.Fab")
			(hide yes)
			(effects
				(font
					(size 1 1)
					(thickness 0.15)
				)
			)
		)
		(property "MPN" "TPD4E05U06QDQARQ1"
			(at 181.367469 41.367469 0)
			(layer "F.Fab")
			(hide yes)
			(effects
				(font
					(size 1 1)
					(thickness 0.15)
				)
			)
		)
		(property "Manufacturer" "Texas Instruments"
			(at 181.367469 41.367469 0)
			(layer "F.Fab")
			(hide yes)
			(effects
				(font
					(size 1 1)
					(thickness 0.15)
				)
			)
		)
		(sheetname "USB Debug, DP")
		(sheetfile "usb.kicad_sch")
		(attr smd)
		(fp_line
			(start 0.498 -1.401)
			(end -0.5 -1.401)
			(stroke
				(width 0.15)
				(type solid)
			)
			(layer "F.SilkS")
		)
		(fp_line
			(start 0.498 1.398)
			(end -0.5 1.398)
			(stroke
				(width 0.15)
				(type solid)
			)
			(layer "F.SilkS")
		)
		(fp_circle
			(center -0.68 -1.27)
			(end -0.63 -1.27)
			(stroke
				(width 0.15)
				(type solid)
			)
			(fill solid)
			(layer "F.SilkS")
		)
		(fp_rect
			(start -0.8 -1.5)
			(end 0.8 1.499)
			(stroke
				(width 0.05)
				(type solid)
			)
			(fill none)
			(layer "F.CrtYd")
		)
		(fp_line
			(start 0.498 -1.25)
			(end -0.25 -1.25)
			(stroke
				(width 0.15)
				(type solid)
			)
			(layer "F.Fab")
		)
		(fp_line
			(start 0.498 -1.25)
			(end 0.498 1.249)
			(stroke
				(width 0.15)
				(type solid)
			)
			(layer "F.Fab")
		)
		(fp_line
			(start -0.25 -1.25)
			(end -0.5 -1)
			(stroke
				(width 0.15)
				(type solid)
			)
			(layer "F.Fab")
		)
		(fp_line
			(start -0.5 -1)
			(end -0.5 1.249)
			(stroke
				(width 0.15)
				(type solid)
			)
			(layer "F.Fab")
		)
		(fp_line
			(start -0.5 1.249)
			(end 0.498 1.249)
			(stroke
				(width 0.15)
				(type solid)
			)
			(layer "F.Fab")
		)
		(fp_text user "${REFERENCE}"
			(at -0.802 4.498 90)
			(layer "F.Fab")
			(hide yes)
			(effects
				(font
					(size 0.7 0.7)
					(thickness 0.15)
				)
				(justify left bottom)
			)
		)
		(fp_text user "Author: Antmicro"
			(at -0.802 5.7 90)
			(layer "F.Fab")
			(hide yes)
			(effects
				(font
					(size 0.7 0.7)
					(thickness 0.15)
				)
				(justify left bottom)
			)
		)
		(fp_text user "License: Apache-2.0"
			(at -0.802 6.9 90)
			(layer "F.Fab")
			(hide yes)
			(effects
				(font
					(size 0.7 0.7)
					(thickness 0.15)
				)
				(justify left bottom)
			)
		)
		(pad "1" smd roundrect
			(at -0.387 -1)
			(size 0.25 0.55)
			(layers "F.Cu" "F.Paste" "F.Mask")
			(roundrect_rratio 0.25)
			(net 614 "/USB Debug, DP/USBC0_SBU_P")
			(pintype "passive")
		)
		(pad "2" smd roundrect
			(at -0.387 -0.5)
			(size 0.25 0.55)
			(layers "F.Cu" "F.Paste" "F.Mask")
			(roundrect_rratio 0.25)
			(net 615 "/USB Debug, DP/USBC0_SBU_N")
			(pintype "passive")
		)
		(pad "3" smd roundrect
			(at -0.387 0)
			(size 0.4 0.55)
			(layers "F.Cu" "F.Paste" "F.Mask")
			(roundrect_rratio 0.25)
			(net 1 "GND")
			(pintype "power_in")
		)
		(pad "4" smd roundrect
			(at -0.387 0.498)
			(size 0.25 0.55)
			(layers "F.Cu" "F.Paste" "F.Mask")
			(roundrect_rratio 0.25)
			(net 784 "unconnected-(U13-Pad4)_1")
			(pintype "passive+no_connect")
		)
		(pad "5" smd roundrect
			(at -0.387 0.998)
			(size 0.25 0.55)
			(layers "F.Cu" "F.Paste" "F.Mask")
			(roundrect_rratio 0.25)
			(net 783 "unconnected-(U13-Pad5)_1")
			(pintype "passive+no_connect")
		)
		(pad "6" smd roundrect
			(at 0.385 0.998)
			(size 0.25 0.55)
			(layers "F.Cu" "F.Paste" "F.Mask")
			(roundrect_rratio 0.25)
			(net 558 "unconnected-(U13-Pad5)")
			(pintype "passive+no_connect")
		)
		(pad "7" smd roundrect
			(at 0.385 0.498)
			(size 0.25 0.55)
			(layers "F.Cu" "F.Paste" "F.Mask")
			(roundrect_rratio 0.25)
			(net 557 "unconnected-(U13-Pad4)")
			(pintype "passive+no_connect")
		)
		(pad "8" smd roundrect
			(at 0.385 0)
			(size 0.4 0.55)
			(layers "F.Cu" "F.Paste" "F.Mask")
			(roundrect_rratio 0.25)
			(net 1 "GND")
			(pintype "passive")
		)
		(pad "9" smd roundrect
			(at 0.385 -0.5)
			(size 0.25 0.55)
			(layers "F.Cu" "F.Paste" "F.Mask")
			(roundrect_rratio 0.25)
			(net 615 "/USB Debug, DP/USBC0_SBU_N")
			(pintype "passive")
		)
		(pad "10" smd roundrect
			(at 0.385 -1)
			(size 0.25 0.55)
			(layers "F.Cu" "F.Paste" "F.Mask")
			(roundrect_rratio 0.25)
			(net 614 "/USB Debug, DP/USBC0_SBU_P")
			(pintype "passive")
		)
	)
	(footprint "antmicro-footprints:XDFN-2_1x0.60mm"
		(layer "F.Cu")
		(at 87.3 127.05 90)
		(property "Reference" "D61"
			(at 2.25 0.25 90)
			(layer "F.SilkS")
			(effects
				(font
					(size 0.7 0.7)
					(thickness 0.15)
				)
				(justify left bottom)
			)
		)
		(property "Value" "TPD1E0B04_XDFN-2"
			(at 0 1.5 90)
			(layer "F.Fab")
			(effects
				(font
					(size 0.7 0.7)
					(thickness 0.15)
				)
				(justify left bottom)
			)
		)
		(property "Footprint" "antmicro-footprints:XDFN-2_1x0.60mm"
			(at 0 0 90)
			(layer "F.Fab")
			(hide yes)
			(effects
				(font
					(size 1.27 1.27)
					(thickness 0.15)
				)
			)
		)
		(property "Datasheet" "https://www.ti.com/general/docs/suppproductinfo.tsp?distId=26&gotoUrl=https://www.ti.com/lit/gpn/tpd1e0b04"
			(at 0 0 90)
			(layer "F.Fab")
			(hide yes)
			(effects
				(font
					(size 1.27 1.27)
					(thickness 0.15)
				)
			)
		)
		(property "MPN" "TPD1E0B04DPYR"
			(at 214.35 39.75 0)
			(layer "F.Fab")
			(hide yes)
			(effects
				(font
					(size 1 1)
					(thickness 0.15)
				)
			)
		)
		(property "Manufacturer" "Texas Instruments"
			(at 214.35 39.75 0)
			(layer "F.Fab")
			(hide yes)
			(effects
				(font
					(size 1 1)
					(thickness 0.15)
				)
			)
		)
		(property "Author" "Antmicro"
			(at 214.35 39.75 0)
			(layer "F.Fab")
			(hide yes)
			(effects
				(font
					(size 1 1)
					(thickness 0.15)
				)
			)
		)
		(property "License" "Apache-2.0"
			(at 214.35 39.75 0)
			(layer "F.Fab")
			(hide yes)
			(effects
				(font
					(size 1 1)
					(thickness 0.15)
				)
			)
		)
		(sheetname "Supply")
		(sheetfile "supply.kicad_sch")
		(attr smd)
		(fp_rect
			(start -0.725 -0.475)
			(end 0.725 0.475)
			(stroke
				(width 0.05)
				(type solid)
			)
			(fill none)
			(layer "F.CrtYd")
		)
		(fp_rect
			(start -0.55 -0.35)
			(end 0.55 0.35)
			(stroke
				(width 0.15)
				(type solid)
			)
			(fill none)
			(layer "F.Fab")
		)
		(fp_text user "Author: Antmicro"
			(at -0.8 4.4 90)
			(layer "F.Fab")
			(hide yes)
			(effects
				(font
					(size 0.7 0.7)
					(thickness 0.15)
				)
				(justify left bottom)
			)
		)
		(fp_text user "${REFERENCE}"
			(at -0.8 3.2 90)
			(layer "F.Fab")
			(hide yes)
			(effects
				(font
					(size 0.7 0.7)
					(thickness 0.15)
				)
				(justify left bottom)
			)
		)
		(fp_text user "License: Apache-2.0"
			(at -0.8 5.6 90)
			(layer "F.Fab")
			(hide yes)
			(effects
				(font
					(size 0.7 0.7)
					(thickness 0.15)
				)
				(justify left bottom)
			)
		)
		(pad "1" smd roundrect
			(at -0.351 0 90)
			(size 0.3 0.5)
			(layers "F.Cu" "F.Paste" "F.Mask")
			(roundrect_rratio 0.25)
			(net 1 "GND")
			(pinfunction "C")
			(pintype "passive")
		)
		(pad "2" smd roundrect
			(at 0.349 0 90)
			(size 0.3 0.5)
			(layers "F.Cu" "F.Paste" "F.Mask")
			(roundrect_rratio 0.25)
			(net 179 "Net-(D61-A)")
			(pinfunction "A")
			(pintype "passive")
		)
	)
	(footprint "antmicro-footprints:C_0603_1608Metric_EIA"
		(layer "F.Cu")
		(at 56.64 94.63 90)
		(descr "Capacitor SMD 0603, IPC-7351 Density Level A")
		(tags "Capacitor 0603")
		(property "Reference" "C120"
			(at -2.32 28.253333 90)
			(layer "F.SilkS")
			(effects
				(font
					(size 0.7 0.7)
					(thickness 0.15)
				)
				(justify left bottom)
			)
		)
		(property "Value" "C_22u_16V_0603"
			(at -1.42757 1.770288 90)
			(layer "F.Fab")
			(effects
				(font
					(size 0.7 0.7)
					(thickness 0.15)
				)
				(justify left bottom)
			)
		)
		(property "Footprint" "antmicro-footprints:C_0603_1608Metric_EIA"
			(at 0 0 90)
			(layer "F.Fab")
			(hide yes)
			(effects
				(font
					(size 1.27 1.27)
					(thickness 0.15)
				)
			)
		)
		(property "Datasheet" "https://product.samsungsem.com/mlcc/CL10A226MO7JZN.do"
			(at 0 0 90)
			(layer "F.Fab")
			(hide yes)
			(effects
				(font
					(size 1.27 1.27)
					(thickness 0.15)
				)
			)
		)
		(property "Description" "SMD Multilayer Ceramic Capacitor"
			(at 0 0 90)
			(layer "F.Fab")
			(hide yes)
			(effects
				(font
					(size 1.27 1.27)
					(thickness 0.15)
				)
			)
		)
		(property "Manufacturer" "Samsung Electro-Mechanics"
			(at 0 0 90)
			(unlocked yes)
			(layer "F.Fab")
			(hide yes)
			(effects
				(font
					(size 1 1)
					(thickness 0.15)
				)
			)
		)
		(property "MPN" "CL10A226MO7JZNC"
			(at 0 0 90)
			(unlocked yes)
			(layer "F.Fab")
			(hide yes)
			(effects
				(font
					(size 1 1)
					(thickness 0.15)
				)
			)
		)
		(property "Val" "22u"
			(at 0 0 90)
			(unlocked yes)
			(layer "F.Fab")
			(hide yes)
			(effects
				(font
					(size 1 1)
					(thickness 0.15)
				)
			)
		)
		(property "License" "Apache-2.0"
			(at 0 0 90)
			(unlocked yes)
			(layer "F.Fab")
			(hide yes)
			(effects
				(font
					(size 1 1)
					(thickness 0.15)
				)
			)
		)
		(property "Author" "Antmicro"
			(at 0 0 90)
			(unlocked yes)
			(layer "F.Fab")
			(hide yes)
			(effects
				(font
					(size 1 1)
					(thickness 0.15)
				)
			)
		)
		(property "Voltage" "16V"
			(at 0 0 90)
			(unlocked yes)
			(layer "F.Fab")
			(hide yes)
			(effects
				(font
					(size 1 1)
					(thickness 0.15)
				)
			)
		)
		(property "Dielectric" ""
			(at 0 0 90)
			(unlocked yes)
			(layer "F.Fab")
			(hide yes)
			(effects
				(font
					(size 1 1)
					(thickness 0.15)
				)
			)
		)
		(sheetname "Supply")
		(sheetfile "supply.kicad_sch")
		(attr smd)
		(fp_line
			(start -0.15 -0.55)
			(end 0.15 -0.55)
			(stroke
				(width 0.15)
				(type solid)
			)
			(layer "F.SilkS")
		)
		(fp_line
			(start -0.15 0.55)
			(end 0.15 0.55)
			(stroke
				(width 0.15)
				(type solid)
			)
			(layer "F.SilkS")
		)
		(fp_rect
			(start -1.25 -0.65)
			(end 1.25 0.65)
			(stroke
				(width 0.05)
				(type solid)
			)
			(fill none)
			(layer "F.CrtYd")
		)
		(fp_rect
			(start -0.8 -0.45)
			(end 0.8 0.45)
			(stroke
				(width 0.15)
				(type solid)
			)
			(fill none)
			(layer "F.Fab")
		)
		(fp_text user "${REFERENCE}"
			(at -1.682 3.895 90)
			(layer "F.Fab")
			(hide yes)
			(effects
				(font
					(size 0.7 0.7)
					(thickness 0.15)
				)
				(justify left bottom)
			)
		)
		(fp_text user "Author: Antmicro"
			(at -1.682 4.894 90)
			(layer "F.Fab")
			(hide yes)
			(effects
				(font
					(size 0.7 0.7)
					(thickness 0.15)
				)
				(justify left bottom)
			)
		)
		(fp_text user "License: Apache-2.0"
			(at -1.682 5.895 90)
			(layer "F.Fab")
			(hide yes)
			(effects
				(font
					(size 0.7 0.7)
					(thickness 0.15)
				)
				(justify left bottom)
			)
		)
		(pad "1" smd roundrect
			(at -0.7 0 90)
			(size 0.8 1.1)
			(layers "F.Cu" "F.Paste" "F.Mask")
			(roundrect_rratio 0.2)
			(net 1 "GND")
			(pintype "passive")
		)
		(pad "2" smd roundrect
			(at 0.7 0 90)
			(size 0.8 1.1)
			(layers "F.Cu" "F.Paste" "F.Mask")
			(roundrect_rratio 0.2)
			(net 761 "/Supply/5V_OUT")
			(pintype "passive")
		)
	)
	(footprint "antmicro-footprints:XDFN-2_1x0.60mm"
		(layer "F.Cu")
		(at 147.45 88.2 -90)
		(property "Reference" "D40"
			(at -6.65 0.15 180)
			(layer "F.SilkS")
			(effects
				(font
					(size 0.7 0.7)
					(thickness 0.15)
				)
				(justify left bottom)
			)
		)
		(property "Value" "TPD1E0B04_XDFN-2"
			(at 0 1.5 -90)
			(layer "F.Fab")
			(effects
				(font
					(size 0.7 0.7)
					(thickness 0.15)
				)
				(justify left bottom)
			)
		)
		(property "Footprint" "antmicro-footprints:XDFN-2_1x0.60mm"
			(at 0 0 -90)
			(layer "F.Fab")
			(hide yes)
			(effects
				(font
					(size 1.27 1.27)
					(thickness 0.15)
				)
			)
		)
		(property "Datasheet" "https://www.ti.com/general/docs/suppproductinfo.tsp?distId=26&gotoUrl=https://www.ti.com/lit/gpn/tpd1e0b04"
			(at 0 0 -90)
			(layer "F.Fab")
			(hide yes)
			(effects
				(font
					(size 1.27 1.27)
					(thickness 0.15)
				)
			)
		)
		(property "MPN" "TPD1E0B04DPYR"
			(at 59.25 235.65 0)
			(layer "F.Fab")
			(hide yes)
			(effects
				(font
					(size 1 1)
					(thickness 0.15)
				)
			)
		)
		(property "Manufacturer" "Texas Instruments"
			(at 59.25 235.65 0)
			(layer "F.Fab")
			(hide yes)
			(effects
				(font
					(size 1 1)
					(thickness 0.15)
				)
			)
		)
		(property "Author" "Antmicro"
			(at 59.25 235.65 0)
			(layer "F.Fab")
			(hide yes)
			(effects
				(font
					(size 1 1)
					(thickness 0.15)
				)
			)
		)
		(property "License" "Apache-2.0"
			(at 59.25 235.65 0)
			(layer "F.Fab")
			(hide yes)
			(effects
				(font
					(size 1 1)
					(thickness 0.15)
				)
			)
		)
		(sheetname "Peripherals")
		(sheetfile "peripherals.kicad_sch")
		(attr smd)
		(fp_rect
			(start -0.725 -0.475)
			(end 0.725 0.475)
			(stroke
				(width 0.05)
				(type solid)
			)
			(fill none)
			(layer "F.CrtYd")
		)
		(fp_rect
			(start -0.55 -0.35)
			(end 0.55 0.35)
			(stroke
				(width 0.15)
				(type solid)
			)
			(fill none)
			(layer "F.Fab")
		)
		(fp_text user "License: Apache-2.0"
			(at -0.8 5.6 -90)
			(layer "F.Fab")
			(hide yes)
			(effects
				(font
					(size 0.7 0.7)
					(thickness 0.15)
				)
				(justify left bottom)
			)
		)
		(fp_text user "Author: Antmicro"
			(at -0.8 4.4 -90)
			(layer "F.Fab")
			(hide yes)
			(effects
				(font
					(size 0.7 0.7)
					(thickness 0.15)
				)
				(justify left bottom)
			)
		)
		(fp_text user "${REFERENCE}"
			(at -0.8 3.2 -90)
			(layer "F.Fab")
			(hide yes)
			(effects
				(font
					(size 0.7 0.7)
					(thickness 0.15)
				)
				(justify left bottom)
			)
		)
		(pad "1" smd roundrect
			(at -0.351 0 270)
			(size 0.3 0.5)
			(layers "F.Cu" "F.Paste" "F.Mask")
			(roundrect_rratio 0.25)
			(net 131 "PCIE2_RX0_P")
			(pinfunction "C")
			(pintype "passive")
		)
		(pad "2" smd roundrect
			(at 0.349 0 270)
			(size 0.3 0.5)
			(layers "F.Cu" "F.Paste" "F.Mask")
			(roundrect_rratio 0.25)
			(net 1 "GND")
			(pinfunction "A")
			(pintype "passive")
		)
	)
	(footprint "antmicro-footprints:R_0402_1005Metric"
		(layer "F.Cu")
		(at 102.95 89.8 -90)
		(descr "Resistor SMD 0402")
		(tags "resistor SMD 0402")
		(property "Reference" "R47"
			(at 0.98 -1.37 -90)
			(layer "F.SilkS")
			(effects
				(font
					(size 0.7 0.7)
					(thickness 0.15)
				)
				(justify left bottom)
			)
		)
		(property "Value" "R_10k_0402"
			(at 0 1.4 -90)
			(layer "F.Fab")
			(effects
				(font
					(size 0.7 0.7)
					(thickness 0.15)
				)
				(justify left bottom)
			)
		)
		(property "Footprint" "antmicro-footprints:R_0402_1005Metric"
			(at 0 0 -90)
			(layer "F.Fab")
			(hide yes)
			(effects
				(font
					(size 1.27 1.27)
					(thickness 0.15)
				)
			)
		)
		(property "Datasheet" "https://www.bourns.com/docs/product-datasheets/cr.pdf"
			(at 0 0 -90)
			(layer "F.Fab")
			(hide yes)
			(effects
				(font
					(size 1.27 1.27)
					(thickness 0.15)
				)
			)
		)
		(property "Author" "Antmicro"
			(at 13.15 192.75 0)
			(layer "F.Fab")
			(hide yes)
			(effects
				(font
					(size 1 1)
					(thickness 0.15)
				)
			)
		)
		(property "License" "Apache-2.0"
			(at 13.15 192.75 0)
			(layer "F.Fab")
			(hide yes)
			(effects
				(font
					(size 1 1)
					(thickness 0.15)
				)
			)
		)
		(property "MPN" "CR0402-FX-1002GLF"
			(at 13.15 192.75 0)
			(layer "F.Fab")
			(hide yes)
			(effects
				(font
					(size 1 1)
					(thickness 0.15)
				)
			)
		)
		(property "Manufacturer" "Bourns"
			(at 13.15 192.75 0)
			(layer "F.Fab")
			(hide yes)
			(effects
				(font
					(size 1 1)
					(thickness 0.15)
				)
			)
		)
		(property "Tolerance" "1%"
			(at 13.15 192.75 0)
			(layer "F.Fab")
			(hide yes)
			(effects
				(font
					(size 1 1)
					(thickness 0.15)
				)
			)
		)
		(property "Val" "10k"
			(at 13.15 192.75 0)
			(layer "F.Fab")
			(hide yes)
			(effects
				(font
					(size 1 1)
					(thickness 0.15)
				)
			)
		)
		(sheetname "HDMI")
		(sheetfile "hdmi.kicad_sch")
		(attr smd)
		(fp_rect
			(start -0.925 -0.47)
			(end 0.925 0.47)
			(stroke
				(width 0.05)
				(type default)
			)
			(fill none)
			(layer "F.CrtYd")
		)
		(fp_rect
			(start -0.5 -0.25)
			(end 0.5 0.25)
			(stroke
				(width 0.15)
				(type solid)
			)
			(fill none)
			(layer "F.Fab")
		)
		(fp_text user "${REFERENCE}"
			(at -0.95 3.168 -90)
			(layer "F.Fab")
			(hide yes)
			(effects
				(font
					(size 0.7 0.7)
					(thickness 0.15)
				)
				(justify left bottom)
			)
		)
		(fp_text user "Author: Antmicro"
			(at -0.95 4.169 -90)
			(layer "F.Fab")
			(hide yes)
			(effects
				(font
					(size 0.7 0.7)
					(thickness 0.15)
				)
				(justify left bottom)
			)
		)
		(fp_text user "License: Apache-2.0"
			(at -0.95 5.169 -90)
			(layer "F.Fab")
			(hide yes)
			(effects
				(font
					(size 0.7 0.7)
					(thickness 0.15)
				)
				(justify left bottom)
			)
		)
		(pad "1" smd roundrect
			(at -0.48 0 270)
			(size 0.59 0.64)
			(layers "F.Cu" "F.Paste" "F.Mask")
			(roundrect_rratio 0.25)
			(net 621 "Net-(Q1-S)")
			(pintype "passive")
		)
		(pad "2" smd roundrect
			(at 0.48 0 270)
			(size 0.59 0.64)
			(layers "F.Cu" "F.Paste" "F.Mask")
			(roundrect_rratio 0.25)
			(net 112 "+1V8")
			(pintype "passive")
		)
	)
	(footprint "antmicro-footprints:R_Array_4x0402"
		(layer "F.Cu")
		(at 137.4 97.72 90)
		(property "Reference" "R53"
			(at -1.13 -0.9 90)
			(layer "F.SilkS")
			(effects
				(font
					(size 0.7 0.7)
					(thickness 0.15)
				)
				(justify left bottom)
			)
		)
		(property "Value" "R_4x330R_0402_array"
			(at -1.5 2 90)
			(layer "F.Fab")
			(effects
				(font
					(size 0.7 0.7)
					(thickness 0.15)
				)
				(justify left bottom)
			)
		)
		(property "Footprint" "antmicro-footprints:R_Array_4x0402"
			(at 0 0 90)
			(layer "F.Fab")
			(hide yes)
			(effects
				(font
					(size 1.27 1.27)
					(thickness 0.15)
				)
			)
		)
		(property "Datasheet" "http://industrial.panasonic.com/cdbs/www-data/pdf/AOC0000/AOC0000C14.pdf"
			(at 0 0 90)
			(layer "F.Fab")
			(hide yes)
			(effects
				(font
					(size 1.27 1.27)
					(thickness 0.15)
				)
			)
		)
		(property "Author" "Antmicro"
			(at 235.12 -39.68 0)
			(layer "F.Fab")
			(hide yes)
			(effects
				(font
					(size 1 1)
					(thickness 0.15)
				)
			)
		)
		(property "License" "Apache-2.0"
			(at 235.12 -39.68 0)
			(layer "F.Fab")
			(hide yes)
			(effects
				(font
					(size 1 1)
					(thickness 0.15)
				)
			)
		)
		(property "MPN" "EXB-28V331JX"
			(at 235.12 -39.68 0)
			(layer "F.Fab")
			(hide yes)
			(effects
				(font
					(size 1 1)
					(thickness 0.15)
				)
			)
		)
		(property "Manufacturer" "Panasonic"
			(at 235.12 -39.68 0)
			(layer "F.Fab")
			(hide yes)
			(effects
				(font
					(size 1 1)
					(thickness 0.15)
				)
			)
		)
		(property "Val" "R_4x330R_0402"
			(at 235.12 -39.68 0)
			(layer "F.Fab")
			(hide yes)
			(effects
				(font
					(size 1 1)
					(thickness 0.15)
				)
			)
		)
		(sheetname "Peripherals")
		(sheetfile "peripherals.kicad_sch")
		(attr smd)
		(fp_line
			(start -1.17 -0.5)
			(end -1.17 0.498)
			(stroke
				(width 0.15)
				(type solid)
			)
			(layer "F.SilkS")
		)
		(fp_line
			(start 1.167 0.498)
			(end 1.167 -0.5)
			(stroke
				(width 0.15)
				(type solid)
			)
			(layer "F.SilkS")
		)
		(fp_rect
			(start -1.2 -0.9)
			(end 1.2 0.9)
			(stroke
				(width 0.05)
				(type solid)
			)
			(fill none)
			(layer "F.CrtYd")
		)
		(fp_line
			(start 0.998 -0.5)
			(end 0.998 0.498)
			(stroke
				(width 0.15)
				(type solid)
			)
			(layer "F.Fab")
		)
		(fp_line
			(start -1 -0.5)
			(end 0.998 -0.5)
			(stroke
				(width 0.15)
				(type solid)
			)
			(layer "F.Fab")
		)
		(fp_line
			(start 0.998 0.498)
			(end -1 0.498)
			(stroke
				(width 0.15)
				(type solid)
			)
			(layer "F.Fab")
		)
		(fp_line
			(start -1 0.498)
			(end -1 -0.5)
			(stroke
				(width 0.15)
				(type solid)
			)
			(layer "F.Fab")
		)
		(fp_text user "${REFERENCE}"
			(at -1.5 3.25 90)
			(layer "F.Fab")
			(hide yes)
			(effects
				(font
					(size 0.7 0.7)
					(thickness 0.15)
				)
				(justify left bottom)
			)
		)
		(fp_text user "License: Apache-2.0"
			(at -1.5 5.75 90)
			(layer "F.Fab")
			(hide yes)
			(effects
				(font
					(size 0.7 0.7)
					(thickness 0.15)
				)
				(justify left bottom)
			)
		)
		(fp_text user "Author: Antmicro"
			(at -1.5 4.5 90)
			(layer "F.Fab")
			(hide yes)
			(effects
				(font
					(size 0.7 0.7)
					(thickness 0.15)
				)
				(justify left bottom)
			)
		)
		(pad "1" smd roundrect
			(at -0.802 0.45 90)
			(size 0.4 0.5)
			(layers "F.Cu" "F.Paste" "F.Mask")
			(roundrect_rratio 0.25)
			(net 584 "/Peripherals/UART1_RXD_CONN")
			(pinfunction "R1.1")
			(pintype "passive")
		)
		(pad "2" smd roundrect
			(at -0.272 0.45 90)
			(size 0.4 0.5)
			(layers "F.Cu" "F.Paste" "F.Mask")
			(roundrect_rratio 0.25)
			(net 579 "/Peripherals/GPIO09_CONN")
			(pinfunction "R2.1")
			(pintype "passive")
		)
		(pad "3" smd roundrect
			(at 0.27 0.45 90)
			(size 0.4 0.5)
			(layers "F.Cu" "F.Paste" "F.Mask")
			(roundrect_rratio 0.25)
			(net 637 "unconnected-(R53-R3.1-Pad3)")
			(pinfunction "R3.1")
			(pintype "passive+no_connect")
		)
		(pad "4" smd roundrect
			(at 0.8 0.45 90)
			(size 0.4 0.5)
			(layers "F.Cu" "F.Paste" "F.Mask")
			(roundrect_rratio 0.25)
			(net 638 "unconnected-(R53-R4.1-Pad4)")
			(pinfunction "R4.1")
			(pintype "passive+no_connect")
		)
		(pad "5" smd roundrect
			(at 0.8 -0.452 90)
			(size 0.4 0.5)
			(layers "F.Cu" "F.Paste" "F.Mask")
			(roundrect_rratio 0.25)
			(net 640 "unconnected-(R53-R4.2-Pad5)")
			(pinfunction "R4.2")
			(pintype "passive+no_connect")
		)
		(pad "6" smd roundrect
			(at 0.27 -0.452 90)
			(size 0.4 0.5)
			(layers "F.Cu" "F.Paste" "F.Mask")
			(roundrect_rratio 0.25)
			(net 645 "unconnected-(R53-R3.2-Pad6)")
			(pinfunction "R3.2")
			(pintype "passive+no_connect")
		)
		(pad "7" smd roundrect
			(at -0.272 -0.452 90)
			(size 0.4 0.5)
			(layers "F.Cu" "F.Paste" "F.Mask")
			(roundrect_rratio 0.25)
			(net 78 "GPIO09")
			(pinfunction "R2.2")
			(pintype "passive")
		)
		(pad "8" smd roundrect
			(at -0.802 -0.452 90)
			(size 0.4 0.5)
			(layers "F.Cu" "F.Paste" "F.Mask")
			(roundrect_rratio 0.25)
			(net 461 "UART1_RXD")
			(pinfunction "R1.2")
			(pintype "passive")
		)
	)
	(footprint "antmicro-footprints:USON-10_2.5x1mm_P0.5mm"
		(layer "F.Cu")
		(at 72 115.5 90)
		(descr "USON-10 2.5x1mm_ Pitch 0.5mm")
		(tags "USON-10 2.5x1mm Pitch 0.5mm")
		(property "Reference" "U15"
			(at 0.85 -1.55 180)
			(layer "F.SilkS")
			(effects
				(font
					(size 0.7 0.7)
					(thickness 0.15)
				)
				(justify left bottom)
			)
		)
		(property "Value" "TPD4E05U06QDQARQ1"
			(at 0.018 2.499 90)
			(layer "F.Fab")
			(effects
				(font
					(size 0.7 0.7)
					(thickness 0.15)
				)
				(justify left bottom)
			)
		)
		(property "Footprint" "antmicro-footprints:USON-10_2.5x1mm_P0.5mm"
			(at 0 0 90)
			(layer "F.Fab")
			(hide yes)
			(effects
				(font
					(size 1.27 1.27)
					(thickness 0.15)
				)
			)
		)
		(property "Datasheet" "https://www.ti.com/lit/ds/symlink/tpd4e05u06-q1.pdf?HQS=dis-mous-null-mousermode-dsf-pf-null-wwe&ts=1663591265741&ref_url=https%253A%252F%252Fwww.mouser.com%252F"
			(at 0 0 90)
			(layer "F.Fab")
			(hide yes)
			(effects
				(font
					(size 1.27 1.27)
					(thickness 0.15)
				)
			)
		)
		(property "Author" "Antmicro"
			(at 187.5 43.5 0)
			(layer "F.Fab")
			(hide yes)
			(effects
				(font
					(size 1 1)
					(thickness 0.15)
				)
			)
		)
		(property "License" "Apache-2.0"
			(at 187.5 43.5 0)
			(layer "F.Fab")
			(hide yes)
			(effects
				(font
					(size 1 1)
					(thickness 0.15)
				)
			)
		)
		(property "MPN" "TPD4E05U06QDQARQ1"
			(at 187.5 43.5 0)
			(layer "F.Fab")
			(hide yes)
			(effects
				(font
					(size 1 1)
					(thickness 0.15)
				)
			)
		)
		(property "Manufacturer" "Texas Instruments"
			(at 187.5 43.5 0)
			(layer "F.Fab")
			(hide yes)
			(effects
				(font
					(size 1 1)
					(thickness 0.15)
				)
			)
		)
		(sheetname "USB Debug, DP")
		(sheetfile "usb.kicad_sch")
		(attr smd)
		(fp_line
			(start 0.498 -1.401)
			(end -0.5 -1.401)
			(stroke
				(width 0.15)
				(type solid)
			)
			(layer "F.SilkS")
		)
		(fp_line
			(start 0.498 1.398)
			(end -0.5 1.398)
			(stroke
				(width 0.15)
				(type solid)
			)
			(layer "F.SilkS")
		)
		(fp_circle
			(center -0.68 -1.27)
			(end -0.63 -1.27)
			(stroke
				(width 0.15)
				(type solid)
			)
			(fill solid)
			(layer "F.SilkS")
		)
		(fp_rect
			(start -0.8 -1.5)
			(end 0.8 1.499)
			(stroke
				(width 0.05)
				(type solid)
			)
			(fill none)
			(layer "F.CrtYd")
		)
		(fp_line
			(start 0.498 -1.25)
			(end -0.25 -1.25)
			(stroke
				(width 0.15)
				(type solid)
			)
			(layer "F.Fab")
		)
		(fp_line
			(start 0.498 -1.25)
			(end 0.498 1.249)
			(stroke
				(width 0.15)
				(type solid)
			)
			(layer "F.Fab")
		)
		(fp_line
			(start -0.25 -1.25)
			(end -0.5 -1)
			(stroke
				(width 0.15)
				(type solid)
			)
			(layer "F.Fab")
		)
		(fp_line
			(start -0.5 -1)
			(end -0.5 1.249)
			(stroke
				(width 0.15)
				(type solid)
			)
			(layer "F.Fab")
		)
		(fp_line
			(start -0.5 1.249)
			(end 0.498 1.249)
			(stroke
				(width 0.15)
				(type solid)
			)
			(layer "F.Fab")
		)
		(fp_text user "${REFERENCE}"
			(at -0.802 4.498 90)
			(layer "F.Fab")
			(hide yes)
			(effects
				(font
					(size 0.7 0.7)
					(thickness 0.15)
				)
				(justify left bottom)
			)
		)
		(fp_text user "Author: Antmicro"
			(at -0.802 5.7 90)
			(layer "F.Fab")
			(hide yes)
			(effects
				(font
					(size 0.7 0.7)
					(thickness 0.15)
				)
				(justify left bottom)
			)
		)
		(fp_text user "License: Apache-2.0"
			(at -0.802 6.9 90)
			(layer "F.Fab")
			(hide yes)
			(effects
				(font
					(size 0.7 0.7)
					(thickness 0.15)
				)
				(justify left bottom)
			)
		)
		(pad "1" smd roundrect
			(at -0.387 -1)
			(size 0.25 0.55)
			(layers "F.Cu" "F.Paste" "F.Mask")
			(roundrect_rratio 0.25)
			(net 154 "/USB Debug, DP/USBC0_RX1_P")
			(pintype "passive")
		)
		(pad "2" smd roundrect
			(at -0.387 -0.5)
			(size 0.25 0.55)
			(layers "F.Cu" "F.Paste" "F.Mask")
			(roundrect_rratio 0.25)
			(net 152 "/USB Debug, DP/USBC0_RX1_N")
			(pintype "passive")
		)
		(pad "3" smd roundrect
			(at -0.387 0)
			(size 0.4 0.55)
			(layers "F.Cu" "F.Paste" "F.Mask")
			(roundrect_rratio 0.25)
			(net 1 "GND")
			(pintype "power_in")
		)
		(pad "4" smd roundrect
			(at -0.387 0.498)
			(size 0.25 0.55)
			(layers "F.Cu" "F.Paste" "F.Mask")
			(roundrect_rratio 0.25)
			(net 258 "/USB Debug, DP/USBC0_CONN_TX1_P")
			(pintype "passive")
		)
		(pad "5" smd roundrect
			(at -0.387 0.998)
			(size 0.25 0.55)
			(layers "F.Cu" "F.Paste" "F.Mask")
			(roundrect_rratio 0.25)
			(net 198 "/USB Debug, DP/USBC0_CONN_TX1_N")
			(pintype "passive")
		)
		(pad "6" smd roundrect
			(at 0.385 0.998)
			(size 0.25 0.55)
			(layers "F.Cu" "F.Paste" "F.Mask")
			(roundrect_rratio 0.25)
			(net 198 "/USB Debug, DP/USBC0_CONN_TX1_N")
			(pintype "passive")
		)
		(pad "7" smd roundrect
			(at 0.385 0.498)
			(size 0.25 0.55)
			(layers "F.Cu" "F.Paste" "F.Mask")
			(roundrect_rratio 0.25)
			(net 258 "/USB Debug, DP/USBC0_CONN_TX1_P")
			(pintype "passive")
		)
		(pad "8" smd roundrect
			(at 0.385 0)
			(size 0.4 0.55)
			(layers "F.Cu" "F.Paste" "F.Mask")
			(roundrect_rratio 0.25)
			(net 1 "GND")
			(pintype "passive")
		)
		(pad "9" smd roundrect
			(at 0.385 -0.5)
			(size 0.25 0.55)
			(layers "F.Cu" "F.Paste" "F.Mask")
			(roundrect_rratio 0.25)
			(net 152 "/USB Debug, DP/USBC0_RX1_N")
			(pintype "passive")
		)
		(pad "10" smd roundrect
			(at 0.385 -1)
			(size 0.25 0.55)
			(layers "F.Cu" "F.Paste" "F.Mask")
			(roundrect_rratio 0.25)
			(net 154 "/USB Debug, DP/USBC0_RX1_P")
			(pintype "passive")
		)
	)
	(footprint "antmicro-footprints:R_0603_1608Metric"
		(layer "F.Cu")
		(at 143.85 119.3)
		(descr "Resistor SMD 0603")
		(tags "resistor SMD 0603")
		(property "Reference" "R248"
			(at -2.75 1.5 0)
			(layer "F.SilkS")
			(effects
				(font
					(size 0.7 0.7)
					(thickness 0.15)
				)
				(justify left bottom)
			)
		)
		(property "Value" "R_0R_22.4A_0603"
			(at 0 1.6 0)
			(layer "F.Fab")
			(effects
				(font
					(size 0.7 0.7)
					(thickness 0.15)
				)
				(justify left bottom)
			)
		)
		(property "Footprint" "antmicro-footprints:R_0603_1608Metric"
			(at 0 0 0)
			(layer "F.Fab")
			(hide yes)
			(effects
				(font
					(size 1.27 1.27)
					(thickness 0.15)
				)
			)
		)
		(property "Datasheet" "https://fscdn.rohm.com/en/products/databook/datasheet/passive/resistor/chip_resistor/pmr-jpw-e.pdf"
			(at 0 0 0)
			(layer "F.Fab")
			(hide yes)
			(effects
				(font
					(size 1.27 1.27)
					(thickness 0.15)
				)
			)
		)
		(property "Author" "Antmicro"
			(at 0 0 0)
			(layer "F.Fab")
			(hide yes)
			(effects
				(font
					(size 1 1)
					(thickness 0.15)
				)
			)
		)
		(property "License" "Apache-2.0"
			(at 0 0 0)
			(layer "F.Fab")
			(hide yes)
			(effects
				(font
					(size 1 1)
					(thickness 0.15)
				)
			)
		)
		(property "MPN" "PMR03EZPJ000"
			(at 0 0 0)
			(layer "F.Fab")
			(hide yes)
			(effects
				(font
					(size 1 1)
					(thickness 0.15)
				)
			)
		)
		(property "Manufacturer" "ROHM Semiconductor"
			(at 0 0 0)
			(layer "F.Fab")
			(hide yes)
			(effects
				(font
					(size 1 1)
					(thickness 0.15)
				)
			)
		)
		(property "Max. Curr." "22.4A"
			(at 0 0 0)
			(layer "F.Fab")
			(hide yes)
			(effects
				(font
					(size 1 1)
					(thickness 0.15)
				)
			)
		)
		(property "Tolerance" "template_tolerance"
			(at 0 0 0)
			(layer "F.Fab")
			(hide yes)
			(effects
				(font
					(size 1 1)
					(thickness 0.15)
				)
			)
		)
		(property "Val" "0R"
			(at 0 0 0)
			(layer "F.Fab")
			(hide yes)
			(effects
				(font
					(size 1 1)
					(thickness 0.15)
				)
			)
		)
		(sheetname "Peripherals")
		(sheetfile "peripherals.kicad_sch")
		(attr smd)
		(fp_line
			(start -0.15 -0.4)
			(end 0.15 -0.4)
			(stroke
				(width 0.15)
				(type solid)
			)
			(layer "F.SilkS")
		)
		(fp_line
			(start -0.15 0.4)
			(end 0.15 0.4)
			(stroke
				(width 0.15)
				(type solid)
			)
			(layer "F.SilkS")
		)
		(fp_rect
			(start -1.25 -0.65)
			(end 1.25 0.65)
			(stroke
				(width 0.05)
				(type solid)
			)
			(fill none)
			(layer "F.CrtYd")
		)
		(fp_rect
			(start -0.8 -0.4)
			(end 0.8 0.4)
			(stroke
				(width 0.15)
				(type solid)
			)
			(fill none)
			(layer "F.Fab")
		)
		(fp_text user "${REFERENCE}"
			(at -1.25 3.898 0)
			(layer "F.Fab")
			(hide yes)
			(effects
				(font
					(size 0.7 0.7)
					(thickness 0.15)
				)
				(justify left bottom)
			)
		)
		(fp_text user "License: Apache-2.0"
			(at -1.25 5.9 0)
			(layer "F.Fab")
			(hide yes)
			(effects
				(font
					(size 0.7 0.7)
					(thickness 0.15)
				)
				(justify left bottom)
			)
		)
		(fp_text user "Author: Antmicro"
			(at -1.25 4.9 0)
			(layer "F.Fab")
			(hide yes)
			(effects
				(font
					(size 0.7 0.7)
					(thickness 0.15)
				)
				(justify left bottom)
			)
		)
		(pad "1" smd roundrect
			(at -0.7 0)
			(size 0.8 1)
			(layers "F.Cu" "F.Paste" "F.Mask")
			(roundrect_rratio 0.2)
			(net 115 "VCC")
			(pintype "passive")
		)
		(pad "2" smd roundrect
			(at 0.7 0)
			(size 0.8 1)
			(layers "F.Cu" "F.Paste" "F.Mask")
			(roundrect_rratio 0.2)
			(net 485 "/Peripherals/VCC_CONN")
			(pintype "passive")
		)
	)
	(footprint "antmicro-footprints:R_0402_1005Metric"
		(layer "F.Cu")
		(at 100.05 114.65 -90)
		(descr "Resistor SMD 0402")
		(tags "resistor SMD 0402")
		(property "Reference" "R232"
			(at -0.8 -0.45 -90)
			(layer "F.SilkS")
			(effects
				(font
					(size 0.7 0.7)
					(thickness 0.15)
				)
				(justify left bottom)
			)
		)
		(property "Value" "R_10k_0402"
			(at 0 1.4 -90)
			(layer "F.Fab")
			(effects
				(font
					(size 0.7 0.7)
					(thickness 0.15)
				)
				(justify left bottom)
			)
		)
		(property "Footprint" "antmicro-footprints:R_0402_1005Metric"
			(at 0 0 -90)
			(layer "F.Fab")
			(hide yes)
			(effects
				(font
					(size 1.27 1.27)
					(thickness 0.15)
				)
			)
		)
		(property "Datasheet" "https://www.bourns.com/docs/product-datasheets/cr.pdf"
			(at 0 0 -90)
			(layer "F.Fab")
			(hide yes)
			(effects
				(font
					(size 1.27 1.27)
					(thickness 0.15)
				)
			)
		)
		(property "Author" "Antmicro"
			(at -14.6 214.7 0)
			(layer "F.Fab")
			(hide yes)
			(effects
				(font
					(size 1 1)
					(thickness 0.15)
				)
			)
		)
		(property "License" "Apache-2.0"
			(at -14.6 214.7 0)
			(layer "F.Fab")
			(hide yes)
			(effects
				(font
					(size 1 1)
					(thickness 0.15)
				)
			)
		)
		(property "MPN" "CR0402-FX-1002GLF"
			(at -14.6 214.7 0)
			(layer "F.Fab")
			(hide yes)
			(effects
				(font
					(size 1 1)
					(thickness 0.15)
				)
			)
		)
		(property "Manufacturer" "Bourns"
			(at -14.6 214.7 0)
			(layer "F.Fab")
			(hide yes)
			(effects
				(font
					(size 1 1)
					(thickness 0.15)
				)
			)
		)
		(property "Tolerance" "1%"
			(at -14.6 214.7 0)
			(layer "F.Fab")
			(hide yes)
			(effects
				(font
					(size 1 1)
					(thickness 0.15)
				)
			)
		)
		(property "Val" "10k"
			(at -14.6 214.7 0)
			(layer "F.Fab")
			(hide yes)
			(effects
				(font
					(size 1 1)
					(thickness 0.15)
				)
			)
		)
		(sheetname "Peripherals")
		(sheetfile "peripherals.kicad_sch")
		(attr smd)
		(fp_rect
			(start -0.925 -0.47)
			(end 0.925 0.47)
			(stroke
				(width 0.05)
				(type default)
			)
			(fill none)
			(layer "F.CrtYd")
		)
		(fp_rect
			(start -0.5 -0.25)
			(end 0.5 0.25)
			(stroke
				(width 0.15)
				(type solid)
			)
			(fill none)
			(layer "F.Fab")
		)
		(fp_text user "Author: Antmicro"
			(at -0.95 4.169 -90)
			(layer "F.Fab")
			(hide yes)
			(effects
				(font
					(size 0.7 0.7)
					(thickness 0.15)
				)
				(justify left bottom)
			)
		)
		(fp_text user "${REFERENCE}"
			(at -0.95 3.168 -90)
			(layer "F.Fab")
			(hide yes)
			(effects
				(font
					(size 0.7 0.7)
					(thickness 0.15)
				)
				(justify left bottom)
			)
		)
		(fp_text user "License: Apache-2.0"
			(at -0.95 5.169 -90)
			(layer "F.Fab")
			(hide yes)
			(effects
				(font
					(size 0.7 0.7)
					(thickness 0.15)
				)
				(justify left bottom)
			)
		)
		(pad "1" smd roundrect
			(at -0.48 0 270)
			(size 0.59 0.64)
			(layers "F.Cu" "F.Paste" "F.Mask")
			(roundrect_rratio 0.25)
			(net 45 "USER_BTN0")
			(pintype "passive")
		)
		(pad "2" smd roundrect
			(at 0.48 0 270)
			(size 0.59 0.64)
			(layers "F.Cu" "F.Paste" "F.Mask")
			(roundrect_rratio 0.25)
			(net 112 "+1V8")
			(pintype "passive")
		)
	)
	(footprint "antmicro-footprints:C_0402_1005Metric"
		(layer "F.Cu")
		(at 79.9 106.25)
		(descr "Capacitor SMD 0402")
		(tags "capacitor SMD 0402")
		(property "Reference" "C36"
			(at -1.15 -0.45 0)
			(layer "F.SilkS")
			(effects
				(font
					(size 0.7 0.7)
					(thickness 0.15)
				)
				(justify left bottom)
			)
		)
		(property "Value" "C_100n_0402"
			(at 0 1.4 0)
			(layer "F.Fab")
			(effects
				(font
					(size 0.7 0.7)
					(thickness 0.15)
				)
				(justify left bottom)
			)
		)
		(property "Footprint" "antmicro-footprints:C_0402_1005Metric"
			(at 0 0 0)
			(layer "F.Fab")
			(hide yes)
			(effects
				(font
					(size 1.27 1.27)
					(thickness 0.15)
				)
			)
		)
		(property "Datasheet" "https://www.murata.com/products/productdetail?partno=GRM155R61H104KE14%23"
			(at 0 0 0)
			(layer "F.Fab")
			(hide yes)
			(effects
				(font
					(size 1.27 1.27)
					(thickness 0.15)
				)
			)
		)
		(property "Author" "Antmicro"
			(at 0 0 0)
			(layer "F.Fab")
			(hide yes)
			(effects
				(font
					(size 1 1)
					(thickness 0.15)
				)
			)
		)
		(property "Dielectric" "X5R"
			(at 0 0 0)
			(layer "F.Fab")
			(hide yes)
			(effects
				(font
					(size 1 1)
					(thickness 0.15)
				)
			)
		)
		(property "License" "Apache-2.0"
			(at 0 0 0)
			(layer "F.Fab")
			(hide yes)
			(effects
				(font
					(size 1 1)
					(thickness 0.15)
				)
			)
		)
		(property "MPN" "GRM155R61H104KE14D"
			(at 0 0 0)
			(layer "F.Fab")
			(hide yes)
			(effects
				(font
					(size 1 1)
					(thickness 0.15)
				)
			)
		)
		(property "Manufacturer" "Murata"
			(at 0 0 0)
			(layer "F.Fab")
			(hide yes)
			(effects
				(font
					(size 1 1)
					(thickness 0.15)
				)
			)
		)
		(property "Val" "100n"
			(at 0 0 0)
			(layer "F.Fab")
			(hide yes)
			(effects
				(font
					(size 1 1)
					(thickness 0.15)
				)
			)
		)
		(property "Voltage" "50V"
			(at 0 0 0)
			(layer "F.Fab")
			(hide yes)
			(effects
				(font
					(size 1 1)
					(thickness 0.15)
				)
			)
		)
		(sheetname "USB Debug, DP")
		(sheetfile "usb.kicad_sch")
		(attr smd)
		(fp_rect
			(start -0.925 -0.47)
			(end 0.925 0.47)
			(stroke
				(width 0.05)
				(type default)
			)
			(fill none)
			(layer "F.CrtYd")
		)
		(fp_line
			(start -0.494 -0.25)
			(end 0.504 -0.25)
			(stroke
				(width 0.15)
				(type solid)
			)
			(layer "F.Fab")
		)
		(fp_line
			(start -0.494 0.248)
			(end -0.494 -0.25)
			(stroke
				(width 0.15)
				(type solid)
			)
			(layer "F.Fab")
		)
		(fp_line
			(start 0.504 -0.25)
			(end 0.504 0.248)
			(stroke
				(width 0.15)
				(type solid)
			)
			(layer "F.Fab")
		)
		(fp_line
			(start 0.504 0.248)
			(end -0.494 0.248)
			(stroke
				(width 0.15)
				(type solid)
			)
			(layer "F.Fab")
		)
		(fp_text user "License: Apache-2.0"
			(at -0.932 5.17 0)
			(layer "F.Fab")
			(hide yes)
			(effects
				(font
					(size 0.7 0.7)
					(thickness 0.15)
				)
				(justify left bottom)
			)
		)
		(fp_text user "${REFERENCE}"
			(at -0.932 3.168 0)
			(layer "F.Fab")
			(hide yes)
			(effects
				(font
					(size 0.7 0.7)
					(thickness 0.15)
				)
				(justify left bottom)
			)
		)
		(fp_text user "Author: Antmicro"
			(at -0.932 4.17 0)
			(layer "F.Fab")
			(hide yes)
			(effects
				(font
					(size 0.7 0.7)
					(thickness 0.15)
				)
				(justify left bottom)
			)
		)
		(pad "1" smd roundrect
			(at -0.48 0)
			(size 0.59 0.64)
			(layers "F.Cu" "F.Paste" "F.Mask")
			(roundrect_rratio 0.25)
			(net 87 "+3V3")
			(pintype "passive")
		)
		(pad "2" smd roundrect
			(at 0.48 0)
			(size 0.59 0.64)
			(layers "F.Cu" "F.Paste" "F.Mask")
			(roundrect_rratio 0.25)
			(net 1 "GND")
			(pintype "passive")
		)
	)
	(footprint "antmicro-footprints:C_0402_1005Metric"
		(layer "F.Cu")
		(at 101.2 122.4 -90)
		(descr "Capacitor SMD 0402")
		(tags "capacitor SMD 0402")
		(property "Reference" "C75"
			(at 0.95 0.35 -90)
			(layer "F.SilkS")
			(effects
				(font
					(size 0.7 0.7)
					(thickness 0.15)
				)
				(justify left bottom)
			)
		)
		(property "Value" "C_100n_0402"
			(at 0 1.4 -90)
			(layer "F.Fab")
			(effects
				(font
					(size 0.7 0.7)
					(thickness 0.15)
				)
				(justify left bottom)
			)
		)
		(property "Footprint" "antmicro-footprints:C_0402_1005Metric"
			(at 0 0 -90)
			(layer "F.Fab")
			(hide yes)
			(effects
				(font
					(size 1.27 1.27)
					(thickness 0.15)
				)
			)
		)
		(property "Datasheet" "https://www.murata.com/products/productdetail?partno=GRM155R61H104KE14%23"
			(at 0 0 -90)
			(layer "F.Fab")
			(hide yes)
			(effects
				(font
					(size 1.27 1.27)
					(thickness 0.15)
				)
			)
		)
		(property "Author" "Antmicro"
			(at -21.2 223.6 0)
			(layer "F.Fab")
			(hide yes)
			(effects
				(font
					(size 1 1)
					(thickness 0.15)
				)
			)
		)
		(property "Dielectric" "X5R"
			(at -21.2 223.6 0)
			(layer "F.Fab")
			(hide yes)
			(effects
				(font
					(size 1 1)
					(thickness 0.15)
				)
			)
		)
		(property "License" "Apache-2.0"
			(at -21.2 223.6 0)
			(layer "F.Fab")
			(hide yes)
			(effects
				(font
					(size 1 1)
					(thickness 0.15)
				)
			)
		)
		(property "MPN" "GRM155R61H104KE14D"
			(at -21.2 223.6 0)
			(layer "F.Fab")
			(hide yes)
			(effects
				(font
					(size 1 1)
					(thickness 0.15)
				)
			)
		)
		(property "Manufacturer" "Murata"
			(at -21.2 223.6 0)
			(layer "F.Fab")
			(hide yes)
			(effects
				(font
					(size 1 1)
					(thickness 0.15)
				)
			)
		)
		(property "Val" "100n"
			(at -21.2 223.6 0)
			(layer "F.Fab")
			(hide yes)
			(effects
				(font
					(size 1 1)
					(thickness 0.15)
				)
			)
		)
		(property "Voltage" "50V"
			(at -21.2 223.6 0)
			(layer "F.Fab")
			(hide yes)
			(effects
				(font
					(size 1 1)
					(thickness 0.15)
				)
			)
		)
		(sheetname "USB3")
		(sheetfile "usb3.kicad_sch")
		(attr smd)
		(fp_rect
			(start -0.925 -0.47)
			(end 0.925 0.47)
			(stroke
				(width 0.05)
				(type default)
			)
			(fill none)
			(layer "F.CrtYd")
		)
		(fp_line
			(start -0.494 0.248)
			(end -0.494 -0.25)
			(stroke
				(width 0.15)
				(type solid)
			)
			(layer "F.Fab")
		)
		(fp_line
			(start 0.504 0.248)
			(end -0.494 0.248)
			(stroke
				(width 0.15)
				(type solid)
			)
			(layer "F.Fab")
		)
		(fp_line
			(start -0.494 -0.25)
			(end 0.504 -0.25)
			(stroke
				(width 0.15)
				(type solid)
			)
			(layer "F.Fab")
		)
		(fp_line
			(start 0.504 -0.25)
			(end 0.504 0.248)
			(stroke
				(width 0.15)
				(type solid)
			)
			(layer "F.Fab")
		)
		(fp_text user "${REFERENCE}"
			(at -0.932 3.168 -90)
			(layer "F.Fab")
			(hide yes)
			(effects
				(font
					(size 0.7 0.7)
					(thickness 0.15)
				)
				(justify left bottom)
			)
		)
		(fp_text user "License: Apache-2.0"
			(at -0.932 5.17 -90)
			(layer "F.Fab")
			(hide yes)
			(effects
				(font
					(size 0.7 0.7)
					(thickness 0.15)
				)
				(justify left bottom)
			)
		)
		(fp_text user "Author: Antmicro"
			(at -0.932 4.17 -90)
			(layer "F.Fab")
			(hide yes)
			(effects
				(font
					(size 0.7 0.7)
					(thickness 0.15)
				)
				(justify left bottom)
			)
		)
		(pad "1" smd roundrect
			(at -0.48 0 270)
			(size 0.59 0.64)
			(layers "F.Cu" "F.Paste" "F.Mask")
			(roundrect_rratio 0.25)
			(net 270 "/USB3/USBC1_VBUS")
			(pintype "passive")
		)
		(pad "2" smd roundrect
			(at 0.48 0 270)
			(size 0.59 0.64)
			(layers "F.Cu" "F.Paste" "F.Mask")
			(roundrect_rratio 0.25)
			(net 1 "GND")
			(pintype "passive")
		)
	)
	(footprint "antmicro-footprints:C_0402_1005Metric"
		(layer "F.Cu")
		(at 101.2 115.8 90)
		(descr "Capacitor SMD 0402")
		(tags "capacitor SMD 0402")
		(property "Reference" "C73"
			(at 1.05 0.45 90)
			(layer "F.SilkS")
			(effects
				(font
					(size 0.7 0.7)
					(thickness 0.15)
				)
				(justify left bottom)
			)
		)
		(property "Value" "C_100n_0402"
			(at 0 1.4 90)
			(layer "F.Fab")
			(effects
				(font
					(size 0.7 0.7)
					(thickness 0.15)
				)
				(justify left bottom)
			)
		)
		(property "Footprint" "antmicro-footprints:C_0402_1005Metric"
			(at 0 0 90)
			(layer "F.Fab")
			(hide yes)
			(effects
				(font
					(size 1.27 1.27)
					(thickness 0.15)
				)
			)
		)
		(property "Datasheet" "https://www.murata.com/products/productdetail?partno=GRM155R61H104KE14%23"
			(at 0 0 90)
			(layer "F.Fab")
			(hide yes)
			(effects
				(font
					(size 1.27 1.27)
					(thickness 0.15)
				)
			)
		)
		(property "Author" "Antmicro"
			(at 217 14.6 0)
			(layer "F.Fab")
			(hide yes)
			(effects
				(font
					(size 1 1)
					(thickness 0.15)
				)
			)
		)
		(property "Dielectric" "X5R"
			(at 217 14.6 0)
			(layer "F.Fab")
			(hide yes)
			(effects
				(font
					(size 1 1)
					(thickness 0.15)
				)
			)
		)
		(property "License" "Apache-2.0"
			(at 217 14.6 0)
			(layer "F.Fab")
			(hide yes)
			(effects
				(font
					(size 1 1)
					(thickness 0.15)
				)
			)
		)
		(property "MPN" "GRM155R61H104KE14D"
			(at 217 14.6 0)
			(layer "F.Fab")
			(hide yes)
			(effects
				(font
					(size 1 1)
					(thickness 0.15)
				)
			)
		)
		(property "Manufacturer" "Murata"
			(at 217 14.6 0)
			(layer "F.Fab")
			(hide yes)
			(effects
				(font
					(size 1 1)
					(thickness 0.15)
				)
			)
		)
		(property "Val" "100n"
			(at 217 14.6 0)
			(layer "F.Fab")
			(hide yes)
			(effects
				(font
					(size 1 1)
					(thickness 0.15)
				)
			)
		)
		(property "Voltage" "50V"
			(at 217 14.6 0)
			(layer "F.Fab")
			(hide yes)
			(effects
				(font
					(size 1 1)
					(thickness 0.15)
				)
			)
		)
		(sheetname "USB3")
		(sheetfile "usb3.kicad_sch")
		(attr smd)
		(fp_rect
			(start -0.925 -0.47)
			(end 0.925 0.47)
			(stroke
				(width 0.05)
				(type default)
			)
			(fill none)
			(layer "F.CrtYd")
		)
		(fp_line
			(start 0.504 -0.25)
			(end 0.504 0.248)
			(stroke
				(width 0.15)
				(type solid)
			)
			(layer "F.Fab")
		)
		(fp_line
			(start -0.494 -0.25)
			(end 0.504 -0.25)
			(stroke
				(width 0.15)
				(type solid)
			)
			(layer "F.Fab")
		)
		(fp_line
			(start 0.504 0.248)
			(end -0.494 0.248)
			(stroke
				(width 0.15)
				(type solid)
			)
			(layer "F.Fab")
		)
		(fp_line
			(start -0.494 0.248)
			(end -0.494 -0.25)
			(stroke
				(width 0.15)
				(type solid)
			)
			(layer "F.Fab")
		)
		(fp_text user "${REFERENCE}"
			(at -0.932 3.168 90)
			(layer "F.Fab")
			(hide yes)
			(effects
				(font
					(size 0.7 0.7)
					(thickness 0.15)
				)
				(justify left bottom)
			)
		)
		(fp_text user "Author: Antmicro"
			(at -0.932 4.17 90)
			(layer "F.Fab")
			(hide yes)
			(effects
				(font
					(size 0.7 0.7)
					(thickness 0.15)
				)
				(justify left bottom)
			)
		)
		(fp_text user "License: Apache-2.0"
			(at -0.932 5.17 90)
			(layer "F.Fab")
			(hide yes)
			(effects
				(font
					(size 0.7 0.7)
					(thickness 0.15)
				)
				(justify left bottom)
			)
		)
		(pad "1" smd roundrect
			(at -0.48 0 90)
			(size 0.59 0.64)
			(layers "F.Cu" "F.Paste" "F.Mask")
			(roundrect_rratio 0.25)
			(net 99 "+5V")
			(pintype "passive")
		)
		(pad "2" smd roundrect
			(at 0.48 0 90)
			(size 0.59 0.64)
			(layers "F.Cu" "F.Paste" "F.Mask")
			(roundrect_rratio 0.25)
			(net 1 "GND")
			(pintype "passive")
		)
	)
	(footprint "antmicro-footprints:L_Bourns-SRP6050CA"
		(layer "F.Cu")
		(at 56.875 99.485 180)
		(property "Reference" "L4"
			(at 3.34 -3.63 0)
			(layer "F.SilkS")
			(effects
				(font
					(size 0.7 0.7)
					(thickness 0.15)
				)
				(justify right bottom)
			)
		)
		(property "Value" "L_1u_20A_Bourns-SRP6050CA"
			(at -0.025 4.85 0)
			(layer "F.Fab")
			(effects
				(font
					(size 0.7 0.7)
					(thickness 0.15)
				)
				(justify right bottom)
			)
		)
		(property "Footprint" "antmicro-footprints:L_Bourns-SRP6050CA"
			(at 0 0 180)
			(layer "F.Fab")
			(hide yes)
			(effects
				(font
					(size 1.27 1.27)
					(thickness 0.15)
				)
			)
		)
		(property "Datasheet" "https://www.bourns.com/docs/Product-Datasheets/SRP6050CA.pdf"
			(at 0 0 180)
			(layer "F.Fab")
			(hide yes)
			(effects
				(font
					(size 1.27 1.27)
					(thickness 0.15)
				)
			)
		)
		(property "Author" "Antmicro"
			(at 113.75 198.97 0)
			(layer "F.Fab")
			(hide yes)
			(effects
				(font
					(size 1 1)
					(thickness 0.15)
				)
			)
		)
		(property "IMax" "20 A"
			(at 113.75 198.97 0)
			(layer "F.Fab")
			(hide yes)
			(effects
				(font
					(size 1 1)
					(thickness 0.15)
				)
			)
		)
		(property "ISat" "23 A"
			(at 113.75 198.97 0)
			(layer "F.Fab")
			(hide yes)
			(effects
				(font
					(size 1 1)
					(thickness 0.15)
				)
			)
		)
		(property "License" "Apache-2.0"
			(at 113.75 198.97 0)
			(layer "F.Fab")
			(hide yes)
			(effects
				(font
					(size 1 1)
					(thickness 0.15)
				)
			)
		)
		(property "MPN" "SRP6050CA-1R0M"
			(at 113.75 198.97 0)
			(layer "F.Fab")
			(hide yes)
			(effects
				(font
					(size 1 1)
					(thickness 0.15)
				)
			)
		)
		(property "Manufacturer" "Bourns"
			(at 113.75 198.97 0)
			(layer "F.Fab")
			(hide yes)
			(effects
				(font
					(size 1 1)
					(thickness 0.15)
				)
			)
		)
		(property "Size" "6.6x6.4"
			(at 113.75 198.97 0)
			(layer "F.Fab")
			(hide yes)
			(effects
				(font
					(size 1 1)
					(thickness 0.15)
				)
			)
		)
		(property "Val" "1u/20A"
			(at 113.75 198.97 0)
			(layer "F.Fab")
			(hide yes)
			(effects
				(font
					(size 1 1)
					(thickness 0.15)
				)
			)
		)
		(sheetname "Supply")
		(sheetfile "supply.kicad_sch")
		(attr smd)
		(fp_line
			(start 3.2 3.298)
			(end -3.2 3.298)
			(stroke
				(width 0.15)
				(type solid)
			)
			(layer "F.SilkS")
		)
		(fp_line
			(start 3.2 -3.301)
			(end 3.2 3.298)
			(stroke
				(width 0.15)
				(type solid)
			)
			(layer "F.SilkS")
		)
		(fp_line
			(start -3.2 -3.301)
			(end 3.2 -3.301)
			(stroke
				(width 0.15)
				(type solid)
			)
			(layer "F.SilkS")
		)
		(fp_line
			(start -3.2 -3.301)
			(end -3.2 3.298)
			(stroke
				(width 0.15)
				(type solid)
			)
			(layer "F.SilkS")
		)
		(fp_rect
			(start -3.45 -3.55)
			(end 3.45 3.55)
			(stroke
				(width 0.05)
				(type solid)
			)
			(fill none)
			(layer "F.CrtYd")
		)
		(fp_rect
			(start -3.202 -3.301)
			(end 3.2 3.298)
			(stroke
				(width 0.15)
				(type solid)
			)
			(fill none)
			(layer "F.Fab")
		)
		(fp_text user "License: Apache-2.0"
			(at -3.45 8.05 0)
			(layer "F.Fab")
			(hide yes)
			(effects
				(font
					(size 0.7 0.7)
					(thickness 0.15)
				)
				(justify right bottom)
			)
		)
		(fp_text user "${REFERENCE}"
			(at -3.45 6.85 0)
			(layer "F.Fab")
			(hide yes)
			(effects
				(font
					(size 0.7 0.7)
					(thickness 0.15)
				)
				(justify right bottom)
			)
		)
		(fp_text user "Author: Antmicro"
			(at -3.45 9.25 0)
			(layer "F.Fab")
			(hide yes)
			(effects
				(font
					(size 0.7 0.7)
					(thickness 0.15)
				)
				(justify right bottom)
			)
		)
		(pad "1" smd roundrect
			(at -2.025 0 180)
			(size 1.55 5.6)
			(layers "F.Cu" "F.Paste" "F.Mask")
			(roundrect_rratio 0.1)
			(net 763 "/Supply/5V_SW")
			(pintype "passive")
		)
		(pad "2" smd roundrect
			(at 2.025 0 180)
			(size 1.55 5.6)
			(layers "F.Cu" "F.Paste" "F.Mask")
			(roundrect_rratio 0.1)
			(net 761 "/Supply/5V_OUT")
			(pintype "passive")
		)
	)
	(footprint "antmicro-footprints:SOT-523"
		(layer "F.Cu")
		(at 42.109 105.185 90)
		(property "Reference" "Q17"
			(at -1.415 1.141 180)
			(layer "F.SilkS")
			(effects
				(font
					(size 0.7 0.7)
					(thickness 0.15)
				)
				(justify left bottom)
			)
		)
		(property "Value" "PJE138K"
			(at 0.1 1.824 90)
			(layer "F.Fab")
			(effects
				(font
					(size 0.7 0.7)
					(thickness 0.15)
				)
				(justify left bottom)
			)
		)
		(property "Footprint" "antmicro-footprints:SOT-523"
			(at 0 0 90)
			(layer "F.Fab")
			(hide yes)
			(effects
				(font
					(size 1.27 1.27)
					(thickness 0.15)
				)
			)
		)
		(property "Datasheet" "https://www.mouser.com/datasheet/2/1057/PJE138K-1876698.pdf"
			(at 0 0 90)
			(layer "F.Fab")
			(hide yes)
			(effects
				(font
					(size 1.27 1.27)
					(thickness 0.15)
				)
			)
		)
		(property "Author" "Antmicro"
			(at 147.294 63.076 0)
			(layer "F.Fab")
			(hide yes)
			(effects
				(font
					(size 1 1)
					(thickness 0.15)
				)
			)
		)
		(property "License" "Apache-2.0"
			(at 147.294 63.076 0)
			(layer "F.Fab")
			(hide yes)
			(effects
				(font
					(size 1 1)
					(thickness 0.15)
				)
			)
		)
		(property "MPN" "PJE138K_R1_00001"
			(at 147.294 63.076 0)
			(layer "F.Fab")
			(hide yes)
			(effects
				(font
					(size 1 1)
					(thickness 0.15)
				)
			)
		)
		(property "Manufacturer" "PANJIT"
			(at 147.294 63.076 0)
			(layer "F.Fab")
			(hide yes)
			(effects
				(font
					(size 1 1)
					(thickness 0.15)
				)
			)
		)
		(sheetname "Ethernet")
		(sheetfile "ethernet.kicad_sch")
		(attr smd)
		(fp_line
			(start -0.277 -0.551)
			(end -0.277 -0.75)
			(stroke
				(width 0.15)
				(type solid)
			)
			(layer "F.SilkS")
		)
		(fp_line
			(start -0.725 -0.551)
			(end -0.277 -0.551)
			(stroke
				(width 0.15)
				(type solid)
			)
			(layer "F.SilkS")
		)
		(fp_line
			(start -0.927 -0.351)
			(end -0.725 -0.551)
			(stroke
				(width 0.15)
				(type solid)
			)
			(layer "F.SilkS")
		)
		(fp_line
			(start -0.927 -0.051)
			(end -0.927 -0.351)
			(stroke
				(width 0.15)
				(type solid)
			)
			(layer "F.SilkS")
		)
		(fp_circle
			(center -0.9652 0.9652)
			(end -0.9152 0.9652)
			(stroke
				(width 0.15)
				(type solid)
			)
			(fill solid)
			(layer "F.SilkS")
		)
		(fp_line
			(start 1.1 -1.16)
			(end 1.1 1.15)
			(stroke
				(width 0.05)
				(type solid)
			)
			(layer "F.CrtYd")
		)
		(fp_line
			(start -1.12 -1.16)
			(end 1.1 -1.16)
			(stroke
				(width 0.05)
				(type solid)
			)
			(layer "F.CrtYd")
		)
		(fp_line
			(start -1.12 -1.16)
			(end -1.12 1.15)
			(stroke
				(width 0.05)
				(type solid)
			)
			(layer "F.CrtYd")
		)
		(fp_line
			(start -1.12 1.15)
			(end 1.1 1.15)
			(stroke
				(width 0.05)
				(type solid)
			)
			(layer "F.CrtYd")
		)
		(fp_line
			(start 0.8 -0.425)
			(end -0.652 -0.425)
			(stroke
				(width 0.15)
				(type solid)
			)
			(layer "F.Fab")
		)
		(fp_line
			(start 0.8 -0.425)
			(end 0.8 0.424)
			(stroke
				(width 0.15)
				(type solid)
			)
			(layer "F.Fab")
		)
		(fp_line
			(start -0.652 -0.425)
			(end -0.802 -0.276)
			(stroke
				(width 0.15)
				(type solid)
			)
			(layer "F.Fab")
		)
		(fp_line
			(start -0.802 -0.276)
			(end -0.802 0.424)
			(stroke
				(width 0.15)
				(type solid)
			)
			(layer "F.Fab")
		)
		(fp_line
			(start 0.8 0.424)
			(end -0.802 0.424)
			(stroke
				(width 0.15)
				(type solid)
			)
			(layer "F.Fab")
		)
		(fp_circle
			(center -0.9652 0.9652)
			(end -0.9144 0.9652)
			(stroke
				(width 0.15)
				(type solid)
			)
			(fill none)
			(layer "F.Fab")
		)
		(fp_text user "License: Apache-2.0"
			(at -1.12 5.024 90)
			(layer "F.Fab")
			(hide yes)
			(effects
				(font
					(size 0.7 0.7)
					(thickness 0.15)
				)
				(justify left bottom)
			)
		)
		(fp_text user "${REFERENCE}"
			(at -1.12 3.824 90)
			(layer "F.Fab")
			(hide yes)
			(effects
				(font
					(size 0.7 0.7)
					(thickness 0.15)
				)
				(justify left bottom)
			)
		)
		(fp_text user "Author: Antmicro"
			(at -1.12 6.224 90)
			(layer "F.Fab")
			(hide yes)
			(effects
				(font
					(size 0.7 0.7)
					(thickness 0.15)
				)
				(justify left bottom)
			)
		)
		(pad "1" smd rect
			(at -0.5 0.65 90)
			(size 0.4 0.51)
			(layers "F.Cu" "F.Paste" "F.Mask")
			(net 127 "/Ethernet/POE_ACTIVE")
			(pinfunction "G")
			(pintype "passive")
		)
		(pad "2" smd rect
			(at 0.498 0.65 90)
			(size 0.4 0.51)
			(layers "F.Cu" "F.Paste" "F.Mask")
			(net 106 "GNDD")
			(pinfunction "S")
			(pintype "passive")
		)
		(pad "3" smd rect
			(at 0 -0.652 90)
			(size 0.4 0.51)
			(layers "F.Cu" "F.Paste" "F.Mask")
			(net 650 "/Ethernet/ULS-12_CTRL")
			(pinfunction "D")
			(pintype "passive")
		)
	)
	(footprint "antmicro-footprints:R_Array_4x0402"
		(layer "F.Cu")
		(at 137.4 94.71 90)
		(property "Reference" "R26"
			(at -0.99 -0.9 90)
			(layer "F.SilkS")
			(effects
				(font
					(size 0.7 0.7)
					(thickness 0.15)
				)
				(justify left bottom)
			)
		)
		(property "Value" "R_4x330R_0402_array"
			(at -1.5 2 90)
			(layer "F.Fab")
			(effects
				(font
					(size 0.7 0.7)
					(thickness 0.15)
				)
				(justify left bottom)
			)
		)
		(property "Footprint" "antmicro-footprints:R_Array_4x0402"
			(at 0 0 90)
			(layer "F.Fab")
			(hide yes)
			(effects
				(font
					(size 1.27 1.27)
					(thickness 0.15)
				)
			)
		)
		(property "Datasheet" "http://industrial.panasonic.com/cdbs/www-data/pdf/AOC0000/AOC0000C14.pdf"
			(at 0 0 90)
			(layer "F.Fab")
			(hide yes)
			(effects
				(font
					(size 1.27 1.27)
					(thickness 0.15)
				)
			)
		)
		(property "Author" "Antmicro"
			(at 232.11 -42.69 0)
			(layer "F.Fab")
			(hide yes)
			(effects
				(font
					(size 1 1)
					(thickness 0.15)
				)
			)
		)
		(property "License" "Apache-2.0"
			(at 232.11 -42.69 0)
			(layer "F.Fab")
			(hide yes)
			(effects
				(font
					(size 1 1)
					(thickness 0.15)
				)
			)
		)
		(property "MPN" "EXB-28V331JX"
			(at 232.11 -42.69 0)
			(layer "F.Fab")
			(hide yes)
			(effects
				(font
					(size 1 1)
					(thickness 0.15)
				)
			)
		)
		(property "Manufacturer" "Panasonic"
			(at 232.11 -42.69 0)
			(layer "F.Fab")
			(hide yes)
			(effects
				(font
					(size 1 1)
					(thickness 0.15)
				)
			)
		)
		(property "Val" "R_4x330R_0402"
			(at 232.11 -42.69 0)
			(layer "F.Fab")
			(hide yes)
			(effects
				(font
					(size 1 1)
					(thickness 0.15)
				)
			)
		)
		(sheetname "Peripherals")
		(sheetfile "peripherals.kicad_sch")
		(attr smd)
		(fp_line
			(start -1.17 -0.5)
			(end -1.17 0.498)
			(stroke
				(width 0.15)
				(type solid)
			)
			(layer "F.SilkS")
		)
		(fp_line
			(start 1.167 0.498)
			(end 1.167 -0.5)
			(stroke
				(width 0.15)
				(type solid)
			)
			(layer "F.SilkS")
		)
		(fp_rect
			(start -1.2 -0.9)
			(end 1.2 0.9)
			(stroke
				(width 0.05)
				(type solid)
			)
			(fill none)
			(layer "F.CrtYd")
		)
		(fp_line
			(start 0.998 -0.5)
			(end 0.998 0.498)
			(stroke
				(width 0.15)
				(type solid)
			)
			(layer "F.Fab")
		)
		(fp_line
			(start -1 -0.5)
			(end 0.998 -0.5)
			(stroke
				(width 0.15)
				(type solid)
			)
			(layer "F.Fab")
		)
		(fp_line
			(start 0.998 0.498)
			(end -1 0.498)
			(stroke
				(width 0.15)
				(type solid)
			)
			(layer "F.Fab")
		)
		(fp_line
			(start -1 0.498)
			(end -1 -0.5)
			(stroke
				(width 0.15)
				(type solid)
			)
			(layer "F.Fab")
		)
		(fp_text user "License: Apache-2.0"
			(at -1.5 5.75 90)
			(layer "F.Fab")
			(hide yes)
			(effects
				(font
					(size 0.7 0.7)
					(thickness 0.15)
				)
				(justify left bottom)
			)
		)
		(fp_text user "Author: Antmicro"
			(at -1.5 4.5 90)
			(layer "F.Fab")
			(hide yes)
			(effects
				(font
					(size 0.7 0.7)
					(thickness 0.15)
				)
				(justify left bottom)
			)
		)
		(fp_text user "${REFERENCE}"
			(at -1.5 3.25 90)
			(layer "F.Fab")
			(hide yes)
			(effects
				(font
					(size 0.7 0.7)
					(thickness 0.15)
				)
				(justify left bottom)
			)
		)
		(pad "1" smd roundrect
			(at -0.802 0.45 90)
			(size 0.4 0.5)
			(layers "F.Cu" "F.Paste" "F.Mask")
			(roundrect_rratio 0.25)
			(net 515 "/Peripherals/GPIO07_CONN")
			(pinfunction "R1.1")
			(pintype "passive")
		)
		(pad "2" smd roundrect
			(at -0.272 0.45 90)
			(size 0.4 0.5)
			(layers "F.Cu" "F.Paste" "F.Mask")
			(roundrect_rratio 0.25)
			(net 348 "/Peripherals/GPIO01_CONN")
			(pinfunction "R2.1")
			(pintype "passive")
		)
		(pad "3" smd roundrect
			(at 0.27 0.45 90)
			(size 0.4 0.5)
			(layers "F.Cu" "F.Paste" "F.Mask")
			(roundrect_rratio 0.25)
			(net 346 "/Peripherals/PCIE2_CLKREQ_CONN*")
			(pinfunction "R3.1")
			(pintype "passive")
		)
		(pad "4" smd roundrect
			(at 0.8 0.45 90)
			(size 0.4 0.5)
			(layers "F.Cu" "F.Paste" "F.Mask")
			(roundrect_rratio 0.25)
			(net 345 "/Peripherals/PCIE2_RST_CONN*")
			(pinfunction "R4.1")
			(pintype "passive")
		)
		(pad "5" smd roundrect
			(at 0.8 -0.452 90)
			(size 0.4 0.5)
			(layers "F.Cu" "F.Paste" "F.Mask")
			(roundrect_rratio 0.25)
			(net 103 "PCIE2_RST*")
			(pinfunction "R4.2")
			(pintype "passive")
		)
		(pad "6" smd roundrect
			(at 0.27 -0.452 90)
			(size 0.4 0.5)
			(layers "F.Cu" "F.Paste" "F.Mask")
			(roundrect_rratio 0.25)
			(net 104 "PCIE2_CLKREQ*")
			(pinfunction "R3.2")
			(pintype "passive")
		)
		(pad "7" smd roundrect
			(at -0.272 -0.452 90)
			(size 0.4 0.5)
			(layers "F.Cu" "F.Paste" "F.Mask")
			(roundrect_rratio 0.25)
			(net 43 "GPIO01")
			(pinfunction "R2.2")
			(pintype "passive")
		)
		(pad "8" smd roundrect
			(at -0.802 -0.452 90)
			(size 0.4 0.5)
			(layers "F.Cu" "F.Paste" "F.Mask")
			(roundrect_rratio 0.25)
			(net 102 "GPIO07")
			(pinfunction "R1.2")
			(pintype "passive")
		)
	)
	(footprint "antmicro-footprints:SOT-523"
		(layer "F.Cu")
		(at 87.5 100.2 -90)
		(property "Reference" "Q2"
			(at -1.23 0.72 0)
			(layer "F.SilkS")
			(effects
				(font
					(size 0.7 0.7)
					(thickness 0.15)
				)
				(justify left bottom)
			)
		)
		(property "Value" "PJE138K"
			(at 0.1 1.824 -90)
			(layer "F.Fab")
			(effects
				(font
					(size 0.7 0.7)
					(thickness 0.15)
				)
				(justify left bottom)
			)
		)
		(property "Footprint" "antmicro-footprints:SOT-523"
			(at 0 0 -90)
			(layer "F.Fab")
			(hide yes)
			(effects
				(font
					(size 1.27 1.27)
					(thickness 0.15)
				)
			)
		)
		(property "Datasheet" "https://www.mouser.com/datasheet/2/1057/PJE138K-1876698.pdf"
			(at 0 0 -90)
			(layer "F.Fab")
			(hide yes)
			(effects
				(font
					(size 1.27 1.27)
					(thickness 0.15)
				)
			)
		)
		(property "Author" "Antmicro"
			(at -12.7 187.7 0)
			(layer "F.Fab")
			(hide yes)
			(effects
				(font
					(size 1 1)
					(thickness 0.15)
				)
			)
		)
		(property "License" "Apache-2.0"
			(at -12.7 187.7 0)
			(layer "F.Fab")
			(hide yes)
			(effects
				(font
					(size 1 1)
					(thickness 0.15)
				)
			)
		)
		(property "MPN" "PJE138K_R1_00001"
			(at -12.7 187.7 0)
			(layer "F.Fab")
			(hide yes)
			(effects
				(font
					(size 1 1)
					(thickness 0.15)
				)
			)
		)
		(property "Manufacturer" "PANJIT"
			(at -12.7 187.7 0)
			(layer "F.Fab")
			(hide yes)
			(effects
				(font
					(size 1 1)
					(thickness 0.15)
				)
			)
		)
		(sheetname "HDMI")
		(sheetfile "hdmi.kicad_sch")
		(attr smd)
		(fp_line
			(start -0.927 -0.051)
			(end -0.927 -0.351)
			(stroke
				(width 0.15)
				(type solid)
			)
			(layer "F.SilkS")
		)
		(fp_line
			(start -0.927 -0.351)
			(end -0.725 -0.551)
			(stroke
				(width 0.15)
				(type solid)
			)
			(layer "F.SilkS")
		)
		(fp_line
			(start -0.725 -0.551)
			(end -0.277 -0.551)
			(stroke
				(width 0.15)
				(type solid)
			)
			(layer "F.SilkS")
		)
		(fp_line
			(start -0.277 -0.551)
			(end -0.277 -0.75)
			(stroke
				(width 0.15)
				(type solid)
			)
			(layer "F.SilkS")
		)
		(fp_circle
			(center -0.9652 0.9652)
			(end -0.9152 0.9652)
			(stroke
				(width 0.15)
				(type solid)
			)
			(fill solid)
			(layer "F.SilkS")
		)
		(fp_line
			(start -1.12 1.15)
			(end 1.1 1.15)
			(stroke
				(width 0.05)
				(type solid)
			)
			(layer "F.CrtYd")
		)
		(fp_line
			(start -1.12 -1.16)
			(end -1.12 1.15)
			(stroke
				(width 0.05)
				(type solid)
			)
			(layer "F.CrtYd")
		)
		(fp_line
			(start -1.12 -1.16)
			(end 1.1 -1.16)
			(stroke
				(width 0.05)
				(type solid)
			)
			(layer "F.CrtYd")
		)
		(fp_line
			(start 1.1 -1.16)
			(end 1.1 1.15)
			(stroke
				(width 0.05)
				(type solid)
			)
			(layer "F.CrtYd")
		)
		(fp_line
			(start 0.8 0.424)
			(end -0.802 0.424)
			(stroke
				(width 0.15)
				(type solid)
			)
			(layer "F.Fab")
		)
		(fp_line
			(start -0.802 -0.276)
			(end -0.802 0.424)
			(stroke
				(width 0.15)
				(type solid)
			)
			(layer "F.Fab")
		)
		(fp_line
			(start -0.652 -0.425)
			(end -0.802 -0.276)
			(stroke
				(width 0.15)
				(type solid)
			)
			(layer "F.Fab")
		)
		(fp_line
			(start 0.8 -0.425)
			(end 0.8 0.424)
			(stroke
				(width 0.15)
				(type solid)
			)
			(layer "F.Fab")
		)
		(fp_line
			(start 0.8 -0.425)
			(end -0.652 -0.425)
			(stroke
				(width 0.15)
				(type solid)
			)
			(layer "F.Fab")
		)
		(fp_circle
			(center -0.9652 0.9652)
			(end -0.9144 0.9652)
			(stroke
				(width 0.15)
				(type solid)
			)
			(fill none)
			(layer "F.Fab")
		)
		(fp_text user "Author: Antmicro"
			(at -1.12 6.224 -90)
			(layer "F.Fab")
			(hide yes)
			(effects
				(font
					(size 0.7 0.7)
					(thickness 0.15)
				)
				(justify left bottom)
			)
		)
		(fp_text user "${REFERENCE}"
			(at -1.12 3.824 -90)
			(layer "F.Fab")
			(hide yes)
			(effects
				(font
					(size 0.7 0.7)
					(thickness 0.15)
				)
				(justify left bottom)
			)
		)
		(fp_text user "License: Apache-2.0"
			(at -1.12 5.024 -90)
			(layer "F.Fab")
			(hide yes)
			(effects
				(font
					(size 0.7 0.7)
					(thickness 0.15)
				)
				(justify left bottom)
			)
		)
		(pad "1" smd rect
			(at -0.5 0.65 270)
			(size 0.4 0.51)
			(layers "F.Cu" "F.Paste" "F.Mask")
			(net 87 "+3V3")
			(pinfunction "G")
			(pintype "passive")
		)
		(pad "2" smd rect
			(at 0.498 0.65 270)
			(size 0.4 0.51)
			(layers "F.Cu" "F.Paste" "F.Mask")
			(net 1 "GND")
			(pinfunction "S")
			(pintype "passive")
		)
		(pad "3" smd rect
			(at 0 -0.652 270)
			(size 0.4 0.51)
			(layers "F.Cu" "F.Paste" "F.Mask")
			(net 623 "Net-(Q2-D)")
			(pinfunction "D")
			(pintype "passive")
		)
	)
	(footprint "antmicro-footprints:R_0402_1005Metric"
		(layer "F.Cu")
		(at 109.8 102.65 -90)
		(descr "Resistor SMD 0402")
		(tags "resistor SMD 0402")
		(property "Reference" "R125"
			(at -0.82 -0.07 -90)
			(layer "F.SilkS")
			(effects
				(font
					(size 0.7 0.7)
					(thickness 0.15)
				)
				(justify left bottom)
			)
		)
		(property "Value" "R_0R_0402"
			(at 0 1.4 -90)
			(layer "F.Fab")
			(effects
				(font
					(size 0.7 0.7)
					(thickness 0.15)
				)
				(justify left bottom)
			)
		)
		(property "Footprint" "antmicro-footprints:R_0402_1005Metric"
			(at 0 0 -90)
			(layer "F.Fab")
			(hide yes)
			(effects
				(font
					(size 1.27 1.27)
					(thickness 0.15)
				)
			)
		)
		(property "Datasheet" "https://industrial.panasonic.com/cdbs/www-data/pdf/RDA0000/AOA0000C301.pdf"
			(at 0 0 -90)
			(layer "F.Fab")
			(hide yes)
			(effects
				(font
					(size 1.27 1.27)
					(thickness 0.15)
				)
			)
		)
		(property "Author" "Antmicro"
			(at 7.15 212.45 0)
			(layer "F.Fab")
			(hide yes)
			(effects
				(font
					(size 1 1)
					(thickness 0.15)
				)
			)
		)
		(property "Current" "1A"
			(at 7.15 212.45 0)
			(layer "F.Fab")
			(hide yes)
			(effects
				(font
					(size 1 1)
					(thickness 0.15)
				)
			)
		)
		(property "License" "Apache-2.0"
			(at 7.15 212.45 0)
			(layer "F.Fab")
			(hide yes)
			(effects
				(font
					(size 1 1)
					(thickness 0.15)
				)
			)
		)
		(property "MPN" "ERJ2GE0R00X"
			(at 7.15 212.45 0)
			(layer "F.Fab")
			(hide yes)
			(effects
				(font
					(size 1 1)
					(thickness 0.15)
				)
			)
		)
		(property "Manufacturer" "Panasonic"
			(at 7.15 212.45 0)
			(layer "F.Fab")
			(hide yes)
			(effects
				(font
					(size 1 1)
					(thickness 0.15)
				)
			)
		)
		(property "Tolerance" ""
			(at 7.15 212.45 0)
			(layer "F.Fab")
			(hide yes)
			(effects
				(font
					(size 1 1)
					(thickness 0.15)
				)
			)
		)
		(property "Val" "0R"
			(at 7.15 212.45 0)
			(layer "F.Fab")
			(hide yes)
			(effects
				(font
					(size 1 1)
					(thickness 0.15)
				)
			)
		)
		(sheetname "USB3")
		(sheetfile "usb3.kicad_sch")
		(attr smd exclude_from_pos_files exclude_from_bom dnp)
		(fp_rect
			(start -0.925 -0.47)
			(end 0.925 0.47)
			(stroke
				(width 0.05)
				(type default)
			)
			(fill none)
			(layer "F.CrtYd")
		)
		(fp_rect
			(start -0.5 -0.25)
			(end 0.5 0.25)
			(stroke
				(width 0.15)
				(type solid)
			)
			(fill none)
			(layer "F.Fab")
		)
		(fp_text user "${REFERENCE}"
			(at -0.95 3.168 -90)
			(layer "F.Fab")
			(hide yes)
			(effects
				(font
					(size 0.7 0.7)
					(thickness 0.15)
				)
				(justify left bottom)
			)
		)
		(fp_text user "License: Apache-2.0"
			(at -0.95 5.169 -90)
			(layer "F.Fab")
			(hide yes)
			(effects
				(font
					(size 0.7 0.7)
					(thickness 0.15)
				)
				(justify left bottom)
			)
		)
		(fp_text user "Author: Antmicro"
			(at -0.95 4.169 -90)
			(layer "F.Fab")
			(hide yes)
			(effects
				(font
					(size 0.7 0.7)
					(thickness 0.15)
				)
				(justify left bottom)
			)
		)
		(pad "1" smd roundrect
			(at -0.48 0 270)
			(size 0.59 0.64)
			(layers "F.Cu" "F.Paste" "F.Mask")
			(roundrect_rratio 0.25)
			(net 252 "SYS_SCL")
			(pintype "passive")
		)
		(pad "2" smd roundrect
			(at 0.48 0 270)
			(size 0.59 0.64)
			(layers "F.Cu" "F.Paste" "F.Mask")
			(roundrect_rratio 0.25)
			(net 363 "/USB3/USBC1_ISC_SCL")
			(pintype "passive")
		)
	)
	(footprint "antmicro-footprints:R_0402_1005Metric"
		(layer "F.Cu")
		(at 75.42 84.34)
		(descr "Resistor SMD 0402")
		(tags "resistor SMD 0402")
		(property "Reference" "R173"
			(at -2.12 -2.3 0)
			(layer "F.SilkS")
			(effects
				(font
					(size 0.7 0.7)
					(thickness 0.15)
				)
				(justify left bottom)
			)
		)
		(property "Value" "R_499k_0402"
			(at -1.011843 1.772047 0)
			(layer "F.Fab")
			(effects
				(font
					(size 0.7 0.7)
					(thickness 0.15)
				)
				(justify left bottom)
			)
		)
		(property "Footprint" "antmicro-footprints:R_0402_1005Metric"
			(at 0 0 0)
			(layer "F.Fab")
			(hide yes)
			(effects
				(font
					(size 1.27 1.27)
					(thickness 0.15)
				)
			)
		)
		(property "Datasheet" "https://www.mouser.com/datasheet/2/54/cr-1858361.pdf"
			(at 0 0 0)
			(layer "F.Fab")
			(hide yes)
			(effects
				(font
					(size 1.27 1.27)
					(thickness 0.15)
				)
			)
		)
		(property "Author" "Antmicro"
			(at 0 0 0)
			(layer "F.Fab")
			(hide yes)
			(effects
				(font
					(size 1 1)
					(thickness 0.15)
				)
			)
		)
		(property "License" "Apache-2.0"
			(at 0 0 0)
			(layer "F.Fab")
			(hide yes)
			(effects
				(font
					(size 1 1)
					(thickness 0.15)
				)
			)
		)
		(property "MPN" "CR0402-FX-4993GLF"
			(at 0 0 0)
			(layer "F.Fab")
			(hide yes)
			(effects
				(font
					(size 1 1)
					(thickness 0.15)
				)
			)
		)
		(property "Manufacturer" "Bourns"
			(at 0 0 0)
			(layer "F.Fab")
			(hide yes)
			(effects
				(font
					(size 1 1)
					(thickness 0.15)
				)
			)
		)
		(property "Tolerance" "1%"
			(at 0 0 0)
			(layer "F.Fab")
			(hide yes)
			(effects
				(font
					(size 1 1)
					(thickness 0.15)
				)
			)
		)
		(property "Val" "499k"
			(at 0 0 0)
			(layer "F.Fab")
			(hide yes)
			(effects
				(font
					(size 1 1)
					(thickness 0.15)
				)
			)
		)
		(sheetname "Supply")
		(sheetfile "supply.kicad_sch")
		(attr smd)
		(fp_rect
			(start -0.925 -0.47)
			(end 0.925 0.47)
			(stroke
				(width 0.05)
				(type default)
			)
			(fill none)
			(layer "F.CrtYd")
		)
		(fp_rect
			(start -0.5 -0.25)
			(end 0.5 0.25)
			(stroke
				(width 0.15)
				(type solid)
			)
			(fill none)
			(layer "F.Fab")
		)
		(fp_text user "Author: Antmicro"
			(at -0.95 4.169 0)
			(layer "F.Fab")
			(hide yes)
			(effects
				(font
					(size 0.7 0.7)
					(thickness 0.15)
				)
				(justify left bottom)
			)
		)
		(fp_text user "${REFERENCE}"
			(at -0.95 3.168 0)
			(layer "F.Fab")
			(hide yes)
			(effects
				(font
					(size 0.7 0.7)
					(thickness 0.15)
				)
				(justify left bottom)
			)
		)
		(fp_text user "License: Apache-2.0"
			(at -0.95 5.169 0)
			(layer "F.Fab")
			(hide yes)
			(effects
				(font
					(size 0.7 0.7)
					(thickness 0.15)
				)
				(justify left bottom)
			)
		)
		(pad "1" smd roundrect
			(at -0.48 0)
			(size 0.59 0.64)
			(layers "F.Cu" "F.Paste" "F.Mask")
			(roundrect_rratio 0.25)
			(net 1 "GND")
			(pintype "passive")
		)
		(pad "2" smd roundrect
			(at 0.48 0)
			(size 0.59 0.64)
			(layers "F.Cu" "F.Paste" "F.Mask")
			(roundrect_rratio 0.25)
			(net 684 "/Supply/3V3_MODE2")
			(pintype "passive")
		)
	)
	(footprint "antmicro-footprints:C_0805_2012Metric"
		(layer "F.Cu")
		(at 62.68 92.95)
		(descr "Capacitor SMD 0805")
		(tags "capacitor SMD 0805")
		(property "Reference" "C152"
			(at 25.62 1.05 0)
			(layer "F.SilkS")
			(effects
				(font
					(size 0.7 0.7)
					(thickness 0.15)
				)
				(justify left bottom)
			)
		)
		(property "Value" "C_22u_25V_0805"
			(at -2.055717 1.963152 0)
			(layer "F.Fab")
			(effects
				(font
					(size 0.7 0.7)
					(thickness 0.15)
				)
				(justify left bottom)
			)
		)
		(property "Footprint" "antmicro-footprints:C_0805_2012Metric"
			(at 0 0 0)
			(layer "F.Fab")
			(hide yes)
			(effects
				(font
					(size 1.27 1.27)
					(thickness 0.15)
				)
			)
		)
		(property "Datasheet" "https://product.samsungsem.com/mlcc/CL21A226MAYNNN.do"
			(at 0 0 0)
			(layer "F.Fab")
			(hide yes)
			(effects
				(font
					(size 1.27 1.27)
					(thickness 0.15)
				)
			)
		)
		(property "Author" "Antmicro"
			(at 0 0 0)
			(layer "F.Fab")
			(hide yes)
			(effects
				(font
					(size 1 1)
					(thickness 0.15)
				)
			)
		)
		(property "Dielectric" "X5R"
			(at 0 0 0)
			(layer "F.Fab")
			(hide yes)
			(effects
				(font
					(size 1 1)
					(thickness 0.15)
				)
			)
		)
		(property "License" "Apache-2.0"
			(at 0 0 0)
			(layer "F.Fab")
			(hide yes)
			(effects
				(font
					(size 1 1)
					(thickness 0.15)
				)
			)
		)
		(property "MPN" "CL21A226MAYNNNE"
			(at 0 0 0)
			(layer "F.Fab")
			(hide yes)
			(effects
				(font
					(size 1 1)
					(thickness 0.15)
				)
			)
		)
		(property "Manufacturer" "Samsung Electro-Mechanics"
			(at 0 0 0)
			(layer "F.Fab")
			(hide yes)
			(effects
				(font
					(size 1 1)
					(thickness 0.15)
				)
			)
		)
		(property "Public" "False"
			(at 0 0 0)
			(layer "F.Fab")
			(hide yes)
			(effects
				(font
					(size 1 1)
					(thickness 0.15)
				)
			)
		)
		(property "Val" "22u"
			(at 0 0 0)
			(layer "F.Fab")
			(hide yes)
			(effects
				(font
					(size 1 1)
					(thickness 0.15)
				)
			)
		)
		(property "Voltage" "25V"
			(at 0 0 0)
			(layer "F.Fab")
			(hide yes)
			(effects
				(font
					(size 1 1)
					(thickness 0.15)
				)
			)
		)
		(sheetname "Supply")
		(sheetfile "supply.kicad_sch")
		(attr smd)
		(fp_line
			(start -0.3 -0.7)
			(end 0.3 -0.7)
			(stroke
				(width 0.15)
				(type solid)
			)
			(layer "F.SilkS")
		)
		(fp_line
			(start -0.3 0.7)
			(end 0.3 0.7)
			(stroke
				(width 0.15)
				(type solid)
			)
			(layer "F.SilkS")
		)
		(fp_rect
			(start 1.95 -0.9)
			(end -1.95 0.9)
			(stroke
				(width 0.05)
				(type default)
			)
			(fill none)
			(layer "F.CrtYd")
		)
		(fp_rect
			(start -0.95 -0.675)
			(end 0.95 0.675)
			(stroke
				(width 0.15)
				(type solid)
			)
			(fill none)
			(layer "F.Fab")
		)
		(fp_text user "License: Apache-2.0"
			(at -1.9 4.947 0)
			(layer "F.Fab")
			(hide yes)
			(effects
				(font
					(size 0.7 0.7)
					(thickness 0.15)
				)
				(justify left bottom)
			)
		)
		(fp_text user "Author: Antmicro"
			(at -1.9 5.947 0)
			(layer "F.Fab")
			(hide yes)
			(effects
				(font
					(size 0.7 0.7)
					(thickness 0.15)
				)
				(justify left bottom)
			)
		)
		(fp_text user "${REFERENCE}"
			(at -1.9 3.947 0)
			(layer "F.Fab")
			(hide yes)
			(effects
				(font
					(size 0.7 0.7)
					(thickness 0.15)
				)
				(justify left bottom)
			)
		)
		(pad "1" smd roundrect
			(at -1.1 0)
			(size 1.2 1.3)
			(layers "F.Cu" "F.Paste" "F.Mask")
			(roundrect_rratio 0.25)
			(net 1 "GND")
			(pintype "passive")
		)
		(pad "2" smd roundrect
			(at 1.1 0)
			(size 1.2 1.3)
			(layers "F.Cu" "F.Paste" "F.Mask")
			(roundrect_rratio 0.25)
			(net 115 "VCC")
			(pintype "passive")
		)
	)
	(footprint "antmicro-footprints:USON-10_2.5x1mm_P0.5mm"
		(layer "F.Cu")
		(at 90.6 119.9 90)
		(descr "USON-10 2.5x1mm_ Pitch 0.5mm")
		(tags "USON-10 2.5x1mm Pitch 0.5mm")
		(property "Reference" "U46"
			(at 0.76 -1.05 0)
			(layer "F.SilkS")
			(effects
				(font
					(size 0.7 0.7)
					(thickness 0.15)
				)
				(justify left bottom)
			)
		)
		(property "Value" "TPD4E05U06QDQARQ1"
			(at 0.018 2.499 90)
			(layer "F.Fab")
			(effects
				(font
					(size 0.7 0.7)
					(thickness 0.15)
				)
				(justify left bottom)
			)
		)
		(property "Footprint" "antmicro-footprints:USON-10_2.5x1mm_P0.5mm"
			(at 0 0 90)
			(layer "F.Fab")
			(hide yes)
			(effects
				(font
					(size 1.27 1.27)
					(thickness 0.15)
				)
			)
		)
		(property "Datasheet" "https://www.ti.com/lit/ds/symlink/tpd4e05u06-q1.pdf?HQS=dis-mous-null-mousermode-dsf-pf-null-wwe&ts=1663591265741&ref_url=https%253A%252F%252Fwww.mouser.com%252F"
			(at 0 0 90)
			(layer "F.Fab")
			(hide yes)
			(effects
				(font
					(size 1.27 1.27)
					(thickness 0.15)
				)
			)
		)
		(property "Author" "Antmicro"
			(at 210.5 29.3 0)
			(layer "F.Fab")
			(hide yes)
			(effects
				(font
					(size 1 1)
					(thickness 0.15)
				)
			)
		)
		(property "License" "Apache-2.0"
			(at 210.5 29.3 0)
			(layer "F.Fab")
			(hide yes)
			(effects
				(font
					(size 1 1)
					(thickness 0.15)
				)
			)
		)
		(property "MPN" "TPD4E05U06QDQARQ1"
			(at 210.5 29.3 0)
			(layer "F.Fab")
			(hide yes)
			(effects
				(font
					(size 1 1)
					(thickness 0.15)
				)
			)
		)
		(property "Manufacturer" "Texas Instruments"
			(at 210.5 29.3 0)
			(layer "F.Fab")
			(hide yes)
			(effects
				(font
					(size 1 1)
					(thickness 0.15)
				)
			)
		)
		(sheetname "HDMI")
		(sheetfile "hdmi.kicad_sch")
		(attr smd)
		(fp_line
			(start 0.498 -1.401)
			(end -0.5 -1.401)
			(stroke
				(width 0.15)
				(type solid)
			)
			(layer "F.SilkS")
		)
		(fp_line
			(start 0.498 1.398)
			(end -0.5 1.398)
			(stroke
				(width 0.15)
				(type solid)
			)
			(layer "F.SilkS")
		)
		(fp_circle
			(center -0.68 -1.27)
			(end -0.63 -1.27)
			(stroke
				(width 0.15)
				(type solid)
			)
			(fill solid)
			(layer "F.SilkS")
		)
		(fp_rect
			(start -0.8 -1.5)
			(end 0.8 1.499)
			(stroke
				(width 0.05)
				(type solid)
			)
			(fill none)
			(layer "F.CrtYd")
		)
		(fp_line
			(start 0.498 -1.25)
			(end -0.25 -1.25)
			(stroke
				(width 0.15)
				(type solid)
			)
			(layer "F.Fab")
		)
		(fp_line
			(start 0.498 -1.25)
			(end 0.498 1.249)
			(stroke
				(width 0.15)
				(type solid)
			)
			(layer "F.Fab")
		)
		(fp_line
			(start -0.25 -1.25)
			(end -0.5 -1)
			(stroke
				(width 0.15)
				(type solid)
			)
			(layer "F.Fab")
		)
		(fp_line
			(start -0.5 -1)
			(end -0.5 1.249)
			(stroke
				(width 0.15)
				(type solid)
			)
			(layer "F.Fab")
		)
		(fp_line
			(start -0.5 1.249)
			(end 0.498 1.249)
			(stroke
				(width 0.15)
				(type solid)
			)
			(layer "F.Fab")
		)
		(fp_text user "License: Apache-2.0"
			(at -0.802 6.9 90)
			(layer "F.Fab")
			(hide yes)
			(effects
				(font
					(size 0.7 0.7)
					(thickness 0.15)
				)
				(justify left bottom)
			)
		)
		(fp_text user "Author: Antmicro"
			(at -0.802 5.7 90)
			(layer "F.Fab")
			(hide yes)
			(effects
				(font
					(size 0.7 0.7)
					(thickness 0.15)
				)
				(justify left bottom)
			)
		)
		(fp_text user "${REFERENCE}"
			(at -0.802 4.498 90)
			(layer "F.Fab")
			(hide yes)
			(effects
				(font
					(size 0.7 0.7)
					(thickness 0.15)
				)
				(justify left bottom)
			)
		)
		(pad "1" smd roundrect
			(at -0.387 -1)
			(size 0.25 0.55)
			(layers "F.Cu" "F.Paste" "F.Mask")
			(roundrect_rratio 0.25)
			(net 529 "/HDMI/HDMI_HPD_5V")
			(pintype "passive")
		)
		(pad "2" smd roundrect
			(at -0.387 -0.5)
			(size 0.25 0.55)
			(layers "F.Cu" "F.Paste" "F.Mask")
			(roundrect_rratio 0.25)
			(net 518 "/HDMI/HDMI_SDA_5V")
			(pintype "passive")
		)
		(pad "3" smd roundrect
			(at -0.387 0)
			(size 0.4 0.55)
			(layers "F.Cu" "F.Paste" "F.Mask")
			(roundrect_rratio 0.25)
			(net 1 "GND")
			(pintype "power_in")
		)
		(pad "4" smd roundrect
			(at -0.387 0.498)
			(size 0.25 0.55)
			(layers "F.Cu" "F.Paste" "F.Mask")
			(roundrect_rratio 0.25)
			(net 519 "/HDMI/HDMI_SCL_5V")
			(pintype "passive")
		)
		(pad "5" smd roundrect
			(at -0.387 0.998)
			(size 0.25 0.55)
			(layers "F.Cu" "F.Paste" "F.Mask")
			(roundrect_rratio 0.25)
			(net 520 "/HDMI/HDMI_CEC_5V")
			(pintype "passive")
		)
		(pad "6" smd roundrect
			(at 0.385 0.998)
			(size 0.25 0.55)
			(layers "F.Cu" "F.Paste" "F.Mask")
			(roundrect_rratio 0.25)
			(net 520 "/HDMI/HDMI_CEC_5V")
			(pintype "passive")
		)
		(pad "7" smd roundrect
			(at 0.385 0.498)
			(size 0.25 0.55)
			(layers "F.Cu" "F.Paste" "F.Mask")
			(roundrect_rratio 0.25)
			(net 519 "/HDMI/HDMI_SCL_5V")
			(pintype "passive")
		)
		(pad "8" smd roundrect
			(at 0.385 0)
			(size 0.4 0.55)
			(layers "F.Cu" "F.Paste" "F.Mask")
			(roundrect_rratio 0.25)
			(net 1 "GND")
			(pintype "passive")
		)
		(pad "9" smd roundrect
			(at 0.385 -0.5)
			(size 0.25 0.55)
			(layers "F.Cu" "F.Paste" "F.Mask")
			(roundrect_rratio 0.25)
			(net 518 "/HDMI/HDMI_SDA_5V")
			(pintype "passive")
		)
		(pad "10" smd roundrect
			(at 0.385 -1)
			(size 0.25 0.55)
			(layers "F.Cu" "F.Paste" "F.Mask")
			(roundrect_rratio 0.25)
			(net 529 "/HDMI/HDMI_HPD_5V")
			(pintype "passive")
		)
	)
	(footprint "antmicro-footprints:R_0402_1005Metric"
		(layer "F.Cu")
		(at 139.1 107.6)
		(descr "Resistor SMD 0402")
		(tags "resistor SMD 0402")
		(property "Reference" "R55"
			(at -3.075 0.1 180)
			(layer "F.SilkS")
			(effects
				(font
					(size 0.7 0.7)
					(thickness 0.15)
				)
				(justify left bottom)
			)
		)
		(property "Value" "R_0R_0402"
			(at 0 1.4 0)
			(layer "F.Fab")
			(effects
				(font
					(size 0.7 0.7)
					(thickness 0.15)
				)
				(justify left bottom)
			)
		)
		(property "Footprint" "antmicro-footprints:R_0402_1005Metric"
			(at 0 0 0)
			(layer "F.Fab")
			(hide yes)
			(effects
				(font
					(size 1.27 1.27)
					(thickness 0.15)
				)
			)
		)
		(property "Datasheet" "https://industrial.panasonic.com/cdbs/www-data/pdf/RDA0000/AOA0000C301.pdf"
			(at 0 0 0)
			(layer "F.Fab")
			(hide yes)
			(effects
				(font
					(size 1.27 1.27)
					(thickness 0.15)
				)
			)
		)
		(property "Author" "Antmicro"
			(at 0 0 0)
			(layer "F.Fab")
			(hide yes)
			(effects
				(font
					(size 1 1)
					(thickness 0.15)
				)
			)
		)
		(property "Current" "1A"
			(at 0 0 0)
			(layer "F.Fab")
			(hide yes)
			(effects
				(font
					(size 1 1)
					(thickness 0.15)
				)
			)
		)
		(property "License" "Apache-2.0"
			(at 0 0 0)
			(layer "F.Fab")
			(hide yes)
			(effects
				(font
					(size 1 1)
					(thickness 0.15)
				)
			)
		)
		(property "MPN" "ERJ2GE0R00X"
			(at 0 0 0)
			(layer "F.Fab")
			(hide yes)
			(effects
				(font
					(size 1 1)
					(thickness 0.15)
				)
			)
		)
		(property "Manufacturer" "Panasonic"
			(at 0 0 0)
			(layer "F.Fab")
			(hide yes)
			(effects
				(font
					(size 1 1)
					(thickness 0.15)
				)
			)
		)
		(property "Tolerance" ""
			(at 0 0 0)
			(layer "F.Fab")
			(hide yes)
			(effects
				(font
					(size 1 1)
					(thickness 0.15)
				)
			)
		)
		(property "Val" "0R"
			(at 0 0 0)
			(layer "F.Fab")
			(hide yes)
			(effects
				(font
					(size 1 1)
					(thickness 0.15)
				)
			)
		)
		(sheetname "Peripherals")
		(sheetfile "peripherals.kicad_sch")
		(attr smd)
		(fp_rect
			(start -0.925 -0.47)
			(end 0.925 0.47)
			(stroke
				(width 0.05)
				(type default)
			)
			(fill none)
			(layer "F.CrtYd")
		)
		(fp_rect
			(start -0.5 -0.25)
			(end 0.5 0.25)
			(stroke
				(width 0.15)
				(type solid)
			)
			(fill none)
			(layer "F.Fab")
		)
		(fp_text user "Author: Antmicro"
			(at -0.95 4.169 0)
			(layer "F.Fab")
			(hide yes)
			(effects
				(font
					(size 0.7 0.7)
					(thickness 0.15)
				)
				(justify left bottom)
			)
		)
		(fp_text user "${REFERENCE}"
			(at -0.95 3.168 0)
			(layer "F.Fab")
			(hide yes)
			(effects
				(font
					(size 0.7 0.7)
					(thickness 0.15)
				)
				(justify left bottom)
			)
		)
		(fp_text user "License: Apache-2.0"
			(at -0.95 5.169 0)
			(layer "F.Fab")
			(hide yes)
			(effects
				(font
					(size 0.7 0.7)
					(thickness 0.15)
				)
				(justify left bottom)
			)
		)
		(pad "1" smd roundrect
			(at -0.48 0)
			(size 0.59 0.64)
			(layers "F.Cu" "F.Paste" "F.Mask")
			(roundrect_rratio 0.25)
			(net 251 "SYS_SDA")
			(pintype "passive")
		)
		(pad "2" smd roundrect
			(at 0.48 0)
			(size 0.59 0.64)
			(layers "F.Cu" "F.Paste" "F.Mask")
			(roundrect_rratio 0.25)
			(net 596 "Net-(J11-Pad63)")
			(pintype "passive")
		)
	)
	(footprint "antmicro-footprints:R_0402_1005Metric"
		(layer "F.Cu")
		(at 99.05 114.65 -90)
		(descr "Resistor SMD 0402")
		(tags "resistor SMD 0402")
		(property "Reference" "R242"
			(at -0.8 -0.45 -90)
			(layer "F.SilkS")
			(effects
				(font
					(size 0.7 0.7)
					(thickness 0.15)
				)
				(justify left bottom)
			)
		)
		(property "Value" "R_10k_0402"
			(at 0 1.4 -90)
			(layer "F.Fab")
			(effects
				(font
					(size 0.7 0.7)
					(thickness 0.15)
				)
				(justify left bottom)
			)
		)
		(property "Footprint" "antmicro-footprints:R_0402_1005Metric"
			(at 0 0 -90)
			(layer "F.Fab")
			(hide yes)
			(effects
				(font
					(size 1.27 1.27)
					(thickness 0.15)
				)
			)
		)
		(property "Datasheet" "https://www.bourns.com/docs/product-datasheets/cr.pdf"
			(at 0 0 -90)
			(layer "F.Fab")
			(hide yes)
			(effects
				(font
					(size 1.27 1.27)
					(thickness 0.15)
				)
			)
		)
		(property "Author" "Antmicro"
			(at -15.6 213.7 0)
			(layer "F.Fab")
			(hide yes)
			(effects
				(font
					(size 1 1)
					(thickness 0.15)
				)
			)
		)
		(property "License" "Apache-2.0"
			(at -15.6 213.7 0)
			(layer "F.Fab")
			(hide yes)
			(effects
				(font
					(size 1 1)
					(thickness 0.15)
				)
			)
		)
		(property "MPN" "CR0402-FX-1002GLF"
			(at -15.6 213.7 0)
			(layer "F.Fab")
			(hide yes)
			(effects
				(font
					(size 1 1)
					(thickness 0.15)
				)
			)
		)
		(property "Manufacturer" "Bourns"
			(at -15.6 213.7 0)
			(layer "F.Fab")
			(hide yes)
			(effects
				(font
					(size 1 1)
					(thickness 0.15)
				)
			)
		)
		(property "Tolerance" "1%"
			(at -15.6 213.7 0)
			(layer "F.Fab")
			(hide yes)
			(effects
				(font
					(size 1 1)
					(thickness 0.15)
				)
			)
		)
		(property "Val" "10k"
			(at -15.6 213.7 0)
			(layer "F.Fab")
			(hide yes)
			(effects
				(font
					(size 1 1)
					(thickness 0.15)
				)
			)
		)
		(sheetname "Peripherals")
		(sheetfile "peripherals.kicad_sch")
		(attr smd)
		(fp_rect
			(start -0.925 -0.47)
			(end 0.925 0.47)
			(stroke
				(width 0.05)
				(type default)
			)
			(fill none)
			(layer "F.CrtYd")
		)
		(fp_rect
			(start -0.5 -0.25)
			(end 0.5 0.25)
			(stroke
				(width 0.15)
				(type solid)
			)
			(fill none)
			(layer "F.Fab")
		)
		(fp_text user "License: Apache-2.0"
			(at -0.95 5.169 -90)
			(layer "F.Fab")
			(hide yes)
			(effects
				(font
					(size 0.7 0.7)
					(thickness 0.15)
				)
				(justify left bottom)
			)
		)
		(fp_text user "Author: Antmicro"
			(at -0.95 4.169 -90)
			(layer "F.Fab")
			(hide yes)
			(effects
				(font
					(size 0.7 0.7)
					(thickness 0.15)
				)
				(justify left bottom)
			)
		)
		(fp_text user "${REFERENCE}"
			(at -0.95 3.168 -90)
			(layer "F.Fab")
			(hide yes)
			(effects
				(font
					(size 0.7 0.7)
					(thickness 0.15)
				)
				(justify left bottom)
			)
		)
		(pad "1" smd roundrect
			(at -0.48 0 270)
			(size 0.59 0.64)
			(layers "F.Cu" "F.Paste" "F.Mask")
			(roundrect_rratio 0.25)
			(net 46 "USER_BTN1")
			(pintype "passive")
		)
		(pad "2" smd roundrect
			(at 0.48 0 270)
			(size 0.59 0.64)
			(layers "F.Cu" "F.Paste" "F.Mask")
			(roundrect_rratio 0.25)
			(net 112 "+1V8")
			(pintype "passive")
		)
	)
	(footprint "antmicro-footprints:C_0402_1005Metric"
		(layer "F.Cu")
		(at 111.8 111.75 90)
		(descr "Capacitor SMD 0402")
		(tags "capacitor SMD 0402")
		(property "Reference" "C71"
			(at 0.8 0.5 90)
			(layer "F.SilkS")
			(effects
				(font
					(size 0.7 0.7)
					(thickness 0.15)
				)
				(justify left bottom)
			)
		)
		(property "Value" "C_100n_0402"
			(at 0 1.4 90)
			(layer "F.Fab")
			(effects
				(font
					(size 0.7 0.7)
					(thickness 0.15)
				)
				(justify left bottom)
			)
		)
		(property "Footprint" "antmicro-footprints:C_0402_1005Metric"
			(at 0 0 90)
			(layer "F.Fab")
			(hide yes)
			(effects
				(font
					(size 1.27 1.27)
					(thickness 0.15)
				)
			)
		)
		(property "Datasheet" "https://www.murata.com/products/productdetail?partno=GRM155R61H104KE14%23"
			(at 0 0 90)
			(layer "F.Fab")
			(hide yes)
			(effects
				(font
					(size 1.27 1.27)
					(thickness 0.15)
				)
			)
		)
		(property "Author" "Antmicro"
			(at 223.55 -0.05 0)
			(layer "F.Fab")
			(hide yes)
			(effects
				(font
					(size 1 1)
					(thickness 0.15)
				)
			)
		)
		(property "Dielectric" "X5R"
			(at 223.55 -0.05 0)
			(layer "F.Fab")
			(hide yes)
			(effects
				(font
					(size 1 1)
					(thickness 0.15)
				)
			)
		)
		(property "License" "Apache-2.0"
			(at 223.55 -0.05 0)
			(layer "F.Fab")
			(hide yes)
			(effects
				(font
					(size 1 1)
					(thickness 0.15)
				)
			)
		)
		(property "MPN" "GRM155R61H104KE14D"
			(at 223.55 -0.05 0)
			(layer "F.Fab")
			(hide yes)
			(effects
				(font
					(size 1 1)
					(thickness 0.15)
				)
			)
		)
		(property "Manufacturer" "Murata"
			(at 223.55 -0.05 0)
			(layer "F.Fab")
			(hide yes)
			(effects
				(font
					(size 1 1)
					(thickness 0.15)
				)
			)
		)
		(property "Val" "100n"
			(at 223.55 -0.05 0)
			(layer "F.Fab")
			(hide yes)
			(effects
				(font
					(size 1 1)
					(thickness 0.15)
				)
			)
		)
		(property "Voltage" "50V"
			(at 223.55 -0.05 0)
			(layer "F.Fab")
			(hide yes)
			(effects
				(font
					(size 1 1)
					(thickness 0.15)
				)
			)
		)
		(sheetname "USB3")
		(sheetfile "usb3.kicad_sch")
		(attr smd)
		(fp_rect
			(start -0.925 -0.47)
			(end 0.925 0.47)
			(stroke
				(width 0.05)
				(type default)
			)
			(fill none)
			(layer "F.CrtYd")
		)
		(fp_line
			(start 0.504 -0.25)
			(end 0.504 0.248)
			(stroke
				(width 0.15)
				(type solid)
			)
			(layer "F.Fab")
		)
		(fp_line
			(start -0.494 -0.25)
			(end 0.504 -0.25)
			(stroke
				(width 0.15)
				(type solid)
			)
			(layer "F.Fab")
		)
		(fp_line
			(start 0.504 0.248)
			(end -0.494 0.248)
			(stroke
				(width 0.15)
				(type solid)
			)
			(layer "F.Fab")
		)
		(fp_line
			(start -0.494 0.248)
			(end -0.494 -0.25)
			(stroke
				(width 0.15)
				(type solid)
			)
			(layer "F.Fab")
		)
		(fp_text user "License: Apache-2.0"
			(at -0.932 5.17 90)
			(layer "F.Fab")
			(hide yes)
			(effects
				(font
					(size 0.7 0.7)
					(thickness 0.15)
				)
				(justify left bottom)
			)
		)
		(fp_text user "Author: Antmicro"
			(at -0.932 4.17 90)
			(layer "F.Fab")
			(hide yes)
			(effects
				(font
					(size 0.7 0.7)
					(thickness 0.15)
				)
				(justify left bottom)
			)
		)
		(fp_text user "${REFERENCE}"
			(at -0.932 3.168 90)
			(layer "F.Fab")
			(hide yes)
			(effects
				(font
					(size 0.7 0.7)
					(thickness 0.15)
				)
				(justify left bottom)
			)
		)
		(pad "1" smd roundrect
			(at -0.48 0 90)
			(size 0.59 0.64)
			(layers "F.Cu" "F.Paste" "F.Mask")
			(roundrect_rratio 0.25)
			(net 267 "/USB3/USBC1_CONN_TX1_P")
			(pintype "passive")
		)
		(pad "2" smd roundrect
			(at 0.48 0 90)
			(size 0.59 0.64)
			(layers "F.Cu" "F.Paste" "F.Mask")
			(roundrect_rratio 0.25)
			(net 266 "/USB3/USBC1_TX1_P")
			(pintype "passive")
		)
	)
	(footprint "antmicro-footprints:SOD-523"
		(layer "F.Cu")
		(at 87.7 119.5 180)
		(property "Reference" "D38"
			(at 3.05 -0.43 180)
			(layer "F.SilkS")
			(effects
				(font
					(size 0.7 0.7)
					(thickness 0.15)
				)
				(justify left bottom)
			)
		)
		(property "Value" "RB521S30T1G"
			(at 0 1.499 180)
			(layer "F.Fab")
			(effects
				(font
					(size 0.7 0.7)
					(thickness 0.15)
				)
				(justify left bottom)
			)
		)
		(property "Footprint" "antmicro-footprints:SOD-523"
			(at 0 0 180)
			(layer "F.Fab")
			(hide yes)
			(effects
				(font
					(size 1.27 1.27)
					(thickness 0.15)
				)
			)
		)
		(property "Datasheet" "https://www.onsemi.com/pdf/datasheet/rb521s30t1-d.pdf"
			(at 0 0 180)
			(layer "F.Fab")
			(hide yes)
			(effects
				(font
					(size 1.27 1.27)
					(thickness 0.15)
				)
			)
		)
		(property "Author" "Antmicro"
			(at 175.4 239 0)
			(layer "F.Fab")
			(hide yes)
			(effects
				(font
					(size 1 1)
					(thickness 0.15)
				)
			)
		)
		(property "License" "Apache-2.0"
			(at 175.4 239 0)
			(layer "F.Fab")
			(hide yes)
			(effects
				(font
					(size 1 1)
					(thickness 0.15)
				)
			)
		)
		(property "MPN" "RB521S30T1G"
			(at 175.4 239 0)
			(layer "F.Fab")
			(hide yes)
			(effects
				(font
					(size 1 1)
					(thickness 0.15)
				)
			)
		)
		(property "Manufacturer" "ON Semiconductor"
			(at 175.4 239 0)
			(layer "F.Fab")
			(hide yes)
			(effects
				(font
					(size 1 1)
					(thickness 0.15)
				)
			)
		)
		(sheetname "HDMI")
		(sheetfile "hdmi.kicad_sch")
		(attr smd)
		(fp_line
			(start -0.35 -0.5)
			(end -0.35 0.5)
			(stroke
				(width 0.15)
				(type solid)
			)
			(layer "F.SilkS")
		)
		(fp_rect
			(start -1 -0.6)
			(end 1 0.6)
			(stroke
				(width 0.05)
				(type solid)
			)
			(fill none)
			(layer "F.CrtYd")
		)
		(fp_line
			(start 0.65 -0.425)
			(end 0.65 0.423)
			(stroke
				(width 0.15)
				(type solid)
			)
			(layer "F.Fab")
		)
		(fp_line
			(start -0.35 -0.4)
			(end -0.35 0.4)
			(stroke
				(width 0.15)
				(type solid)
			)
			(layer "F.Fab")
		)
		(fp_line
			(start -0.652 0.423)
			(end 0.65 0.423)
			(stroke
				(width 0.15)
				(type solid)
			)
			(layer "F.Fab")
		)
		(fp_line
			(start -0.652 0.423)
			(end -0.652 -0.425)
			(stroke
				(width 0.15)
				(type solid)
			)
			(layer "F.Fab")
		)
		(fp_line
			(start -0.652 -0.425)
			(end 0.65 -0.425)
			(stroke
				(width 0.15)
				(type solid)
			)
			(layer "F.Fab")
		)
		(fp_text user "${REFERENCE}"
			(at -1.276 3.499 180)
			(layer "F.Fab")
			(hide yes)
			(effects
				(font
					(size 0.7 0.7)
					(thickness 0.15)
				)
				(justify left bottom)
			)
		)
		(fp_text user "Author: Antmicro"
			(at -1.276 4.7 180)
			(layer "F.Fab")
			(hide yes)
			(effects
				(font
					(size 0.7 0.7)
					(thickness 0.15)
				)
				(justify left bottom)
			)
		)
		(fp_text user "License: Apache-2.0"
			(at -1.276 5.9 180)
			(layer "F.Fab")
			(hide yes)
			(effects
				(font
					(size 0.7 0.7)
					(thickness 0.15)
				)
				(justify left bottom)
			)
		)
		(pad "1" smd roundrect
			(at -0.701 0 180)
			(size 0.5 0.6)
			(layers "F.Cu" "F.Paste" "F.Mask")
			(roundrect_rratio 0.25)
			(net 498 "/HDMI/5V_HDMI")
			(pinfunction "C")
			(pintype "passive")
		)
		(pad "2" smd roundrect
			(at 0.699 0 180)
			(size 0.5 0.6)
			(layers "F.Cu" "F.Paste" "F.Mask")
			(roundrect_rratio 0.25)
			(net 424 "Net-(D38-A)")
			(pinfunction "A")
			(pintype "passive")
		)
	)
	(footprint "antmicro-footprints:R_0402_1005Metric"
		(layer "F.Cu")
		(at 148 111.5 180)
		(descr "Resistor SMD 0402")
		(tags "resistor SMD 0402")
		(property "Reference" "R336"
			(at 1.22 -5.85 180)
			(layer "F.SilkS")
			(effects
				(font
					(size 0.7 0.7)
					(thickness 0.15)
				)
				(justify left bottom)
			)
		)
		(property "Value" "R_470R_0402"
			(at 0 1.4 180)
			(layer "F.Fab")
			(effects
				(font
					(size 0.7 0.7)
					(thickness 0.15)
				)
				(justify left bottom)
			)
		)
		(property "Footprint" "antmicro-footprints:R_0402_1005Metric"
			(at 0 0 180)
			(layer "F.Fab")
			(hide yes)
			(effects
				(font
					(size 1.27 1.27)
					(thickness 0.15)
				)
			)
		)
		(property "Datasheet" "https://www.bourns.com/docs/product-datasheets/cr.pdf"
			(at 0 0 180)
			(layer "F.Fab")
			(hide yes)
			(effects
				(font
					(size 1.27 1.27)
					(thickness 0.15)
				)
			)
		)
		(property "Author" "Antmicro"
			(at 296 223 0)
			(layer "F.Fab")
			(hide yes)
			(effects
				(font
					(size 1 1)
					(thickness 0.15)
				)
			)
		)
		(property "License" "Apache-2.0"
			(at 296 223 0)
			(layer "F.Fab")
			(hide yes)
			(effects
				(font
					(size 1 1)
					(thickness 0.15)
				)
			)
		)
		(property "MPN" "CR0402-FX-4700GLF"
			(at 296 223 0)
			(layer "F.Fab")
			(hide yes)
			(effects
				(font
					(size 1 1)
					(thickness 0.15)
				)
			)
		)
		(property "Manufacturer" "Bourns"
			(at 296 223 0)
			(layer "F.Fab")
			(hide yes)
			(effects
				(font
					(size 1 1)
					(thickness 0.15)
				)
			)
		)
		(property "Tolerance" "1%"
			(at 296 223 0)
			(layer "F.Fab")
			(hide yes)
			(effects
				(font
					(size 1 1)
					(thickness 0.15)
				)
			)
		)
		(property "Val" "470R"
			(at 296 223 0)
			(layer "F.Fab")
			(hide yes)
			(effects
				(font
					(size 1 1)
					(thickness 0.15)
				)
			)
		)
		(sheetname "Peripherals")
		(sheetfile "peripherals.kicad_sch")
		(attr smd)
		(fp_rect
			(start -0.925 -0.47)
			(end 0.925 0.47)
			(stroke
				(width 0.05)
				(type default)
			)
			(fill none)
			(layer "F.CrtYd")
		)
		(fp_rect
			(start -0.5 -0.25)
			(end 0.5 0.25)
			(stroke
				(width 0.15)
				(type solid)
			)
			(fill none)
			(layer "F.Fab")
		)
		(fp_text user "Author: Antmicro"
			(at -0.95 4.169 180)
			(layer "F.Fab")
			(hide yes)
			(effects
				(font
					(size 0.7 0.7)
					(thickness 0.15)
				)
				(justify left bottom)
			)
		)
		(fp_text user "License: Apache-2.0"
			(at -0.95 5.169 180)
			(layer "F.Fab")
			(hide yes)
			(effects
				(font
					(size 0.7 0.7)
					(thickness 0.15)
				)
				(justify left bottom)
			)
		)
		(fp_text user "${REFERENCE}"
			(at -0.95 3.168 180)
			(layer "F.Fab")
			(hide yes)
			(effects
				(font
					(size 0.7 0.7)
					(thickness 0.15)
				)
				(justify left bottom)
			)
		)
		(pad "1" smd roundrect
			(at -0.48 0 180)
			(size 0.59 0.64)
			(layers "F.Cu" "F.Paste" "F.Mask")
			(roundrect_rratio 0.25)
			(net 101 "CAN_TX")
			(pintype "passive")
		)
		(pad "2" smd roundrect
			(at 0.48 0 180)
			(size 0.59 0.64)
			(layers "F.Cu" "F.Paste" "F.Mask")
			(roundrect_rratio 0.25)
			(net 601 "Net-(J11-Pad70)")
			(pintype "passive")
		)
	)
	(footprint "antmicro-footprints:R_Array_4x0402"
		(layer "F.Cu")
		(at 147.85 99.4 -90)
		(property "Reference" "R100"
			(at 1.42 -1.65 -90)
			(layer "F.SilkS")
			(effects
				(font
					(size 0.7 0.7)
					(thickness 0.15)
				)
				(justify left bottom)
			)
		)
		(property "Value" "R_4x330R_0402_array"
			(at -1.5 2 -90)
			(layer "F.Fab")
			(effects
				(font
					(size 0.7 0.7)
					(thickness 0.15)
				)
				(justify left bottom)
			)
		)
		(property "Footprint" "antmicro-footprints:R_Array_4x0402"
			(at 0 0 -90)
			(layer "F.Fab")
			(hide yes)
			(effects
				(font
					(size 1.27 1.27)
					(thickness 0.15)
				)
			)
		)
		(property "Datasheet" "http://industrial.panasonic.com/cdbs/www-data/pdf/AOC0000/AOC0000C14.pdf"
			(at 0 0 -90)
			(layer "F.Fab")
			(hide yes)
			(effects
				(font
					(size 1.27 1.27)
					(thickness 0.15)
				)
			)
		)
		(property "Author" "Antmicro"
			(at 48.45 247.25 0)
			(layer "F.Fab")
			(hide yes)
			(effects
				(font
					(size 1 1)
					(thickness 0.15)
				)
			)
		)
		(property "License" "Apache-2.0"
			(at 48.45 247.25 0)
			(layer "F.Fab")
			(hide yes)
			(effects
				(font
					(size 1 1)
					(thickness 0.15)
				)
			)
		)
		(property "MPN" "EXB-28V331JX"
			(at 48.45 247.25 0)
			(layer "F.Fab")
			(hide yes)
			(effects
				(font
					(size 1 1)
					(thickness 0.15)
				)
			)
		)
		(property "Manufacturer" "Panasonic"
			(at 48.45 247.25 0)
			(layer "F.Fab")
			(hide yes)
			(effects
				(font
					(size 1 1)
					(thickness 0.15)
				)
			)
		)
		(property "Val" "R_4x330R_0402"
			(at 48.45 247.25 0)
			(layer "F.Fab")
			(hide yes)
			(effects
				(font
					(size 1 1)
					(thickness 0.15)
				)
			)
		)
		(sheetname "Peripherals")
		(sheetfile "peripherals.kicad_sch")
		(attr smd)
		(fp_line
			(start 1.167 0.498)
			(end 1.167 -0.5)
			(stroke
				(width 0.15)
				(type solid)
			)
			(layer "F.SilkS")
		)
		(fp_line
			(start -1.17 -0.5)
			(end -1.17 0.498)
			(stroke
				(width 0.15)
				(type solid)
			)
			(layer "F.SilkS")
		)
		(fp_rect
			(start -1.2 -0.9)
			(end 1.2 0.9)
			(stroke
				(width 0.05)
				(type solid)
			)
			(fill none)
			(layer "F.CrtYd")
		)
		(fp_line
			(start -1 0.498)
			(end -1 -0.5)
			(stroke
				(width 0.15)
				(type solid)
			)
			(layer "F.Fab")
		)
		(fp_line
			(start 0.998 0.498)
			(end -1 0.498)
			(stroke
				(width 0.15)
				(type solid)
			)
			(layer "F.Fab")
		)
		(fp_line
			(start -1 -0.5)
			(end 0.998 -0.5)
			(stroke
				(width 0.15)
				(type solid)
			)
			(layer "F.Fab")
		)
		(fp_line
			(start 0.998 -0.5)
			(end 0.998 0.498)
			(stroke
				(width 0.15)
				(type solid)
			)
			(layer "F.Fab")
		)
		(fp_text user "Author: Antmicro"
			(at -1.5 4.5 -90)
			(layer "F.Fab")
			(hide yes)
			(effects
				(font
					(size 0.7 0.7)
					(thickness 0.15)
				)
				(justify left bottom)
			)
		)
		(fp_text user "License: Apache-2.0"
			(at -1.5 5.75 -90)
			(layer "F.Fab")
			(hide yes)
			(effects
				(font
					(size 0.7 0.7)
					(thickness 0.15)
				)
				(justify left bottom)
			)
		)
		(fp_text user "${REFERENCE}"
			(at -1.5 3.25 -90)
			(layer "F.Fab")
			(hide yes)
			(effects
				(font
					(size 0.7 0.7)
					(thickness 0.15)
				)
				(justify left bottom)
			)
		)
		(pad "1" smd roundrect
			(at -0.802 0.45 270)
			(size 0.4 0.5)
			(layers "F.Cu" "F.Paste" "F.Mask")
			(roundrect_rratio 0.25)
			(net 581 "/Peripherals/GPIO12_CONN")
			(pinfunction "R1.1")
			(pintype "passive")
		)
		(pad "2" smd roundrect
			(at -0.272 0.45 270)
			(size 0.4 0.5)
			(layers "F.Cu" "F.Paste" "F.Mask")
			(roundrect_rratio 0.25)
			(net 583 "/Peripherals/GPIO11_CONN")
			(pinfunction "R2.1")
			(pintype "passive")
		)
		(pad "3" smd roundrect
			(at 0.27 0.45 270)
			(size 0.4 0.5)
			(layers "F.Cu" "F.Paste" "F.Mask")
			(roundrect_rratio 0.25)
			(net 582 "/Peripherals/UART1_TXD_CONN")
			(pinfunction "R3.1")
			(pintype "passive")
		)
		(pad "4" smd roundrect
			(at 0.8 0.45 270)
			(size 0.4 0.5)
			(layers "F.Cu" "F.Paste" "F.Mask")
			(roundrect_rratio 0.25)
			(net 586 "/Peripherals/I2S0_SCLK_CONN")
			(pinfunction "R4.1")
			(pintype "passive")
		)
		(pad "5" smd roundrect
			(at 0.8 -0.452 270)
			(size 0.4 0.5)
			(layers "F.Cu" "F.Paste" "F.Mask")
			(roundrect_rratio 0.25)
			(net 75 "I2S0_SCLK")
			(pinfunction "R4.2")
			(pintype "passive")
		)
		(pad "6" smd roundrect
			(at 0.27 -0.452 270)
			(size 0.4 0.5)
			(layers "F.Cu" "F.Paste" "F.Mask")
			(roundrect_rratio 0.25)
			(net 460 "UART1_TXD")
			(pinfunction "R3.2")
			(pintype "passive")
		)
		(pad "7" smd roundrect
			(at -0.272 -0.452 270)
			(size 0.4 0.5)
			(layers "F.Cu" "F.Paste" "F.Mask")
			(roundrect_rratio 0.25)
			(net 82 "GPIO11")
			(pinfunction "R2.2")
			(pintype "passive")
		)
		(pad "8" smd roundrect
			(at -0.802 -0.452 270)
			(size 0.4 0.5)
			(layers "F.Cu" "F.Paste" "F.Mask")
			(roundrect_rratio 0.25)
			(net 83 "GPIO12")
			(pinfunction "R1.2")
			(pintype "passive")
		)
	)
	(footprint "antmicro-footprints:C_0402_1005Metric"
		(layer "F.Cu")
		(at 65.75 95.82 -90)
		(descr "Capacitor SMD 0402")
		(tags "capacitor SMD 0402")
		(property "Reference" "C102"
			(at -1.01 -1.33 90)
			(layer "F.SilkS")
			(effects
				(font
					(size 0.7 0.7)
					(thickness 0.15)
				)
				(justify right bottom)
			)
		)
		(property "Value" "C_100n_0402"
			(at -1.022927 2.155213 90)
			(layer "F.Fab")
			(effects
				(font
					(size 0.7 0.7)
					(thickness 0.15)
				)
				(justify right bottom)
			)
		)
		(property "Footprint" "antmicro-footprints:C_0402_1005Metric"
			(at 0 0 -90)
			(layer "F.Fab")
			(hide yes)
			(effects
				(font
					(size 1.27 1.27)
					(thickness 0.15)
				)
			)
		)
		(property "Datasheet" "https://www.murata.com/products/productdetail?partno=GRM155R61H104KE14%23"
			(at 0 0 -90)
			(layer "F.Fab")
			(hide yes)
			(effects
				(font
					(size 1.27 1.27)
					(thickness 0.15)
				)
			)
		)
		(property "Author" "Antmicro"
			(at -30.07 161.57 0)
			(layer "F.Fab")
			(hide yes)
			(effects
				(font
					(size 1 1)
					(thickness 0.15)
				)
			)
		)
		(property "Dielectric" "X5R"
			(at -30.07 161.57 0)
			(layer "F.Fab")
			(hide yes)
			(effects
				(font
					(size 1 1)
					(thickness 0.15)
				)
			)
		)
		(property "License" "Apache-2.0"
			(at -30.07 161.57 0)
			(layer "F.Fab")
			(hide yes)
			(effects
				(font
					(size 1 1)
					(thickness 0.15)
				)
			)
		)
		(property "MPN" "GRM155R61H104KE14D"
			(at -30.07 161.57 0)
			(layer "F.Fab")
			(hide yes)
			(effects
				(font
					(size 1 1)
					(thickness 0.15)
				)
			)
		)
		(property "Manufacturer" "Murata"
			(at -30.07 161.57 0)
			(layer "F.Fab")
			(hide yes)
			(effects
				(font
					(size 1 1)
					(thickness 0.15)
				)
			)
		)
		(property "Val" "100n"
			(at -30.07 161.57 0)
			(layer "F.Fab")
			(hide yes)
			(effects
				(font
					(size 1 1)
					(thickness 0.15)
				)
			)
		)
		(property "Voltage" "50V"
			(at -30.07 161.57 0)
			(layer "F.Fab")
			(hide yes)
			(effects
				(font
					(size 1 1)
					(thickness 0.15)
				)
			)
		)
		(sheetname "Supply")
		(sheetfile "supply.kicad_sch")
		(attr smd)
		(fp_rect
			(start -0.925 -0.47)
			(end 0.925 0.47)
			(stroke
				(width 0.05)
				(type default)
			)
			(fill none)
			(layer "F.CrtYd")
		)
		(fp_line
			(start -0.494 0.248)
			(end -0.494 -0.25)
			(stroke
				(width 0.15)
				(type solid)
			)
			(layer "F.Fab")
		)
		(fp_line
			(start 0.504 0.248)
			(end -0.494 0.248)
			(stroke
				(width 0.15)
				(type solid)
			)
			(layer "F.Fab")
		)
		(fp_line
			(start -0.494 -0.25)
			(end 0.504 -0.25)
			(stroke
				(width 0.15)
				(type solid)
			)
			(layer "F.Fab")
		)
		(fp_line
			(start 0.504 -0.25)
			(end 0.504 0.248)
			(stroke
				(width 0.15)
				(type solid)
			)
			(layer "F.Fab")
		)
		(fp_text user "${REFERENCE}"
			(at -0.939 4.599 90)
			(layer "F.Fab")
			(hide yes)
			(effects
				(font
					(size 0.7 0.7)
					(thickness 0.15)
				)
				(justify right bottom)
			)
		)
		(fp_text user "Author: Antmicro"
			(at -0.939 3.399 90)
			(layer "F.Fab")
			(hide yes)
			(effects
				(font
					(size 0.7 0.7)
					(thickness 0.15)
				)
				(justify right bottom)
			)
		)
		(fp_text user "License: Apache-2.0"
			(at -0.939 5.799 90)
			(layer "F.Fab")
			(hide yes)
			(effects
				(font
					(size 0.7 0.7)
					(thickness 0.15)
				)
				(justify right bottom)
			)
		)
		(pad "1" smd roundrect
			(at -0.48 0 270)
			(size 0.59 0.64)
			(layers "F.Cu" "F.Paste" "F.Mask")
			(roundrect_rratio 0.25)
			(net 765 "/Supply/5V_PHASE")
			(pintype "passive")
		)
		(pad "2" smd roundrect
			(at 0.48 0 270)
			(size 0.59 0.64)
			(layers "F.Cu" "F.Paste" "F.Mask")
			(roundrect_rratio 0.25)
			(net 760 "/Supply/5V_BOOT")
			(pintype "passive")
		)
	)
	(footprint "antmicro-footprints:XDFN-2_1x0.60mm"
		(layer "F.Cu")
		(at 147.45 85.6 -90)
		(property "Reference" "D46"
			(at -5.89 0.15 180)
			(layer "F.SilkS")
			(effects
				(font
					(size 0.7 0.7)
					(thickness 0.15)
				)
				(justify left bottom)
			)
		)
		(property "Value" "TPD1E0B04_XDFN-2"
			(at 0 1.5 -90)
			(layer "F.Fab")
			(effects
				(font
					(size 0.7 0.7)
					(thickness 0.15)
				)
				(justify left bottom)
			)
		)
		(property "Footprint" "antmicro-footprints:XDFN-2_1x0.60mm"
			(at 0 0 -90)
			(layer "F.Fab")
			(hide yes)
			(effects
				(font
					(size 1.27 1.27)
					(thickness 0.15)
				)
			)
		)
		(property "Datasheet" "https://www.ti.com/general/docs/suppproductinfo.tsp?distId=26&gotoUrl=https://www.ti.com/lit/gpn/tpd1e0b04"
			(at 0 0 -90)
			(layer "F.Fab")
			(hide yes)
			(effects
				(font
					(size 1.27 1.27)
					(thickness 0.15)
				)
			)
		)
		(property "MPN" "TPD1E0B04DPYR"
			(at 61.85 233.05 0)
			(layer "F.Fab")
			(hide yes)
			(effects
				(font
					(size 1 1)
					(thickness 0.15)
				)
			)
		)
		(property "Manufacturer" "Texas Instruments"
			(at 61.85 233.05 0)
			(layer "F.Fab")
			(hide yes)
			(effects
				(font
					(size 1 1)
					(thickness 0.15)
				)
			)
		)
		(property "Author" "Antmicro"
			(at 61.85 233.05 0)
			(layer "F.Fab")
			(hide yes)
			(effects
				(font
					(size 1 1)
					(thickness 0.15)
				)
			)
		)
		(property "License" "Apache-2.0"
			(at 61.85 233.05 0)
			(layer "F.Fab")
			(hide yes)
			(effects
				(font
					(size 1 1)
					(thickness 0.15)
				)
			)
		)
		(sheetname "Peripherals")
		(sheetfile "peripherals.kicad_sch")
		(attr smd)
		(fp_rect
			(start -0.725 -0.475)
			(end 0.725 0.475)
			(stroke
				(width 0.05)
				(type solid)
			)
			(fill none)
			(layer "F.CrtYd")
		)
		(fp_rect
			(start -0.55 -0.35)
			(end 0.55 0.35)
			(stroke
				(width 0.15)
				(type solid)
			)
			(fill none)
			(layer "F.Fab")
		)
		(fp_text user "Author: Antmicro"
			(at -0.8 4.4 -90)
			(layer "F.Fab")
			(hide yes)
			(effects
				(font
					(size 0.7 0.7)
					(thickness 0.15)
				)
				(justify left bottom)
			)
		)
		(fp_text user "License: Apache-2.0"
			(at -0.8 5.6 -90)
			(layer "F.Fab")
			(hide yes)
			(effects
				(font
					(size 0.7 0.7)
					(thickness 0.15)
				)
				(justify left bottom)
			)
		)
		(fp_text user "${REFERENCE}"
			(at -0.8 3.2 -90)
			(layer "F.Fab")
			(hide yes)
			(effects
				(font
					(size 0.7 0.7)
					(thickness 0.15)
				)
				(justify left bottom)
			)
		)
		(pad "1" smd roundrect
			(at -0.351 0 270)
			(size 0.3 0.5)
			(layers "F.Cu" "F.Paste" "F.Mask")
			(roundrect_rratio 0.25)
			(net 175 "PCIE2_RX1_P")
			(pinfunction "C")
			(pintype "passive")
		)
		(pad "2" smd roundrect
			(at 0.349 0 270)
			(size 0.3 0.5)
			(layers "F.Cu" "F.Paste" "F.Mask")
			(roundrect_rratio 0.25)
			(net 1 "GND")
			(pinfunction "A")
			(pintype "passive")
		)
	)
	(footprint "antmicro-footprints:LED_0603_1608Metric_G"
		(layer "F.Cu")
		(at 59.3 123.4 90)
		(descr "LED SMD 0603 Green")
		(tags "LED SMD 0603 Green")
		(property "Reference" "D53"
			(at -1.2 1.5 90)
			(layer "F.SilkS")
			(effects
				(font
					(size 0.7 0.7)
					(thickness 0.15)
				)
				(justify left bottom)
			)
		)
		(property "Value" "LED_G_0603_LTST-C190GKT"
			(at -0.001 1.599 90)
			(layer "F.Fab")
			(effects
				(font
					(size 0.7 0.7)
					(thickness 0.15)
				)
				(justify left bottom)
			)
		)
		(property "Footprint" "antmicro-footprints:LED_0603_1608Metric_G"
			(at 0 0 90)
			(layer "F.Fab")
			(hide yes)
			(effects
				(font
					(size 1.27 1.27)
					(thickness 0.15)
				)
			)
		)
		(property "Datasheet" "https://media.digikey.com/pdf/Data%20Sheets/Lite-On%20PDFs/LTST-C190GKT.pdf"
			(at 0 0 90)
			(layer "F.Fab")
			(hide yes)
			(effects
				(font
					(size 1.27 1.27)
					(thickness 0.15)
				)
			)
		)
		(property "Author" "Antmicro"
			(at 182.7 64.1 0)
			(layer "F.Fab")
			(hide yes)
			(effects
				(font
					(size 1 1)
					(thickness 0.15)
				)
			)
		)
		(property "Color" "Green"
			(at 182.7 64.1 0)
			(layer "F.Fab")
			(hide yes)
			(effects
				(font
					(size 1 1)
					(thickness 0.15)
				)
			)
		)
		(property "License" "Apache-2.0"
			(at 182.7 64.1 0)
			(layer "F.Fab")
			(hide yes)
			(effects
				(font
					(size 1 1)
					(thickness 0.15)
				)
			)
		)
		(property "MPN" "LTST-C190GKT"
			(at 182.7 64.1 0)
			(layer "F.Fab")
			(hide yes)
			(effects
				(font
					(size 1 1)
					(thickness 0.15)
				)
			)
		)
		(property "Manufacturer" "Lite-On"
			(at 182.7 64.1 0)
			(layer "F.Fab")
			(hide yes)
			(effects
				(font
					(size 1 1)
					(thickness 0.15)
				)
			)
		)
		(sheetname "Supply")
		(sheetfile "supply.kicad_sch")
		(attr smd)
		(fp_line
			(start 0.22 -0.35)
			(end -0.22 -0.35)
			(stroke
				(width 0.15)
				(type solid)
			)
			(layer "F.SilkS")
		)
		(fp_line
			(start -1.18 -0.319)
			(end -1.18 0.321)
			(stroke
				(width 0.15)
				(type solid)
			)
			(layer "F.SilkS")
		)
		(fp_line
			(start 0.105328 0.001008)
			(end 0.24 0.001)
			(stroke
				(width 0.1)
				(type solid)
			)
			(layer "F.SilkS")
		)
		(fp_line
			(start -0.094672 0.001008)
			(end 0.105328 -0.198992)
			(stroke
				(width 0.1)
				(type solid)
			)
			(layer "F.SilkS")
		)
		(fp_line
			(start -0.094672 0.001008)
			(end -0.24 0.001008)
			(stroke
				(width 0.1)
				(type solid)
			)
			(layer "F.SilkS")
		)
		(fp_line
			(start 0.105328 0.201008)
			(end 0.105328 -0.198992)
			(stroke
				(width 0.1)
				(type solid)
			)
			(layer "F.SilkS")
		)
		(fp_line
			(start 0.105328 0.201008)
			(end -0.094672 0.001008)
			(stroke
				(width 0.1)
				(type solid)
			)
			(layer "F.SilkS")
		)
		(fp_line
			(start -0.094672 0.201008)
			(end -0.094672 -0.198992)
			(stroke
				(width 0.1)
				(type solid)
			)
			(layer "F.SilkS")
		)
		(fp_line
			(start 0.22 0.35)
			(end -0.22 0.35)
			(stroke
				(width 0.15)
				(type solid)
			)
			(layer "F.SilkS")
		)
		(fp_rect
			(start 1.25 0.65)
			(end -1.25 -0.65)
			(stroke
				(width 0.05)
				(type solid)
			)
			(fill none)
			(layer "F.CrtYd")
		)
		(fp_line
			(start 0.201 -0.202)
			(end -0.101 0)
			(stroke
				(width 0.15)
				(type solid)
			)
			(layer "F.Fab")
		)
		(fp_line
			(start -0.199 -0.202)
			(end -0.199 0.1)
			(stroke
				(width 0.15)
				(type solid)
			)
			(layer "F.Fab")
		)
		(fp_line
			(start 0.599 0)
			(end 0.201 0)
			(stroke
				(width 0.15)
				(type solid)
			)
			(layer "F.Fab")
		)
		(fp_line
			(start 0.201 0)
			(end 0.201 -0.202)
			(stroke
				(width 0.15)
				(type solid)
			)
			(layer "F.Fab")
		)
		(fp_line
			(start -0.101 0)
			(end 0.201 0.2)
			(stroke
				(width 0.15)
				(type solid)
			)
			(layer "F.Fab")
		)
		(fp_line
			(start -0.199 0)
			(end -0.597 0)
			(stroke
				(width 0.15)
				(type solid)
			)
			(layer "F.Fab")
		)
		(fp_line
			(start 0.201 0.2)
			(end 0.201 0)
			(stroke
				(width 0.15)
				(type solid)
			)
			(layer "F.Fab")
		)
		(fp_line
			(start -0.199 0.2)
			(end -0.199 0.1)
			(stroke
				(width 0.15)
				(type solid)
			)
			(layer "F.Fab")
		)
		(fp_rect
			(start 0.848 0.4)
			(end -0.85 -0.402)
			(stroke
				(width 0.15)
				(type solid)
			)
			(fill none)
			(layer "F.Fab")
		)
		(fp_text user "Author: Antmicro"
			(at -1.4224 4.799 90)
			(layer "F.Fab")
			(hide yes)
			(effects
				(font
					(size 0.7 0.7)
					(thickness 0.15)
				)
				(justify left bottom)
			)
		)
		(fp_text user "License: Apache-2.0"
			(at -1.4224 3.599 90)
			(layer "F.Fab")
			(hide yes)
			(effects
				(font
					(size 0.7 0.7)
					(thickness 0.15)
				)
				(justify left bottom)
			)
		)
		(fp_text user "${REFERENCE}"
			(at -1.4224 5.999 90)
			(layer "F.Fab")
			(hide yes)
			(effects
				(font
					(size 0.7 0.7)
					(thickness 0.15)
				)
				(justify left bottom)
			)
		)
		(pad "1" smd roundrect
			(at -0.7 0 270)
			(size 0.8 1)
			(layers "F.Cu" "F.Paste" "F.Mask")
			(roundrect_rratio 0.2)
			(net 1 "GND")
			(pinfunction "C")
			(pintype "passive")
		)
		(pad "2" smd roundrect
			(at 0.7 0 270)
			(size 0.8 1)
			(layers "F.Cu" "F.Paste" "F.Mask")
			(roundrect_rratio 0.2)
			(net 654 "Net-(D53-A)")
			(pinfunction "A")
			(pintype "passive")
		)
	)
	(footprint "antmicro-footprints:C_0603_1608Metric"
		(layer "F.Cu")
		(at 105.05 102.3 90)
		(descr "Capacitor SMD 0603")
		(tags "capacitor 0603")
		(property "Reference" "C66"
			(at 1.1 0.45 90)
			(layer "F.SilkS")
			(effects
				(font
					(size 0.7 0.7)
					(thickness 0.15)
				)
				(justify left bottom)
			)
		)
		(property "Value" "C_10u_0603"
			(at 0 1.6 90)
			(layer "F.Fab")
			(effects
				(font
					(size 0.7 0.7)
					(thickness 0.15)
				)
				(justify left bottom)
			)
		)
		(property "Footprint" "antmicro-footprints:C_0603_1608Metric"
			(at 0 0 90)
			(layer "F.Fab")
			(hide yes)
			(effects
				(font
					(size 1.27 1.27)
					(thickness 0.15)
				)
			)
		)
		(property "Datasheet" "https://www.murata.com/products/productdetail?partno=GRM188R61A106KE69%23"
			(at 0 0 90)
			(layer "F.Fab")
			(hide yes)
			(effects
				(font
					(size 1.27 1.27)
					(thickness 0.15)
				)
			)
		)
		(property "Author" "Antmicro"
			(at 207.35 -2.75 0)
			(layer "F.Fab")
			(hide yes)
			(effects
				(font
					(size 1 1)
					(thickness 0.15)
				)
			)
		)
		(property "Dielectric" "template_dielectric"
			(at 207.35 -2.75 0)
			(layer "F.Fab")
			(hide yes)
			(effects
				(font
					(size 1 1)
					(thickness 0.15)
				)
			)
		)
		(property "License" "Apache-2.0"
			(at 207.35 -2.75 0)
			(layer "F.Fab")
			(hide yes)
			(effects
				(font
					(size 1 1)
					(thickness 0.15)
				)
			)
		)
		(property "MPN" "GRM188R61A106KE69D"
			(at 207.35 -2.75 0)
			(layer "F.Fab")
			(hide yes)
			(effects
				(font
					(size 1 1)
					(thickness 0.15)
				)
			)
		)
		(property "Manufacturer" "Murata"
			(at 207.35 -2.75 0)
			(layer "F.Fab")
			(hide yes)
			(effects
				(font
					(size 1 1)
					(thickness 0.15)
				)
			)
		)
		(property "Val" "10u"
			(at 207.35 -2.75 0)
			(layer "F.Fab")
			(hide yes)
			(effects
				(font
					(size 1 1)
					(thickness 0.15)
				)
			)
		)
		(property "Voltage" ""
			(at 207.35 -2.75 0)
			(layer "F.Fab")
			(hide yes)
			(effects
				(font
					(size 1 1)
					(thickness 0.15)
				)
			)
		)
		(sheetname "USB3")
		(sheetfile "usb3.kicad_sch")
		(attr smd)
		(fp_line
			(start -0.15 -0.4)
			(end 0.15 -0.4)
			(stroke
				(width 0.15)
				(type solid)
			)
			(layer "F.SilkS")
		)
		(fp_line
			(start -0.15 0.4)
			(end 0.15 0.4)
			(stroke
				(width 0.15)
				(type solid)
			)
			(layer "F.SilkS")
		)
		(fp_rect
			(start -1.25 -0.65)
			(end 1.25 0.65)
			(stroke
				(width 0.05)
				(type solid)
			)
			(fill none)
			(layer "F.CrtYd")
		)
		(fp_rect
			(start -0.8 -0.4)
			(end 0.8 0.4)
			(stroke
				(width 0.15)
				(type solid)
			)
			(fill none)
			(layer "F.Fab")
		)
		(fp_text user "Author: Antmicro"
			(at -1.682 4.894 90)
			(layer "F.Fab")
			(hide yes)
			(effects
				(font
					(size 0.7 0.7)
					(thickness 0.15)
				)
				(justify left bottom)
			)
		)
		(fp_text user "License: Apache-2.0"
			(at -1.682 5.895 90)
			(layer "F.Fab")
			(hide yes)
			(effects
				(font
					(size 0.7 0.7)
					(thickness 0.15)
				)
				(justify left bottom)
			)
		)
		(fp_text user "${REFERENCE}"
			(at -1.682 3.895 90)
			(layer "F.Fab")
			(hide yes)
			(effects
				(font
					(size 0.7 0.7)
					(thickness 0.15)
				)
				(justify left bottom)
			)
		)
		(pad "1" smd roundrect
			(at -0.7 0 90)
			(size 0.8 1)
			(layers "F.Cu" "F.Paste" "F.Mask")
			(roundrect_rratio 0.2)
			(net 99 "+5V")
			(pintype "passive")
		)
		(pad "2" smd roundrect
			(at 0.7 0 90)
			(size 0.8 1)
			(layers "F.Cu" "F.Paste" "F.Mask")
			(roundrect_rratio 0.2)
			(net 1 "GND")
			(pintype "passive")
		)
	)
	(footprint "antmicro-footprints:Spacer_Drill3.7mm_H6.5mm_9774065151R"
		(locked yes)
		(layer "F.Cu")
		(at 124.525 118.1125)
		(descr "Spacer M=3 h=6.5mm fi=5.1mm")
		(property "Reference" "H2"
			(at -1.95 -3.251 0)
			(layer "F.SilkS")
			(effects
				(font
					(size 0.7 0.7)
					(thickness 0.15)
				)
				(justify left bottom)
			)
		)
		(property "Value" "Spacer_Drill3.7mm_H6.5mm_9774065151R"
			(at 0 4 0)
			(layer "F.Fab")
			(effects
				(font
					(size 0.7 0.7)
					(thickness 0.15)
				)
				(justify left bottom)
			)
		)
		(property "Footprint" "antmicro-footprints:Spacer_Drill3.7mm_H6.5mm_9774065151R"
			(at 0 0 0)
			(layer "F.Fab")
			(hide yes)
			(effects
				(font
					(size 1.27 1.27)
					(thickness 0.15)
				)
			)
		)
		(property "Datasheet" "https://www.we-online.com/components/products/datasheet/9774065151R.pdf"
			(at 0 0 0)
			(layer "F.Fab")
			(hide yes)
			(effects
				(font
					(size 1.27 1.27)
					(thickness 0.15)
				)
			)
		)
		(property "Author" "Antmicro"
			(at 0 0 0)
			(layer "F.Fab")
			(hide yes)
			(effects
				(font
					(size 1 1)
					(thickness 0.15)
				)
			)
		)
		(property "License" "Apache-2.0"
			(at 0 0 0)
			(layer "F.Fab")
			(hide yes)
			(effects
				(font
					(size 1 1)
					(thickness 0.15)
				)
			)
		)
		(property "MPN" "9774065151R"
			(at 0 0 0)
			(layer "F.Fab")
			(hide yes)
			(effects
				(font
					(size 1 1)
					(thickness 0.15)
				)
			)
		)
		(property "Manufacturer" "Würth Elektronik"
			(at 0 0 0)
			(layer "F.Fab")
			(hide yes)
			(effects
				(font
					(size 1 1)
					(thickness 0.15)
				)
			)
		)
		(sheetname "SoM")
		(sheetfile "som.kicad_sch")
		(solder_paste_ratio -1)
		(attr smd)
		(fp_circle
			(center 0 0)
			(end 3.05 0)
			(stroke
				(width 0.05)
				(type solid)
			)
			(fill none)
			(layer "F.CrtYd")
		)
		(fp_circle
			(center 0 0)
			(end 2.6 0)
			(stroke
				(width 0.15)
				(type solid)
			)
			(fill none)
			(layer "F.Fab")
		)
		(fp_text user "Author: Antmicro"
			(at -3.05041 7.1 0)
			(layer "F.Fab")
			(hide yes)
			(effects
				(font
					(size 0.7 0.7)
					(thickness 0.15)
				)
				(justify left bottom)
			)
		)
		(fp_text user "${REFERENCE}"
			(at -3.05041 8.3 0)
			(layer "F.Fab")
			(hide yes)
			(effects
				(font
					(size 0.7 0.7)
					(thickness 0.15)
				)
				(justify left bottom)
			)
		)
		(fp_text user "License: Apache-2.0"
			(at -3.05041 5.9 0)
			(layer "F.Fab")
			(hide yes)
			(effects
				(font
					(size 0.7 0.7)
					(thickness 0.15)
				)
				(justify left bottom)
			)
		)
		(pad "" smd custom
			(at -1.7 -1.7)
			(size 0.62 0.62)
			(layers "F.Paste")
			(thermal_bridge_angle 90)
			(options
				(clearance outline)
				(anchor circle)
			)
			(primitives
				(gr_arc
					(start -0.250195 1.279127)
					(mid 0.285453 0.294389)
					(end 1.266786 -0.24747)
					(width 0.2)
				)
				(gr_arc
					(start -0.34334 1.279127)
					(mid 0.218448 0.232561)
					(end 1.259603 -0.339191)
					(width 0.2)
				)
				(gr_arc
					(start -0.436309 1.279127)
					(mid 0.152481 0.169693)
					(end 1.255279 -0.431435)
					(width 0.2)
				)
				(gr_arc
					(start -0.529126 1.279127)
					(mid 0.087542 0.105784)
					(end 1.253811 -0.524161)
					(width 0.2)
				)
				(gr_arc
					(start -0.621807 1.279127)
					(mid 0.0309 0.033527)
					(end 1.275473 -0.621136)
					(width 0.2)
				)
				(gr_arc
					(start -0.71437 1.279127)
					(mid -0.037758 -0.026651)
					(end 1.263664 -0.711602)
					(width 0.2)
				)
				(gr_arc
					(start -0.806826 1.279127)
					(mid -0.105837 -0.087395)
					(end 1.253435 -0.802342)
					(width 0.2)
				)
				(gr_arc
					(start -0.899187 1.279127)
					(mid -0.165236 -0.156885)
					(end 1.267475 -0.897258)
					(width 0.2)
				)
				(gr_arc
					(start -0.991463 1.279127)
					(mid -0.228522 -0.222449)
					(end 1.270645 -0.990112)
					(width 0.2)
				)
				(gr_arc
					(start -1.083663 1.279127)
					(mid -0.294507 -0.285313)
					(end 1.266278 -1.081674)
					(width 0.2)
				)
				(gr_line
					(start 1.279127 -0.250195)
					(end 1.279127 -1.083663)
					(width 0.2)
				)
				(gr_line
					(start -0.250195 1.279127)
					(end -1.083663 1.279127)
					(width 0.2)
				)
			)
		)
		(pad "" smd custom
			(at -1.7 1.7 90)
			(size 0.62 0.62)
			(layers "F.Paste")
			(thermal_bridge_angle 90)
			(options
				(clearance outline)
				(anchor circle)
			)
			(primitives
				(gr_arc
					(start -0.250195 1.279127)
					(mid 0.285453 0.294389)
					(end 1.266786 -0.24747)
					(width 0.2)
				)
				(gr_arc
					(start -0.34334 1.279127)
					(mid 0.218448 0.232561)
					(end 1.259603 -0.339191)
					(width 0.2)
				)
				(gr_arc
					(start -0.436309 1.279127)
					(mid 0.152481 0.169693)
					(end 1.255279 -0.431435)
					(width 0.2)
				)
				(gr_arc
					(start -0.529126 1.279127)
					(mid 0.087542 0.105784)
					(end 1.253811 -0.524161)
					(width 0.2)
				)
				(gr_arc
					(start -0.621807 1.279127)
					(mid 0.0309 0.033527)
					(end 1.275473 -0.621136)
					(width 0.2)
				)
				(gr_arc
					(start -0.71437 1.279127)
					(mid -0.037758 -0.026651)
					(end 1.263664 -0.711602)
					(width 0.2)
				)
				(gr_arc
					(start -0.806826 1.279127)
					(mid -0.105837 -0.087395)
					(end 1.253435 -0.802342)
					(width 0.2)
				)
				(gr_arc
					(start -0.899187 1.279127)
					(mid -0.165236 -0.156885)
					(end 1.267475 -0.897258)
					(width 0.2)
				)
				(gr_arc
					(start -0.991463 1.279127)
					(mid -0.228522 -0.222449)
					(end 1.270645 -0.990112)
					(width 0.2)
				)
				(gr_arc
					(start -1.083663 1.279127)
					(mid -0.294507 -0.285313)
					(end 1.266278 -1.081674)
					(width 0.2)
				)
				(gr_line
					(start 1.279127 -0.250195)
					(end 1.279127 -1.083663)
					(width 0.2)
				)
				(gr_line
					(start -0.250195 1.279127)
					(end -1.083663 1.279127)
					(width 0.2)
				)
			)
		)
		(pad "" smd custom
			(at 1.7 -1.7 270)
			(size 0.62 0.62)
			(layers "F.Paste")
			(thermal_bridge_angle 90)
			(options
				(clearance outline)
				(anchor circle)
			)
			(primitives
				(gr_arc
					(start -0.250195 1.279127)
					(mid 0.285453 0.294389)
					(end 1.266786 -0.24747)
					(width 0.2)
				)
				(gr_arc
					(start -0.34334 1.279127)
					(mid 0.218448 0.232561)
					(end 1.259603 -0.339191)
					(width 0.2)
				)
				(gr_arc
					(start -0.436309 1.279127)
					(mid 0.152481 0.169693)
					(end 1.255279 -0.431435)
					(width 0.2)
				)
				(gr_arc
					(start -0.529126 1.279127)
					(mid 0.087542 0.105784)
					(end 1.253811 -0.524161)
					(width 0.2)
				)
				(gr_arc
					(start -0.621807 1.279127)
					(mid 0.0309 0.033527)
					(end 1.275473 -0.621136)
					(width 0.2)
				)
				(gr_arc
					(start -0.71437 1.279127)
					(mid -0.037758 -0.026651)
					(end 1.263664 -0.711602)
					(width 0.2)
				)
				(gr_arc
					(start -0.806826 1.279127)
					(mid -0.105837 -0.087395)
					(end 1.253435 -0.802342)
					(width 0.2)
				)
				(gr_arc
					(start -0.899187 1.279127)
					(mid -0.165236 -0.156885)
					(end 1.267475 -0.897258)
					(width 0.2)
				)
				(gr_arc
					(start -0.991463 1.279127)
					(mid -0.228522 -0.222449)
					(end 1.270645 -0.990112)
					(width 0.2)
				)
				(gr_arc
					(start -1.083663 1.279127)
					(mid -0.294507 -0.285313)
					(end 1.266278 -1.081674)
					(width 0.2)
				)
				(gr_line
					(start 1.279127 -0.250195)
					(end 1.279127 -1.083663)
					(width 0.2)
				)
				(gr_line
					(start -0.250195 1.279127)
					(end -1.083663 1.279127)
					(width 0.2)
				)
			)
		)
		(pad "" smd custom
			(at 1.7 1.7 180)
			(size 0.62 0.62)
			(layers "F.Paste")
			(thermal_bridge_angle 90)
			(options
				(clearance outline)
				(anchor circle)
			)
			(primitives
				(gr_arc
					(start -0.250195 1.279127)
					(mid 0.285453 0.294389)
					(end 1.266786 -0.24747)
					(width 0.2)
				)
				(gr_arc
					(start -0.34334 1.279127)
					(mid 0.218448 0.232561)
					(end 1.259603 -0.339191)
					(width 0.2)
				)
				(gr_arc
					(start -0.436309 1.279127)
					(mid 0.152481 0.169693)
					(end 1.255279 -0.431435)
					(width 0.2)
				)
				(gr_arc
					(start -0.529126 1.279127)
					(mid 0.087542 0.105784)
					(end 1.253811 -0.524161)
					(width 0.2)
				)
				(gr_arc
					(start -0.621807 1.279127)
					(mid 0.0309 0.033527)
					(end 1.275473 -0.621136)
					(width 0.2)
				)
				(gr_arc
					(start -0.71437 1.279127)
					(mid -0.037758 -0.026651)
					(end 1.263664 -0.711602)
					(width 0.2)
				)
				(gr_arc
					(start -0.806826 1.279127)
					(mid -0.105837 -0.087395)
					(end 1.253435 -0.802342)
					(width 0.2)
				)
				(gr_arc
					(start -0.899187 1.279127)
					(mid -0.165236 -0.156885)
					(end 1.267475 -0.897258)
					(width 0.2)
				)
				(gr_arc
					(start -0.991463 1.279127)
					(mid -0.228522 -0.222449)
					(end 1.270645 -0.990112)
					(width 0.2)
				)
				(gr_arc
					(start -1.083663 1.279127)
					(mid -0.294507 -0.285313)
					(end 1.266278 -1.081674)
					(width 0.2)
				)
				(gr_line
					(start 1.279127 -0.250195)
					(end 1.279127 -1.083663)
					(width 0.2)
				)
				(gr_line
					(start -0.250195 1.279127)
					(end -1.083663 1.279127)
					(width 0.2)
				)
			)
		)
		(pad "1" thru_hole circle
			(at 0 0)
			(size 6 6)
			(drill 3.7)
			(layers "*.Cu" "*.Mask")
			(remove_unused_layers no)
			(net 1 "GND")
			(pintype "passive")
		)
	)
	(footprint "antmicro-footprints:Module_Jetson-Orin-NX-Nano"
		(layer "F.Cu")
		(at 92.742 98.588)
		(descr "Jetson Orin NX series and Jetson Orin Nano")
		(tags "Jetson Orin NX Nano")
		(property "Reference" "M1"
			(at 0 0 0)
			(layer "F.SilkS")
			(hide yes)
			(effects
				(font
					(size 0.7 0.7)
					(thickness 0.15)
				)
				(justify left bottom)
			)
		)
		(property "Value" "Jetson-Orin-NX-Nano"
			(at 0 1.2 0)
			(layer "F.Fab")
			(effects
				(font
					(size 0.7 0.7)
					(thickness 0.15)
				)
				(justify left bottom)
			)
		)
		(property "Footprint" "antmicro-footprints:Module_Jetson-Orin-NX-Nano"
			(at 0 0 0)
			(layer "F.Fab")
			(hide yes)
			(effects
				(font
					(size 1.27 1.27)
					(thickness 0.15)
				)
			)
		)
		(property "Datasheet" "https://static6.arrow.com/aropdfconversion/c4902ff7fe8bae4b5d563d5e41c1cfab77501490/jetson-orin-nx-datasheet-nvidia-us-web-2605318-5.pdf"
			(at 0 0 0)
			(layer "F.Fab")
			(hide yes)
			(effects
				(font
					(size 1.27 1.27)
					(thickness 0.15)
				)
			)
		)
		(property "Author" "Antmicro"
			(at 0 0 0)
			(layer "F.Fab")
			(hide yes)
			(effects
				(font
					(size 1 1)
					(thickness 0.15)
				)
			)
		)
		(property "Displayed name" "Jetson Orin NX Nano"
			(at 0 0 0)
			(layer "F.Fab")
			(hide yes)
			(effects
				(font
					(size 1 1)
					(thickness 0.15)
				)
			)
		)
		(property "License" "Apache-2.0"
			(at 0 0 0)
			(layer "F.Fab")
			(hide yes)
			(effects
				(font
					(size 1 1)
					(thickness 0.15)
				)
			)
		)
		(property "MPN" "900-13767-0000-000"
			(at 0 0 0)
			(layer "F.Fab")
			(hide yes)
			(effects
				(font
					(size 1 1)
					(thickness 0.15)
				)
			)
		)
		(property "Manufacturer" "Nvidia"
			(at 0 0 0)
			(layer "F.Fab")
			(hide yes)
			(effects
				(font
					(size 1 1)
					(thickness 0.15)
				)
			)
		)
		(sheetname "SoM")
		(sheetfile "som.kicad_sch")
		(attr exclude_from_pos_files exclude_from_bom dnp)
		(fp_text user "${REFERENCE}"
			(at -35.8 25.5 0)
			(layer "F.Fab")
			(hide yes)
			(effects
				(font
					(size 0.7 0.7)
					(thickness 0.15)
				)
				(justify left bottom)
			)
		)
		(fp_text user "Author: Antmicro"
			(at -35.8 26.7 0)
			(layer "F.Fab")
			(hide yes)
			(effects
				(font
					(size 0.7 0.7)
					(thickness 0.15)
				)
				(justify left bottom)
			)
		)
		(fp_text user "License: Apache-2.0"
			(at -35.8 27.9 0)
			(layer "F.Fab")
			(hide yes)
			(effects
				(font
					(size 0.7 0.7)
					(thickness 0.15)
				)
				(justify left bottom)
			)
		)
	)
	(footprint "antmicro-footprints:R_0402_1005Metric"
		(layer "F.Cu")
		(at 56.1 109.25 -90)
		(descr "Resistor SMD 0402")
		(tags "resistor SMD 0402")
		(property "Reference" "R250"
			(at 1.725 0.575 -90)
			(layer "F.SilkS")
			(effects
				(font
					(size 0.7 0.7)
					(thickness 0.15)
				)
				(justify left bottom)
			)
		)
		(property "Value" "R_10k_0402"
			(at 0 1.4 -90)
			(layer "F.Fab")
			(effects
				(font
					(size 0.7 0.7)
					(thickness 0.15)
				)
				(justify left bottom)
			)
		)
		(property "Footprint" "antmicro-footprints:R_0402_1005Metric"
			(at 0 0 -90)
			(layer "F.Fab")
			(hide yes)
			(effects
				(font
					(size 1.27 1.27)
					(thickness 0.15)
				)
			)
		)
		(property "Datasheet" "https://www.bourns.com/docs/product-datasheets/cr.pdf"
			(at 0 0 -90)
			(layer "F.Fab")
			(hide yes)
			(effects
				(font
					(size 1.27 1.27)
					(thickness 0.15)
				)
			)
		)
		(property "Author" "Antmicro"
			(at -53.15 165.35 0)
			(layer "F.Fab")
			(hide yes)
			(effects
				(font
					(size 1 1)
					(thickness 0.15)
				)
			)
		)
		(property "License" "Apache-2.0"
			(at -53.15 165.35 0)
			(layer "F.Fab")
			(hide yes)
			(effects
				(font
					(size 1 1)
					(thickness 0.15)
				)
			)
		)
		(property "MPN" "CR0402-FX-1002GLF"
			(at -53.15 165.35 0)
			(layer "F.Fab")
			(hide yes)
			(effects
				(font
					(size 1 1)
					(thickness 0.15)
				)
			)
		)
		(property "Manufacturer" "Bourns"
			(at -53.15 165.35 0)
			(layer "F.Fab")
			(hide yes)
			(effects
				(font
					(size 1 1)
					(thickness 0.15)
				)
			)
		)
		(property "Tolerance" "1%"
			(at -53.15 165.35 0)
			(layer "F.Fab")
			(hide yes)
			(effects
				(font
					(size 1 1)
					(thickness 0.15)
				)
			)
		)
		(property "Val" "10k"
			(at -53.15 165.35 0)
			(layer "F.Fab")
			(hide yes)
			(effects
				(font
					(size 1 1)
					(thickness 0.15)
				)
			)
		)
		(sheetname "Supply")
		(sheetfile "supply.kicad_sch")
		(attr smd)
		(fp_rect
			(start -0.925 -0.47)
			(end 0.925 0.47)
			(stroke
				(width 0.05)
				(type default)
			)
			(fill none)
			(layer "F.CrtYd")
		)
		(fp_rect
			(start -0.5 -0.25)
			(end 0.5 0.25)
			(stroke
				(width 0.15)
				(type solid)
			)
			(fill none)
			(layer "F.Fab")
		)
		(fp_text user "Author: Antmicro"
			(at -0.95 4.169 -90)
			(layer "F.Fab")
			(hide yes)
			(effects
				(font
					(size 0.7 0.7)
					(thickness 0.15)
				)
				(justify left bottom)
			)
		)
		(fp_text user "${REFERENCE}"
			(at -0.95 3.168 -90)
			(layer "F.Fab")
			(hide yes)
			(effects
				(font
					(size 0.7 0.7)
					(thickness 0.15)
				)
				(justify left bottom)
			)
		)
		(fp_text user "License: Apache-2.0"
			(at -0.95 5.169 -90)
			(layer "F.Fab")
			(hide yes)
			(effects
				(font
					(size 0.7 0.7)
					(thickness 0.15)
				)
				(justify left bottom)
			)
		)
		(pad "1" smd roundrect
			(at -0.48 0 270)
			(size 0.59 0.64)
			(layers "F.Cu" "F.Paste" "F.Mask")
			(roundrect_rratio 0.25)
			(net 1 "GND")
			(pintype "passive")
		)
		(pad "2" smd roundrect
			(at 0.48 0 270)
			(size 0.59 0.64)
			(layers "F.Cu" "F.Paste" "F.Mask")
			(roundrect_rratio 0.25)
			(net 717 "Net-(Q13-Pad2)")
			(pintype "passive")
		)
	)
	(footprint "antmicro-footprints:SOT-523"
		(layer "F.Cu")
		(at 92.85 93.9 180)
		(property "Reference" "Q3"
			(at -2.05 -0.68 -90)
			(layer "F.SilkS")
			(effects
				(font
					(size 0.7 0.7)
					(thickness 0.15)
				)
				(justify left bottom)
			)
		)
		(property "Value" "PJE138K"
			(at 0.1 1.824 180)
			(layer "F.Fab")
			(effects
				(font
					(size 0.7 0.7)
					(thickness 0.15)
				)
				(justify left bottom)
			)
		)
		(property "Footprint" "antmicro-footprints:SOT-523"
			(at 0 0 180)
			(layer "F.Fab")
			(hide yes)
			(effects
				(font
					(size 1.27 1.27)
					(thickness 0.15)
				)
			)
		)
		(property "Datasheet" "https://www.mouser.com/datasheet/2/1057/PJE138K-1876698.pdf"
			(at 0 0 180)
			(layer "F.Fab")
			(hide yes)
			(effects
				(font
					(size 1.27 1.27)
					(thickness 0.15)
				)
			)
		)
		(property "Author" "Antmicro"
			(at 185.7 187.8 0)
			(layer "F.Fab")
			(hide yes)
			(effects
				(font
					(size 1 1)
					(thickness 0.15)
				)
			)
		)
		(property "License" "Apache-2.0"
			(at 185.7 187.8 0)
			(layer "F.Fab")
			(hide yes)
			(effects
				(font
					(size 1 1)
					(thickness 0.15)
				)
			)
		)
		(property "MPN" "PJE138K_R1_00001"
			(at 185.7 187.8 0)
			(layer "F.Fab")
			(hide yes)
			(effects
				(font
					(size 1 1)
					(thickness 0.15)
				)
			)
		)
		(property "Manufacturer" "PANJIT"
			(at 185.7 187.8 0)
			(layer "F.Fab")
			(hide yes)
			(effects
				(font
					(size 1 1)
					(thickness 0.15)
				)
			)
		)
		(sheetname "HDMI")
		(sheetfile "hdmi.kicad_sch")
		(attr smd exclude_from_pos_files exclude_from_bom dnp)
		(fp_line
			(start -0.277 -0.551)
			(end -0.277 -0.75)
			(stroke
				(width 0.15)
				(type solid)
			)
			(layer "F.SilkS")
		)
		(fp_line
			(start -0.725 -0.551)
			(end -0.277 -0.551)
			(stroke
				(width 0.15)
				(type solid)
			)
			(layer "F.SilkS")
		)
		(fp_line
			(start -0.927 -0.051)
			(end -0.927 -0.351)
			(stroke
				(width 0.15)
				(type solid)
			)
			(layer "F.SilkS")
		)
		(fp_line
			(start -0.927 -0.351)
			(end -0.725 -0.551)
			(stroke
				(width 0.15)
				(type solid)
			)
			(layer "F.SilkS")
		)
		(fp_circle
			(center -0.9652 0.9652)
			(end -0.9152 0.9652)
			(stroke
				(width 0.15)
				(type solid)
			)
			(fill solid)
			(layer "F.SilkS")
		)
		(fp_line
			(start 1.1 -1.16)
			(end 1.1 1.15)
			(stroke
				(width 0.05)
				(type solid)
			)
			(layer "F.CrtYd")
		)
		(fp_line
			(start -1.12 1.15)
			(end 1.1 1.15)
			(stroke
				(width 0.05)
				(type solid)
			)
			(layer "F.CrtYd")
		)
		(fp_line
			(start -1.12 -1.16)
			(end 1.1 -1.16)
			(stroke
				(width 0.05)
				(type solid)
			)
			(layer "F.CrtYd")
		)
		(fp_line
			(start -1.12 -1.16)
			(end -1.12 1.15)
			(stroke
				(width 0.05)
				(type solid)
			)
			(layer "F.CrtYd")
		)
		(fp_line
			(start 0.8 0.424)
			(end -0.802 0.424)
			(stroke
				(width 0.15)
				(type solid)
			)
			(layer "F.Fab")
		)
		(fp_line
			(start 0.8 -0.425)
			(end 0.8 0.424)
			(stroke
				(width 0.15)
				(type solid)
			)
			(layer "F.Fab")
		)
		(fp_line
			(start 0.8 -0.425)
			(end -0.652 -0.425)
			(stroke
				(width 0.15)
				(type solid)
			)
			(layer "F.Fab")
		)
		(fp_line
			(start -0.652 -0.425)
			(end -0.802 -0.276)
			(stroke
				(width 0.15)
				(type solid)
			)
			(layer "F.Fab")
		)
		(fp_line
			(start -0.802 -0.276)
			(end -0.802 0.424)
			(stroke
				(width 0.15)
				(type solid)
			)
			(layer "F.Fab")
		)
		(fp_circle
			(center -0.9652 0.9652)
			(end -0.9144 0.9652)
			(stroke
				(width 0.15)
				(type solid)
			)
			(fill none)
			(layer "F.Fab")
		)
		(fp_text user "${REFERENCE}"
			(at -1.12 3.824 180)
			(layer "F.Fab")
			(hide yes)
			(effects
				(font
					(size 0.7 0.7)
					(thickness 0.15)
				)
				(justify left bottom)
			)
		)
		(fp_text user "License: Apache-2.0"
			(at -1.12 5.024 180)
			(layer "F.Fab")
			(hide yes)
			(effects
				(font
					(size 0.7 0.7)
					(thickness 0.15)
				)
				(justify left bottom)
			)
		)
		(fp_text user "Author: Antmicro"
			(at -1.12 6.224 180)
			(layer "F.Fab")
			(hide yes)
			(effects
				(font
					(size 0.7 0.7)
					(thickness 0.15)
				)
				(justify left bottom)
			)
		)
		(pad "1" smd rect
			(at -0.5 0.65 180)
			(size 0.4 0.51)
			(layers "F.Cu" "F.Paste" "F.Mask")
			(net 677 "USBC_HPD")
			(pinfunction "G")
			(pintype "passive")
		)
		(pad "2" smd rect
			(at 0.498 0.65 180)
			(size 0.4 0.51)
			(layers "F.Cu" "F.Paste" "F.Mask")
			(net 1 "GND")
			(pinfunction "S")
			(pintype "passive")
		)
		(pad "3" smd rect
			(at 0 -0.652 180)
			(size 0.4 0.51)
			(layers "F.Cu" "F.Paste" "F.Mask")
			(net 624 "Net-(Q3-D)")
			(pinfunction "D")
			(pintype "passive")
		)
	)
	(footprint "antmicro-footprints:TP_SMD_0.75mm"
		(layer "F.Cu")
		(at 104.1 82.25)
		(property "Reference" "TP35"
			(at 0.225 0.425 0)
			(layer "F.SilkS")
			(effects
				(font
					(size 0.7 0.7)
					(thickness 0.15)
				)
				(justify left bottom)
			)
		)
		(property "Value" "TP_0.75mm_SMD"
			(at 0 1.2 0)
			(layer "F.Fab")
			(effects
				(font
					(size 0.7 0.7)
					(thickness 0.15)
				)
				(justify left bottom)
			)
		)
		(property "Footprint" "antmicro-footprints:TP_SMD_0.75mm"
			(at 0 0 0)
			(layer "F.Fab")
			(hide yes)
			(effects
				(font
					(size 1.27 1.27)
					(thickness 0.15)
				)
			)
		)
		(property "Author" "Antmicro"
			(at 0 0 0)
			(layer "F.Fab")
			(hide yes)
			(effects
				(font
					(size 1 1)
					(thickness 0.15)
				)
			)
		)
		(property "License" "Apache-2.0"
			(at 0 0 0)
			(layer "F.Fab")
			(hide yes)
			(effects
				(font
					(size 1 1)
					(thickness 0.15)
				)
			)
		)
		(property "MPN" ""
			(at 0 0 0)
			(layer "F.Fab")
			(hide yes)
			(effects
				(font
					(size 1 1)
					(thickness 0.15)
				)
			)
		)
		(property "Manufacturer" ""
			(at 0 0 0)
			(layer "F.Fab")
			(hide yes)
			(effects
				(font
					(size 1 1)
					(thickness 0.15)
				)
			)
		)
		(sheetname "SoM")
		(sheetfile "som.kicad_sch")
		(attr exclude_from_pos_files exclude_from_bom)
		(fp_circle
			(center 0 0)
			(end 0.475 0)
			(stroke
				(width 0.05)
				(type default)
			)
			(fill none)
			(layer "F.CrtYd")
		)
		(fp_text user "License: Apache-2.0"
			(at -0.4 5.101 0)
			(layer "F.Fab")
			(hide yes)
			(effects
				(font
					(size 0.7 0.7)
					(thickness 0.15)
				)
				(justify left bottom)
			)
		)
		(fp_text user "Author: Antmicro"
			(at -0.4 3.901 0)
			(layer "F.Fab")
			(hide yes)
			(effects
				(font
					(size 0.7 0.7)
					(thickness 0.15)
				)
				(justify left bottom)
			)
		)
		(fp_text user "${REFERENCE}"
			(at -0.4 2.7 0)
			(layer "F.Fab")
			(hide yes)
			(effects
				(font
					(size 0.7 0.7)
					(thickness 0.15)
				)
				(justify left bottom)
			)
		)
		(pad "1" smd circle
			(at 0 0)
			(size 0.75 0.75)
			(layers "F.Cu" "F.Mask")
			(net 742 "Net-(J15E-HDMI_CEC)")
			(pinfunction "1")
			(pintype "passive")
		)
	)
	(footprint "antmicro-footprints:XDFN-2_1x0.60mm"
		(layer "F.Cu")
		(at 130.19 123.34 90)
		(property "Reference" "D56"
			(at 0.69 -1.24 -90)
			(layer "F.SilkS")
			(effects
				(font
					(size 0.7 0.7)
					(thickness 0.15)
				)
				(justify left bottom)
			)
		)
		(property "Value" "TPD1E0B04_XDFN-2"
			(at 0 1.5 90)
			(layer "F.Fab")
			(effects
				(font
					(size 0.7 0.7)
					(thickness 0.15)
				)
				(justify left bottom)
			)
		)
		(property "Footprint" "antmicro-footprints:XDFN-2_1x0.60mm"
			(at 0 0 90)
			(layer "F.Fab")
			(hide yes)
			(effects
				(font
					(size 1.27 1.27)
					(thickness 0.15)
				)
			)
		)
		(property "Datasheet" "https://www.ti.com/general/docs/suppproductinfo.tsp?distId=26&gotoUrl=https://www.ti.com/lit/gpn/tpd1e0b04"
			(at 0 0 90)
			(layer "F.Fab")
			(hide yes)
			(effects
				(font
					(size 1.27 1.27)
					(thickness 0.15)
				)
			)
		)
		(property "MPN" "TPD1E0B04DPYR"
			(at 253.53 -6.85 0)
			(layer "F.Fab")
			(hide yes)
			(effects
				(font
					(size 1 1)
					(thickness 0.15)
				)
			)
		)
		(property "Manufacturer" "Texas Instruments"
			(at 253.53 -6.85 0)
			(layer "F.Fab")
			(hide yes)
			(effects
				(font
					(size 1 1)
					(thickness 0.15)
				)
			)
		)
		(property "Author" "Antmicro"
			(at 253.53 -6.85 0)
			(layer "F.Fab")
			(hide yes)
			(effects
				(font
					(size 1 1)
					(thickness 0.15)
				)
			)
		)
		(property "License" "Apache-2.0"
			(at 253.53 -6.85 0)
			(layer "F.Fab")
			(hide yes)
			(effects
				(font
					(size 1 1)
					(thickness 0.15)
				)
			)
		)
		(sheetname "Peripherals")
		(sheetfile "peripherals.kicad_sch")
		(attr smd)
		(fp_rect
			(start -0.725 -0.475)
			(end 0.725 0.475)
			(stroke
				(width 0.05)
				(type solid)
			)
			(fill none)
			(layer "F.CrtYd")
		)
		(fp_rect
			(start -0.55 -0.35)
			(end 0.55 0.35)
			(stroke
				(width 0.15)
				(type solid)
			)
			(fill none)
			(layer "F.Fab")
		)
		(fp_text user "${REFERENCE}"
			(at -0.8 3.2 90)
			(layer "F.Fab")
			(hide yes)
			(effects
				(font
					(size 0.7 0.7)
					(thickness 0.15)
				)
				(justify left bottom)
			)
		)
		(fp_text user "License: Apache-2.0"
			(at -0.8 5.6 90)
			(layer "F.Fab")
			(hide yes)
			(effects
				(font
					(size 0.7 0.7)
					(thickness 0.15)
				)
				(justify left bottom)
			)
		)
		(fp_text user "Author: Antmicro"
			(at -0.8 4.4 90)
			(layer "F.Fab")
			(hide yes)
			(effects
				(font
					(size 0.7 0.7)
					(thickness 0.15)
				)
				(justify left bottom)
			)
		)
		(pad "1" smd roundrect
			(at -0.351 0 90)
			(size 0.3 0.5)
			(layers "F.Cu" "F.Paste" "F.Mask")
			(roundrect_rratio 0.25)
			(net 1 "GND")
			(pinfunction "C")
			(pintype "passive")
		)
		(pad "2" smd roundrect
			(at 0.349 0 90)
			(size 0.3 0.5)
			(layers "F.Cu" "F.Paste" "F.Mask")
			(roundrect_rratio 0.25)
			(net 659 "I2C1_SCL")
			(pinfunction "A")
			(pintype "passive")
		)
	)
	(footprint "antmicro-footprints:SOD-923"
		(layer "F.Cu")
		(at 53.725 117.4 180)
		(property "Reference" "D28"
			(at 2.75 -0.425 0)
			(unlocked yes)
			(layer "F.SilkS")
			(effects
				(font
					(size 0.7 0.7)
					(thickness 0.15)
				)
				(justify left bottom)
			)
		)
		(property "Value" "DF2S30FS_SOD"
			(at 0 1.3 180)
			(unlocked yes)
			(layer "F.Fab")
			(effects
				(font
					(size 0.7 0.7)
					(thickness 0.15)
				)
				(justify left bottom)
			)
		)
		(property "Footprint" "antmicro-footprints:SOD-923"
			(at 0 0 180)
			(layer "F.Fab")
			(hide yes)
			(effects
				(font
					(size 1.27 1.27)
					(thickness 0.15)
				)
			)
		)
		(property "Datasheet" "https://toshiba.semicon-storage.com/info/DF2S30FS_datasheet_en_20211216.pdf?did=11156&prodName=DF2S30FS"
			(at 0 0 180)
			(layer "F.Fab")
			(hide yes)
			(effects
				(font
					(size 1.27 1.27)
					(thickness 0.15)
				)
			)
		)
		(property "Author" "Antmicro"
			(at 107.45 234.8 0)
			(layer "F.Fab")
			(hide yes)
			(effects
				(font
					(size 1 1)
					(thickness 0.15)
				)
			)
		)
		(property "License" "Apache-2.0"
			(at 107.45 234.8 0)
			(layer "F.Fab")
			(hide yes)
			(effects
				(font
					(size 1 1)
					(thickness 0.15)
				)
			)
		)
		(property "MPN" "DF2S30FS"
			(at 107.45 234.8 0)
			(layer "F.Fab")
			(hide yes)
			(effects
				(font
					(size 1 1)
					(thickness 0.15)
				)
			)
		)
		(property "Manufacturer" "Toshiba"
			(at 107.45 234.8 0)
			(layer "F.Fab")
			(hide yes)
			(effects
				(font
					(size 1 1)
					(thickness 0.15)
				)
			)
		)
		(sheetname "Supply")
		(sheetfile "supply.kicad_sch")
		(attr smd)
		(fp_line
			(start 0.5 0.4)
			(end 0.5 0.3)
			(stroke
				(width 0.15)
				(type solid)
			)
			(layer "F.SilkS")
		)
		(fp_line
			(start 0.5 -0.4)
			(end 0.5 -0.3)
			(stroke
				(width 0.15)
				(type solid)
			)
			(layer "F.SilkS")
		)
		(fp_line
			(start -0.16 -0.4)
			(end -0.16 0.4)
			(stroke
				(width 0.15)
				(type solid)
			)
			(layer "F.SilkS")
		)
		(fp_line
			(start -0.5 0.4)
			(end 0.5 0.4)
			(stroke
				(width 0.15)
				(type solid)
			)
			(layer "F.SilkS")
		)
		(fp_line
			(start -0.5 0.4)
			(end -0.5 0.3)
			(stroke
				(width 0.15)
				(type solid)
			)
			(layer "F.SilkS")
		)
		(fp_line
			(start -0.5 -0.3)
			(end -0.5 -0.4)
			(stroke
				(width 0.15)
				(type solid)
			)
			(layer "F.SilkS")
		)
		(fp_line
			(start -0.5 -0.4)
			(end 0.5 -0.4)
			(stroke
				(width 0.15)
				(type solid)
			)
			(layer "F.SilkS")
		)
		(fp_rect
			(start -0.68 -0.41)
			(end 0.68 0.41)
			(stroke
				(width 0.05)
				(type solid)
			)
			(fill none)
			(layer "F.CrtYd")
		)
		(fp_line
			(start -0.202 -0.3)
			(end -0.202 0.298)
			(stroke
				(width 0.15)
				(type solid)
			)
			(layer "F.Fab")
		)
		(fp_rect
			(start -0.402 -0.3)
			(end 0.4 0.298)
			(stroke
				(width 0.15)
				(type solid)
			)
			(fill none)
			(layer "F.Fab")
		)
		(fp_text user "License: Apache-2.0"
			(at -0.68 4.5 180)
			(layer "F.Fab")
			(hide yes)
			(effects
				(font
					(size 0.7 0.7)
					(thickness 0.15)
				)
				(justify left bottom)
			)
		)
		(fp_text user "Author: Antmicro"
			(at -0.68 5.7 180)
			(layer "F.Fab")
			(hide yes)
			(effects
				(font
					(size 0.7 0.7)
					(thickness 0.15)
				)
				(justify left bottom)
			)
		)
		(fp_text user "${REFERENCE}"
			(at -0.68 3.3 180)
			(unlocked yes)
			(layer "F.Fab")
			(hide yes)
			(effects
				(font
					(size 0.7 0.7)
					(thickness 0.15)
				)
				(justify left bottom)
			)
		)
		(pad "1" smd roundrect
			(at -0.438 0 180)
			(size 0.4 0.325)
			(layers "F.Cu" "F.Paste" "F.Mask")
			(roundrect_rratio 0.25)
			(net 189 "Net-(D28-C)")
			(pinfunction "C")
			(pintype "passive")
		)
		(pad "2" smd roundrect
			(at 0.436 0 180)
			(size 0.4 0.325)
			(layers "F.Cu" "F.Paste" "F.Mask")
			(roundrect_rratio 0.25)
			(net 1 "GND")
			(pinfunction "A")
			(pintype "passive")
		)
	)
	(footprint "antmicro-footprints:R_0402_1005Metric"
		(layer "F.Cu")
		(at 79.23 85.88 90)
		(descr "Resistor SMD 0402")
		(tags "resistor SMD 0402")
		(property "Reference" "R177"
			(at 0.71 0.41 90)
			(layer "F.SilkS")
			(effects
				(font
					(size 0.7 0.7)
					(thickness 0.15)
				)
				(justify left bottom)
			)
		)
		(property "Value" "R_45k3_0402"
			(at -1.011843 1.772047 90)
			(layer "F.Fab")
			(effects
				(font
					(size 0.7 0.7)
					(thickness 0.15)
				)
				(justify left bottom)
			)
		)
		(property "Footprint" "antmicro-footprints:R_0402_1005Metric"
			(at 0 0 90)
			(layer "F.Fab")
			(hide yes)
			(effects
				(font
					(size 1.27 1.27)
					(thickness 0.15)
				)
			)
		)
		(property "Datasheet" "https://www.bourns.com/docs/product-datasheets/cr.pdf"
			(at 0 0 90)
			(layer "F.Fab")
			(hide yes)
			(effects
				(font
					(size 1.27 1.27)
					(thickness 0.15)
				)
			)
		)
		(property "Author" "Antmicro"
			(at 165.11 6.65 0)
			(layer "F.Fab")
			(hide yes)
			(effects
				(font
					(size 1 1)
					(thickness 0.15)
				)
			)
		)
		(property "License" "Apache-2.0"
			(at 165.11 6.65 0)
			(layer "F.Fab")
			(hide yes)
			(effects
				(font
					(size 1 1)
					(thickness 0.15)
				)
			)
		)
		(property "MPN" "CR0402-FX-4532GLF"
			(at 165.11 6.65 0)
			(layer "F.Fab")
			(hide yes)
			(effects
				(font
					(size 1 1)
					(thickness 0.15)
				)
			)
		)
		(property "Manufacturer" "Bourns"
			(at 165.11 6.65 0)
			(layer "F.Fab")
			(hide yes)
			(effects
				(font
					(size 1 1)
					(thickness 0.15)
				)
			)
		)
		(property "Tolerance" "1%"
			(at 165.11 6.65 0)
			(layer "F.Fab")
			(hide yes)
			(effects
				(font
					(size 1 1)
					(thickness 0.15)
				)
			)
		)
		(property "Val" "45k3"
			(at 165.11 6.65 0)
			(layer "F.Fab")
			(hide yes)
			(effects
				(font
					(size 1 1)
					(thickness 0.15)
				)
			)
		)
		(sheetname "Supply")
		(sheetfile "supply.kicad_sch")
		(attr smd)
		(fp_rect
			(start -0.925 -0.47)
			(end 0.925 0.47)
			(stroke
				(width 0.05)
				(type default)
			)
			(fill none)
			(layer "F.CrtYd")
		)
		(fp_rect
			(start -0.5 -0.25)
			(end 0.5 0.25)
			(stroke
				(width 0.15)
				(type solid)
			)
			(fill none)
			(layer "F.Fab")
		)
		(fp_text user "License: Apache-2.0"
			(at -0.95 5.169 90)
			(layer "F.Fab")
			(hide yes)
			(effects
				(font
					(size 0.7 0.7)
					(thickness 0.15)
				)
				(justify left bottom)
			)
		)
		(fp_text user "Author: Antmicro"
			(at -0.95 4.169 90)
			(layer "F.Fab")
			(hide yes)
			(effects
				(font
					(size 0.7 0.7)
					(thickness 0.15)
				)
				(justify left bottom)
			)
		)
		(fp_text user "${REFERENCE}"
			(at -0.95 3.168 90)
			(layer "F.Fab")
			(hide yes)
			(effects
				(font
					(size 0.7 0.7)
					(thickness 0.15)
				)
				(justify left bottom)
			)
		)
		(pad "1" smd roundrect
			(at -0.48 0 90)
			(size 0.59 0.64)
			(layers "F.Cu" "F.Paste" "F.Mask")
			(roundrect_rratio 0.25)
			(net 711 "/Supply/3V3_FB")
			(pintype "passive")
		)
		(pad "2" smd roundrect
			(at 0.48 0 90)
			(size 0.59 0.64)
			(layers "F.Cu" "F.Paste" "F.Mask")
			(roundrect_rratio 0.25)
			(net 641 "/Supply/3V3_OUT")
			(pintype "passive")
		)
	)
	(footprint "antmicro-footprints:C_0402_1005Metric"
		(layer "F.Cu")
		(at 127.05 94.2 180)
		(descr "Capacitor SMD 0402")
		(tags "capacitor SMD 0402")
		(property "Reference" "C9"
			(at 0.7 0.4 180)
			(layer "F.SilkS")
			(effects
				(font
					(size 0.7 0.7)
					(thickness 0.15)
				)
				(justify left bottom)
			)
		)
		(property "Value" "C_220n_0402"
			(at 0 1.4 180)
			(layer "F.Fab")
			(effects
				(font
					(size 0.7 0.7)
					(thickness 0.15)
				)
				(justify left bottom)
			)
		)
		(property "Footprint" "antmicro-footprints:C_0402_1005Metric"
			(at 0 0 180)
			(layer "F.Fab")
			(hide yes)
			(effects
				(font
					(size 1.27 1.27)
					(thickness 0.15)
				)
			)
		)
		(property "Datasheet" "https://www.yageo.com/en/Chart/Download/pdf/CC0402KRX5R6BB224"
			(at 0 0 180)
			(layer "F.Fab")
			(hide yes)
			(effects
				(font
					(size 1.27 1.27)
					(thickness 0.15)
				)
			)
		)
		(property "Author" "Antmicro"
			(at 254.1 188.4 0)
			(layer "F.Fab")
			(hide yes)
			(effects
				(font
					(size 1 1)
					(thickness 0.15)
				)
			)
		)
		(property "Dielectric" ""
			(at 254.1 188.4 0)
			(layer "F.Fab")
			(hide yes)
			(effects
				(font
					(size 1 1)
					(thickness 0.15)
				)
			)
		)
		(property "License" "Apache-2.0"
			(at 254.1 188.4 0)
			(layer "F.Fab")
			(hide yes)
			(effects
				(font
					(size 1 1)
					(thickness 0.15)
				)
			)
		)
		(property "MPN" "CC0402KRX5R6BB224"
			(at 254.1 188.4 0)
			(layer "F.Fab")
			(hide yes)
			(effects
				(font
					(size 1 1)
					(thickness 0.15)
				)
			)
		)
		(property "Manufacturer" "YAGEO"
			(at 254.1 188.4 0)
			(layer "F.Fab")
			(hide yes)
			(effects
				(font
					(size 1 1)
					(thickness 0.15)
				)
			)
		)
		(property "Val" "220n"
			(at 254.1 188.4 0)
			(layer "F.Fab")
			(hide yes)
			(effects
				(font
					(size 1 1)
					(thickness 0.15)
				)
			)
		)
		(property "Voltage" ""
			(at 254.1 188.4 0)
			(layer "F.Fab")
			(hide yes)
			(effects
				(font
					(size 1 1)
					(thickness 0.15)
				)
			)
		)
		(sheetname "M.2")
		(sheetfile "m-2.kicad_sch")
		(attr smd)
		(fp_rect
			(start -0.925 -0.47)
			(end 0.925 0.47)
			(stroke
				(width 0.05)
				(type default)
			)
			(fill none)
			(layer "F.CrtYd")
		)
		(fp_line
			(start 0.504 0.248)
			(end -0.494 0.248)
			(stroke
				(width 0.15)
				(type solid)
			)
			(layer "F.Fab")
		)
		(fp_line
			(start 0.504 -0.25)
			(end 0.504 0.248)
			(stroke
				(width 0.15)
				(type solid)
			)
			(layer "F.Fab")
		)
		(fp_line
			(start -0.494 0.248)
			(end -0.494 -0.25)
			(stroke
				(width 0.15)
				(type solid)
			)
			(layer "F.Fab")
		)
		(fp_line
			(start -0.494 -0.25)
			(end 0.504 -0.25)
			(stroke
				(width 0.15)
				(type solid)
			)
			(layer "F.Fab")
		)
		(fp_text user "License: Apache-2.0"
			(at -0.932 5.17 180)
			(layer "F.Fab")
			(hide yes)
			(effects
				(font
					(size 0.7 0.7)
					(thickness 0.15)
				)
				(justify left bottom)
			)
		)
		(fp_text user "Author: Antmicro"
			(at -0.932 4.17 180)
			(layer "F.Fab")
			(hide yes)
			(effects
				(font
					(size 0.7 0.7)
					(thickness 0.15)
				)
				(justify left bottom)
			)
		)
		(fp_text user "${REFERENCE}"
			(at -0.932 3.168 180)
			(layer "F.Fab")
			(hide yes)
			(effects
				(font
					(size 0.7 0.7)
					(thickness 0.15)
				)
				(justify left bottom)
			)
		)
		(pad "1" smd roundrect
			(at -0.48 0 180)
			(size 0.59 0.64)
			(layers "F.Cu" "F.Paste" "F.Mask")
			(roundrect_rratio 0.25)
			(net 451 "PCIE1_TX0_P")
			(pintype "passive")
		)
		(pad "2" smd roundrect
			(at 0.48 0 180)
			(size 0.59 0.64)
			(layers "F.Cu" "F.Paste" "F.Mask")
			(roundrect_rratio 0.25)
			(net 96 "/M.2/C_PCIE1_TX0_P")
			(pintype "passive")
		)
	)
	(footprint "antmicro-footprints:USON-10_2.5x1mm_P0.5mm"
		(layer "F.Cu")
		(at 93.625 119.9 90)
		(descr "USON-10 2.5x1mm_ Pitch 0.5mm")
		(tags "USON-10 2.5x1mm Pitch 0.5mm")
		(property "Reference" "U45"
			(at -0.1 5.425 -90)
			(layer "F.SilkS")
			(effects
				(font
					(size 0.7 0.7)
					(thickness 0.15)
				)
				(justify left bottom)
			)
		)
		(property "Value" "TPD4E05U06QDQARQ1"
			(at 0.018 2.499 90)
			(layer "F.Fab")
			(effects
				(font
					(size 0.7 0.7)
					(thickness 0.15)
				)
				(justify left bottom)
			)
		)
		(property "Footprint" "antmicro-footprints:USON-10_2.5x1mm_P0.5mm"
			(at 0 0 90)
			(layer "F.Fab")
			(hide yes)
			(effects
				(font
					(size 1.27 1.27)
					(thickness 0.15)
				)
			)
		)
		(property "Datasheet" "https://www.ti.com/lit/ds/symlink/tpd4e05u06-q1.pdf?HQS=dis-mous-null-mousermode-dsf-pf-null-wwe&ts=1663591265741&ref_url=https%253A%252F%252Fwww.mouser.com%252F"
			(at 0 0 90)
			(layer "F.Fab")
			(hide yes)
			(effects
				(font
					(size 1.27 1.27)
					(thickness 0.15)
				)
			)
		)
		(property "Author" "Antmicro"
			(at 213.525 26.275 0)
			(layer "F.Fab")
			(hide yes)
			(effects
				(font
					(size 1 1)
					(thickness 0.15)
				)
			)
		)
		(property "License" "Apache-2.0"
			(at 213.525 26.275 0)
			(layer "F.Fab")
			(hide yes)
			(effects
				(font
					(size 1 1)
					(thickness 0.15)
				)
			)
		)
		(property "MPN" "TPD4E05U06QDQARQ1"
			(at 213.525 26.275 0)
			(layer "F.Fab")
			(hide yes)
			(effects
				(font
					(size 1 1)
					(thickness 0.15)
				)
			)
		)
		(property "Manufacturer" "Texas Instruments"
			(at 213.525 26.275 0)
			(layer "F.Fab")
			(hide yes)
			(effects
				(font
					(size 1 1)
					(thickness 0.15)
				)
			)
		)
		(sheetname "HDMI")
		(sheetfile "hdmi.kicad_sch")
		(attr smd)
		(fp_line
			(start 0.498 -1.401)
			(end -0.5 -1.401)
			(stroke
				(width 0.15)
				(type solid)
			)
			(layer "F.SilkS")
		)
		(fp_line
			(start 0.498 1.398)
			(end -0.5 1.398)
			(stroke
				(width 0.15)
				(type solid)
			)
			(layer "F.SilkS")
		)
		(fp_circle
			(center -0.68 -1.27)
			(end -0.63 -1.27)
			(stroke
				(width 0.15)
				(type solid)
			)
			(fill solid)
			(layer "F.SilkS")
		)
		(fp_rect
			(start -0.8 -1.5)
			(end 0.8 1.499)
			(stroke
				(width 0.05)
				(type solid)
			)
			(fill none)
			(layer "F.CrtYd")
		)
		(fp_line
			(start 0.498 -1.25)
			(end -0.25 -1.25)
			(stroke
				(width 0.15)
				(type solid)
			)
			(layer "F.Fab")
		)
		(fp_line
			(start 0.498 -1.25)
			(end 0.498 1.249)
			(stroke
				(width 0.15)
				(type solid)
			)
			(layer "F.Fab")
		)
		(fp_line
			(start -0.25 -1.25)
			(end -0.5 -1)
			(stroke
				(width 0.15)
				(type solid)
			)
			(layer "F.Fab")
		)
		(fp_line
			(start -0.5 -1)
			(end -0.5 1.249)
			(stroke
				(width 0.15)
				(type solid)
			)
			(layer "F.Fab")
		)
		(fp_line
			(start -0.5 1.249)
			(end 0.498 1.249)
			(stroke
				(width 0.15)
				(type solid)
			)
			(layer "F.Fab")
		)
		(fp_text user "License: Apache-2.0"
			(at -0.802 6.9 90)
			(layer "F.Fab")
			(hide yes)
			(effects
				(font
					(size 0.7 0.7)
					(thickness 0.15)
				)
				(justify left bottom)
			)
		)
		(fp_text user "Author: Antmicro"
			(at -0.802 5.7 90)
			(layer "F.Fab")
			(hide yes)
			(effects
				(font
					(size 0.7 0.7)
					(thickness 0.15)
				)
				(justify left bottom)
			)
		)
		(fp_text user "${REFERENCE}"
			(at -0.802 4.498 90)
			(layer "F.Fab")
			(hide yes)
			(effects
				(font
					(size 0.7 0.7)
					(thickness 0.15)
				)
				(justify left bottom)
			)
		)
		(pad "1" smd roundrect
			(at -0.387 -1)
			(size 0.25 0.55)
			(layers "F.Cu" "F.Paste" "F.Mask")
			(roundrect_rratio 0.25)
			(net 521 "/HDMI/HDMI_CLK_CONN_N")
			(pintype "passive")
		)
		(pad "2" smd roundrect
			(at -0.387 -0.5)
			(size 0.25 0.55)
			(layers "F.Cu" "F.Paste" "F.Mask")
			(roundrect_rratio 0.25)
			(net 522 "/HDMI/HDMI_CLK_CONN_P")
			(pintype "passive")
		)
		(pad "3" smd roundrect
			(at -0.387 0)
			(size 0.4 0.55)
			(layers "F.Cu" "F.Paste" "F.Mask")
			(roundrect_rratio 0.25)
			(net 1 "GND")
			(pintype "power_in")
		)
		(pad "4" smd roundrect
			(at -0.387 0.498)
			(size 0.25 0.55)
			(layers "F.Cu" "F.Paste" "F.Mask")
			(roundrect_rratio 0.25)
			(net 523 "/HDMI/HDMI_D0_CONN_N")
			(pintype "passive")
		)
		(pad "5" smd roundrect
			(at -0.387 0.998)
			(size 0.25 0.55)
			(layers "F.Cu" "F.Paste" "F.Mask")
			(roundrect_rratio 0.25)
			(net 524 "/HDMI/HDMI_D0_CONN_P")
			(pintype "passive")
		)
		(pad "6" smd roundrect
			(at 0.385 0.998)
			(size 0.25 0.55)
			(layers "F.Cu" "F.Paste" "F.Mask")
			(roundrect_rratio 0.25)
			(net 524 "/HDMI/HDMI_D0_CONN_P")
			(pintype "passive")
		)
		(pad "7" smd roundrect
			(at 0.385 0.498)
			(size 0.25 0.55)
			(layers "F.Cu" "F.Paste" "F.Mask")
			(roundrect_rratio 0.25)
			(net 523 "/HDMI/HDMI_D0_CONN_N")
			(pintype "passive")
		)
		(pad "8" smd roundrect
			(at 0.385 0)
			(size 0.4 0.55)
			(layers "F.Cu" "F.Paste" "F.Mask")
			(roundrect_rratio 0.25)
			(net 1 "GND")
			(pintype "passive")
		)
		(pad "9" smd roundrect
			(at 0.385 -0.5)
			(size 0.25 0.55)
			(layers "F.Cu" "F.Paste" "F.Mask")
			(roundrect_rratio 0.25)
			(net 522 "/HDMI/HDMI_CLK_CONN_P")
			(pintype "passive")
		)
		(pad "10" smd roundrect
			(at 0.385 -1)
			(size 0.25 0.55)
			(layers "F.Cu" "F.Paste" "F.Mask")
			(roundrect_rratio 0.25)
			(net 521 "/HDMI/HDMI_CLK_CONN_N")
			(pintype "passive")
		)
	)
	(footprint "antmicro-footprints:TP_SMD_0.75mm"
		(layer "F.Cu")
		(at 65.48 122.485)
		(property "Reference" "TP28"
			(at 0.45 -0.42 90)
			(layer "F.SilkS")
			(effects
				(font
					(size 0.7 0.7)
					(thickness 0.15)
				)
				(justify left bottom)
			)
		)
		(property "Value" "TP_0.75mm_SMD"
			(at 0 1.2 0)
			(layer "F.Fab")
			(effects
				(font
					(size 0.7 0.7)
					(thickness 0.15)
				)
				(justify left bottom)
			)
		)
		(property "Footprint" "antmicro-footprints:TP_SMD_0.75mm"
			(at 0 0 0)
			(layer "F.Fab")
			(hide yes)
			(effects
				(font
					(size 1.27 1.27)
					(thickness 0.15)
				)
			)
		)
		(property "Author" "Antmicro"
			(at 0 0 0)
			(layer "F.Fab")
			(hide yes)
			(effects
				(font
					(size 1 1)
					(thickness 0.15)
				)
			)
		)
		(property "License" "Apache-2.0"
			(at 0 0 0)
			(layer "F.Fab")
			(hide yes)
			(effects
				(font
					(size 1 1)
					(thickness 0.15)
				)
			)
		)
		(property "MPN" ""
			(at 0 0 0)
			(layer "F.Fab")
			(hide yes)
			(effects
				(font
					(size 1 1)
					(thickness 0.15)
				)
			)
		)
		(property "Manufacturer" ""
			(at 0 0 0)
			(layer "F.Fab")
			(hide yes)
			(effects
				(font
					(size 1 1)
					(thickness 0.15)
				)
			)
		)
		(sheetname "USB Debug, DP")
		(sheetfile "usb.kicad_sch")
		(attr exclude_from_pos_files exclude_from_bom)
		(fp_circle
			(center 0 0)
			(end 0.475 0)
			(stroke
				(width 0.05)
				(type default)
			)
			(fill none)
			(layer "F.CrtYd")
		)
		(fp_text user "License: Apache-2.0"
			(at -0.4 5.101 0)
			(layer "F.Fab")
			(hide yes)
			(effects
				(font
					(size 0.7 0.7)
					(thickness 0.15)
				)
				(justify left bottom)
			)
		)
		(fp_text user "${REFERENCE}"
			(at -0.4 2.7 0)
			(layer "F.Fab")
			(hide yes)
			(effects
				(font
					(size 0.7 0.7)
					(thickness 0.15)
				)
				(justify left bottom)
			)
		)
		(fp_text user "Author: Antmicro"
			(at -0.4 3.901 0)
			(layer "F.Fab")
			(hide yes)
			(effects
				(font
					(size 0.7 0.7)
					(thickness 0.15)
				)
				(justify left bottom)
			)
		)
		(pad "1" smd circle
			(at 0 0)
			(size 0.75 0.75)
			(layers "F.Cu" "F.Mask")
			(net 692 "Net-(U10-CAD_SNK{slash}RSVD1)")
			(pinfunction "1")
			(pintype "passive")
		)
	)
	(footprint "antmicro-footprints:C_0402_1005Metric"
		(layer "F.Cu")
		(at 78.62 110.34 -90)
		(descr "Capacitor SMD 0402")
		(tags "capacitor SMD 0402")
		(property "Reference" "C37"
			(at 1.11 -1.33 -90)
			(layer "F.SilkS")
			(effects
				(font
					(size 0.7 0.7)
					(thickness 0.15)
				)
				(justify left bottom)
			)
		)
		(property "Value" "C_100n_0402"
			(at 0 1.4 -90)
			(layer "F.Fab")
			(effects
				(font
					(size 0.7 0.7)
					(thickness 0.15)
				)
				(justify left bottom)
			)
		)
		(property "Footprint" "antmicro-footprints:C_0402_1005Metric"
			(at 0 0 -90)
			(layer "F.Fab")
			(hide yes)
			(effects
				(font
					(size 1.27 1.27)
					(thickness 0.15)
				)
			)
		)
		(property "Datasheet" "https://www.murata.com/products/productdetail?partno=GRM155R61H104KE14%23"
			(at 0 0 -90)
			(layer "F.Fab")
			(hide yes)
			(effects
				(font
					(size 1.27 1.27)
					(thickness 0.15)
				)
			)
		)
		(property "Author" "Antmicro"
			(at -31.72 188.96 0)
			(layer "F.Fab")
			(hide yes)
			(effects
				(font
					(size 1 1)
					(thickness 0.15)
				)
			)
		)
		(property "Dielectric" "X5R"
			(at -31.72 188.96 0)
			(layer "F.Fab")
			(hide yes)
			(effects
				(font
					(size 1 1)
					(thickness 0.15)
				)
			)
		)
		(property "License" "Apache-2.0"
			(at -31.72 188.96 0)
			(layer "F.Fab")
			(hide yes)
			(effects
				(font
					(size 1 1)
					(thickness 0.15)
				)
			)
		)
		(property "MPN" "GRM155R61H104KE14D"
			(at -31.72 188.96 0)
			(layer "F.Fab")
			(hide yes)
			(effects
				(font
					(size 1 1)
					(thickness 0.15)
				)
			)
		)
		(property "Manufacturer" "Murata"
			(at -31.72 188.96 0)
			(layer "F.Fab")
			(hide yes)
			(effects
				(font
					(size 1 1)
					(thickness 0.15)
				)
			)
		)
		(property "Val" "100n"
			(at -31.72 188.96 0)
			(layer "F.Fab")
			(hide yes)
			(effects
				(font
					(size 1 1)
					(thickness 0.15)
				)
			)
		)
		(property "Voltage" "50V"
			(at -31.72 188.96 0)
			(layer "F.Fab")
			(hide yes)
			(effects
				(font
					(size 1 1)
					(thickness 0.15)
				)
			)
		)
		(sheetname "USB Debug, DP")
		(sheetfile "usb.kicad_sch")
		(attr smd)
		(fp_rect
			(start -0.925 -0.47)
			(end 0.925 0.47)
			(stroke
				(width 0.05)
				(type default)
			)
			(fill none)
			(layer "F.CrtYd")
		)
		(fp_line
			(start -0.494 0.248)
			(end -0.494 -0.25)
			(stroke
				(width 0.15)
				(type solid)
			)
			(layer "F.Fab")
		)
		(fp_line
			(start 0.504 0.248)
			(end -0.494 0.248)
			(stroke
				(width 0.15)
				(type solid)
			)
			(layer "F.Fab")
		)
		(fp_line
			(start -0.494 -0.25)
			(end 0.504 -0.25)
			(stroke
				(width 0.15)
				(type solid)
			)
			(layer "F.Fab")
		)
		(fp_line
			(start 0.504 -0.25)
			(end 0.504 0.248)
			(stroke
				(width 0.15)
				(type solid)
			)
			(layer "F.Fab")
		)
		(fp_text user "License: Apache-2.0"
			(at -0.932 5.17 -90)
			(layer "F.Fab")
			(hide yes)
			(effects
				(font
					(size 0.7 0.7)
					(thickness 0.15)
				)
				(justify left bottom)
			)
		)
		(fp_text user "${REFERENCE}"
			(at -0.932 3.168 -90)
			(layer "F.Fab")
			(hide yes)
			(effects
				(font
					(size 0.7 0.7)
					(thickness 0.15)
				)
				(justify left bottom)
			)
		)
		(fp_text user "Author: Antmicro"
			(at -0.932 4.17 -90)
			(layer "F.Fab")
			(hide yes)
			(effects
				(font
					(size 0.7 0.7)
					(thickness 0.15)
				)
				(justify left bottom)
			)
		)
		(pad "1" smd roundrect
			(at -0.48 0 270)
			(size 0.59 0.64)
			(layers "F.Cu" "F.Paste" "F.Mask")
			(roundrect_rratio 0.25)
			(net 87 "+3V3")
			(pintype "passive")
		)
		(pad "2" smd roundrect
			(at 0.48 0 270)
			(size 0.59 0.64)
			(layers "F.Cu" "F.Paste" "F.Mask")
			(roundrect_rratio 0.25)
			(net 1 "GND")
			(pintype "passive")
		)
	)
	(footprint "antmicro-footprints:C_0402_1005Metric"
		(layer "F.Cu")
		(at 74.07 89.44 -90)
		(descr "Capacitor SMD 0402")
		(tags "capacitor SMD 0402")
		(property "Reference" "C121"
			(at -3.63 -0.4 90)
			(layer "F.SilkS")
			(effects
				(font
					(size 0.7 0.7)
					(thickness 0.15)
				)
				(justify right bottom)
			)
		)
		(property "Value" "C_100n_0402"
			(at -1.022927 2.155213 90)
			(layer "F.Fab")
			(effects
				(font
					(size 0.7 0.7)
					(thickness 0.15)
				)
				(justify right bottom)
			)
		)
		(property "Footprint" "antmicro-footprints:C_0402_1005Metric"
			(at 0 0 -90)
			(layer "F.Fab")
			(hide yes)
			(effects
				(font
					(size 1.27 1.27)
					(thickness 0.15)
				)
			)
		)
		(property "Datasheet" "https://www.murata.com/products/productdetail?partno=GRM155R61H104KE14%23"
			(at 0 0 -90)
			(layer "F.Fab")
			(hide yes)
			(effects
				(font
					(size 1.27 1.27)
					(thickness 0.15)
				)
			)
		)
		(property "Author" "Antmicro"
			(at -15.37 163.51 0)
			(layer "F.Fab")
			(hide yes)
			(effects
				(font
					(size 1 1)
					(thickness 0.15)
				)
			)
		)
		(property "Dielectric" "X5R"
			(at -15.37 163.51 0)
			(layer "F.Fab")
			(hide yes)
			(effects
				(font
					(size 1 1)
					(thickness 0.15)
				)
			)
		)
		(property "License" "Apache-2.0"
			(at -15.37 163.51 0)
			(layer "F.Fab")
			(hide yes)
			(effects
				(font
					(size 1 1)
					(thickness 0.15)
				)
			)
		)
		(property "MPN" "GRM155R61H104KE14D"
			(at -15.37 163.51 0)
			(layer "F.Fab")
			(hide yes)
			(effects
				(font
					(size 1 1)
					(thickness 0.15)
				)
			)
		)
		(property "Manufacturer" "Murata"
			(at -15.37 163.51 0)
			(layer "F.Fab")
			(hide yes)
			(effects
				(font
					(size 1 1)
					(thickness 0.15)
				)
			)
		)
		(property "Val" "100n"
			(at -15.37 163.51 0)
			(layer "F.Fab")
			(hide yes)
			(effects
				(font
					(size 1 1)
					(thickness 0.15)
				)
			)
		)
		(property "Voltage" "50V"
			(at -15.37 163.51 0)
			(layer "F.Fab")
			(hide yes)
			(effects
				(font
					(size 1 1)
					(thickness 0.15)
				)
			)
		)
		(sheetname "Supply")
		(sheetfile "supply.kicad_sch")
		(attr smd)
		(fp_rect
			(start -0.925 -0.47)
			(end 0.925 0.47)
			(stroke
				(width 0.05)
				(type default)
			)
			(fill none)
			(layer "F.CrtYd")
		)
		(fp_line
			(start -0.494 0.248)
			(end -0.494 -0.25)
			(stroke
				(width 0.15)
				(type solid)
			)
			(layer "F.Fab")
		)
		(fp_line
			(start 0.504 0.248)
			(end -0.494 0.248)
			(stroke
				(width 0.15)
				(type solid)
			)
			(layer "F.Fab")
		)
		(fp_line
			(start -0.494 -0.25)
			(end 0.504 -0.25)
			(stroke
				(width 0.15)
				(type solid)
			)
			(layer "F.Fab")
		)
		(fp_line
			(start 0.504 -0.25)
			(end 0.504 0.248)
			(stroke
				(width 0.15)
				(type solid)
			)
			(layer "F.Fab")
		)
		(fp_text user "License: Apache-2.0"
			(at -0.939 5.799 90)
			(layer "F.Fab")
			(hide yes)
			(effects
				(font
					(size 0.7 0.7)
					(thickness 0.15)
				)
				(justify right bottom)
			)
		)
		(fp_text user "Author: Antmicro"
			(at -0.939 3.399 90)
			(layer "F.Fab")
			(hide yes)
			(effects
				(font
					(size 0.7 0.7)
					(thickness 0.15)
				)
				(justify right bottom)
			)
		)
		(fp_text user "${REFERENCE}"
			(at -0.939 4.599 90)
			(layer "F.Fab")
			(hide yes)
			(effects
				(font
					(size 0.7 0.7)
					(thickness 0.15)
				)
				(justify right bottom)
			)
		)
		(pad "1" smd roundrect
			(at -0.48 0 270)
			(size 0.59 0.64)
			(layers "F.Cu" "F.Paste" "F.Mask")
			(roundrect_rratio 0.25)
			(net 115 "VCC")
			(pintype "passive")
		)
		(pad "2" smd roundrect
			(at 0.48 0 270)
			(size 0.59 0.64)
			(layers "F.Cu" "F.Paste" "F.Mask")
			(roundrect_rratio 0.25)
			(net 1 "GND")
			(pintype "passive")
		)
	)
	(footprint "antmicro-footprints:FB_0805_2012Metric"
		(layer "F.Cu")
		(at 86.25 117.95)
		(descr "FERRITE BEAD 0805")
		(tags "FERRITE BEAD 0805")
		(property "Reference" "FB4"
			(at -1.575 -0.8 0)
			(layer "F.SilkS")
			(effects
				(font
					(size 0.6 0.6)
					(thickness 0.15)
				)
				(justify left bottom)
			)
		)
		(property "Value" "FB_220Z_2A_Murata-BLM21PG_0805"
			(at 0 1.8 0)
			(layer "F.Fab")
			(effects
				(font
					(size 0.7 0.7)
					(thickness 0.15)
				)
				(justify left bottom)
			)
		)
		(property "Footprint" "antmicro-footprints:FB_0805_2012Metric"
			(at 0 0 0)
			(layer "F.Fab")
			(hide yes)
			(effects
				(font
					(size 1.27 1.27)
					(thickness 0.15)
				)
			)
		)
		(property "Datasheet" "https://www.murata.com/products/productdata/8796738977822/ENFA0005.pdf?1653276712000"
			(at 0 0 0)
			(layer "F.Fab")
			(hide yes)
			(effects
				(font
					(size 1.27 1.27)
					(thickness 0.15)
				)
			)
		)
		(property "Author" "Antmicro"
			(at 0 0 0)
			(layer "F.Fab")
			(hide yes)
			(effects
				(font
					(size 1 1)
					(thickness 0.15)
				)
			)
		)
		(property "Current" ""
			(at 0 0 0)
			(layer "F.Fab")
			(hide yes)
			(effects
				(font
					(size 1 1)
					(thickness 0.15)
				)
			)
		)
		(property "License" "Apache-2.0"
			(at 0 0 0)
			(layer "F.Fab")
			(hide yes)
			(effects
				(font
					(size 1 1)
					(thickness 0.15)
				)
			)
		)
		(property "MPN" "BLM21PG221SN1D"
			(at 0 0 0)
			(layer "F.Fab")
			(hide yes)
			(effects
				(font
					(size 1 1)
					(thickness 0.15)
				)
			)
		)
		(property "Manufacturer" "Murata"
			(at 0 0 0)
			(layer "F.Fab")
			(hide yes)
			(effects
				(font
					(size 1 1)
					(thickness 0.15)
				)
			)
		)
		(property "Val" "220Z/2A"
			(at 0 0 0)
			(layer "F.Fab")
			(hide yes)
			(effects
				(font
					(size 1 1)
					(thickness 0.15)
				)
			)
		)
		(sheetname "HDMI")
		(sheetfile "hdmi.kicad_sch")
		(attr smd)
		(fp_line
			(start -0.319 0.698)
			(end 0.281 0.698)
			(stroke
				(width 0.15)
				(type solid)
			)
			(layer "F.SilkS")
		)
		(fp_line
			(start -0.299 -0.698)
			(end 0.299 -0.698)
			(stroke
				(width 0.15)
				(type solid)
			)
			(layer "F.SilkS")
		)
		(fp_rect
			(start 1.95 -0.9)
			(end -1.95 0.9)
			(stroke
				(width 0.05)
				(type default)
			)
			(fill none)
			(layer "F.CrtYd")
		)
		(fp_line
			(start -0.948 -0.681)
			(end 0.948 -0.681)
			(stroke
				(width 0.15)
				(type solid)
			)
			(layer "F.Fab")
		)
		(fp_line
			(start -0.948 -0.676)
			(end -0.948 0.676)
			(stroke
				(width 0.15)
				(type solid)
			)
			(layer "F.Fab")
		)
		(fp_line
			(start -0.948 0.681)
			(end 0.948 0.681)
			(stroke
				(width 0.15)
				(type solid)
			)
			(layer "F.Fab")
		)
		(fp_line
			(start 0.948 -0.676)
			(end 0.948 0.676)
			(stroke
				(width 0.15)
				(type solid)
			)
			(layer "F.Fab")
		)
		(fp_text user "License: Apache-2.0"
			(at -1.9 5.75 0)
			(layer "F.Fab")
			(hide yes)
			(effects
				(font
					(size 0.7 0.7)
					(thickness 0.15)
				)
				(justify left bottom)
			)
		)
		(fp_text user "Author: Antmicro"
			(at -1.9 4.4 0)
			(layer "F.Fab")
			(hide yes)
			(effects
				(font
					(size 0.7 0.7)
					(thickness 0.15)
				)
				(justify left bottom)
			)
		)
		(fp_text user "${REFERENCE}"
			(at -1.9 3.1 0)
			(layer "F.Fab")
			(hide yes)
			(effects
				(font
					(size 0.7 0.7)
					(thickness 0.15)
				)
				(justify left bottom)
			)
		)
		(pad "1" smd roundrect
			(at -1.1 0)
			(size 1.2 1.3)
			(layers "F.Cu" "F.Paste" "F.Mask")
			(roundrect_rratio 0.25)
			(net 99 "+5V")
			(pintype "passive")
		)
		(pad "2" smd roundrect
			(at 1.1 0)
			(size 1.2 1.3)
			(layers "F.Cu" "F.Paste" "F.Mask")
			(roundrect_rratio 0.25)
			(net 424 "Net-(D38-A)")
			(pintype "passive")
		)
	)
	(footprint "antmicro-footprints:SW_KMR211NGLFS_SMD"
		(layer "F.Cu")
		(at 122.9 125.9 180)
		(property "Reference" "S2"
			(at 2.25 2.03 180)
			(layer "F.SilkS")
			(effects
				(font
					(size 0.7 0.7)
					(thickness 0.15)
				)
				(justify left bottom)
			)
		)
		(property "Value" "SW_KMR211NGLFS_SMD"
			(at -3 3 180)
			(layer "F.Fab")
			(effects
				(font
					(size 0.7 0.7)
					(thickness 0.15)
				)
				(justify left bottom)
			)
		)
		(property "Footprint" "antmicro-footprints:SW_KMR211NGLFS_SMD"
			(at 0 0 180)
			(layer "F.Fab")
			(hide yes)
			(effects
				(font
					(size 1.27 1.27)
					(thickness 0.15)
				)
			)
		)
		(property "Datasheet" "http://www.farnell.com/datasheets/2631211.pdf"
			(at 0 0 180)
			(layer "F.Fab")
			(hide yes)
			(effects
				(font
					(size 1.27 1.27)
					(thickness 0.15)
				)
			)
		)
		(property "Author" "Antmicro"
			(at 245.8 251.8 0)
			(layer "F.Fab")
			(hide yes)
			(effects
				(font
					(size 1 1)
					(thickness 0.15)
				)
			)
		)
		(property "License" "Apache-2.0"
			(at 245.8 251.8 0)
			(layer "F.Fab")
			(hide yes)
			(effects
				(font
					(size 1 1)
					(thickness 0.15)
				)
			)
		)
		(property "MPN" "KMR211NGLFS"
			(at 245.8 251.8 0)
			(layer "F.Fab")
			(hide yes)
			(effects
				(font
					(size 1 1)
					(thickness 0.15)
				)
			)
		)
		(property "Manufacturer" "C&K"
			(at 245.8 251.8 0)
			(layer "F.Fab")
			(hide yes)
			(effects
				(font
					(size 1 1)
					(thickness 0.15)
				)
			)
		)
		(sheetname "Peripherals")
		(sheetfile "peripherals.kicad_sch")
		(attr smd)
		(fp_line
			(start 2.101 1.601)
			(end 2.101 1.48)
			(stroke
				(width 0.15)
				(type solid)
			)
			(layer "F.SilkS")
		)
		(fp_line
			(start 2.101 1.601)
			(end -2.1 1.601)
			(stroke
				(width 0.15)
				(type solid)
			)
			(layer "F.SilkS")
		)
		(fp_line
			(start 2.101 -1.58)
			(end 2.101 -1.459)
			(stroke
				(width 0.15)
				(type solid)
			)
			(layer "F.SilkS")
		)
		(fp_line
			(start 2.101 -1.6)
			(end -2.1 -1.6)
			(stroke
				(width 0.15)
				(type solid)
			)
			(layer "F.SilkS")
		)
		(fp_line
			(start -2.1 1.601)
			(end -2.1 1.48)
			(stroke
				(width 0.15)
				(type solid)
			)
			(layer "F.SilkS")
		)
		(fp_line
			(start -2.1 -1.6)
			(end -2.1 -1.499)
			(stroke
				(width 0.15)
				(type solid)
			)
			(layer "F.SilkS")
		)
		(fp_rect
			(start 2.751 1.75)
			(end -2.748 -1.749)
			(stroke
				(width 0.05)
				(type solid)
			)
			(fill none)
			(layer "F.CrtYd")
		)
		(fp_line
			(start 2.101 1.601)
			(end 2.101 -1.6)
			(stroke
				(width 0.15)
				(type solid)
			)
			(layer "F.Fab")
		)
		(fp_line
			(start 2.101 -1.6)
			(end -2.1 -1.6)
			(stroke
				(width 0.15)
				(type solid)
			)
			(layer "F.Fab")
		)
		(fp_line
			(start 0.25 0.802)
			(end -0.248 0.802)
			(stroke
				(width 0.15)
				(type solid)
			)
			(layer "F.Fab")
		)
		(fp_line
			(start -0.248 -0.8)
			(end 0.25 -0.8)
			(stroke
				(width 0.15)
				(type solid)
			)
			(layer "F.Fab")
		)
		(fp_line
			(start -2.1 1.601)
			(end 2.101 1.601)
			(stroke
				(width 0.15)
				(type solid)
			)
			(layer "F.Fab")
		)
		(fp_line
			(start -2.1 -1.6)
			(end -2.1 1.601)
			(stroke
				(width 0.15)
				(type solid)
			)
			(layer "F.Fab")
		)
		(fp_arc
			(start 0.25 -0.8)
			(mid 1.051001 0.001)
			(end 0.25 0.802)
			(stroke
				(width 0.15)
				(type solid)
			)
			(layer "F.Fab")
		)
		(fp_arc
			(start -0.248 0.802)
			(mid -1.050001 0.001)
			(end -0.248 -0.8)
			(stroke
				(width 0.15)
				(type solid)
			)
			(layer "F.Fab")
		)
		(fp_text user "${REFERENCE}"
			(at -3 4.25 180)
			(layer "F.Fab")
			(hide yes)
			(effects
				(font
					(size 0.7 0.7)
					(thickness 0.15)
				)
				(justify left bottom)
			)
		)
		(fp_text user "License: Apache-2.0"
			(at -3 6.75 180)
			(layer "F.Fab")
			(hide yes)
			(effects
				(font
					(size 0.7 0.7)
					(thickness 0.15)
				)
				(justify left bottom)
			)
		)
		(fp_text user "Author: Antmicro"
			(at -3 5.5 180)
			(layer "F.Fab")
			(hide yes)
			(effects
				(font
					(size 0.7 0.7)
					(thickness 0.15)
				)
				(justify left bottom)
			)
		)
		(pad "1" smd rect
			(at -2.048 -0.8)
			(size 0.9 1)
			(layers "F.Cu" "F.Paste" "F.Mask")
			(net 45 "USER_BTN0")
			(pinfunction "1")
			(pintype "passive")
		)
		(pad "2" smd rect
			(at 2.05 -0.8)
			(size 0.9 1)
			(layers "F.Cu" "F.Paste" "F.Mask")
			(net 45 "USER_BTN0")
			(pinfunction "2")
			(pintype "passive")
		)
		(pad "3" smd rect
			(at -2.048 0.802)
			(size 0.9 1)
			(layers "F.Cu" "F.Paste" "F.Mask")
			(net 1 "GND")
			(pinfunction "3")
			(pintype "passive")
		)
		(pad "4" smd rect
			(at 2.05 0.802)
			(size 0.9 1)
			(layers "F.Cu" "F.Paste" "F.Mask")
			(net 1 "GND")
			(pinfunction "4")
			(pintype "passive")
		)
	)
	(footprint "antmicro-footprints:R_0402_1005Metric"
		(layer "F.Cu")
		(at 105.154938 110)
		(descr "Resistor SMD 0402")
		(tags "resistor SMD 0402")
		(property "Reference" "R200"
			(at -3.654938 0.4 0)
			(layer "F.SilkS")
			(effects
				(font
					(size 0.7 0.7)
					(thickness 0.15)
				)
				(justify left bottom)
			)
		)
		(property "Value" "R_0R_0402"
			(at 0 1.4 0)
			(layer "F.Fab")
			(effects
				(font
					(size 0.7 0.7)
					(thickness 0.15)
				)
				(justify left bottom)
			)
		)
		(property "Footprint" "antmicro-footprints:R_0402_1005Metric"
			(at 0 0 0)
			(layer "F.Fab")
			(hide yes)
			(effects
				(font
					(size 1.27 1.27)
					(thickness 0.15)
				)
			)
		)
		(property "Datasheet" "https://industrial.panasonic.com/cdbs/www-data/pdf/RDA0000/AOA0000C301.pdf"
			(at 0 0 0)
			(layer "F.Fab")
			(hide yes)
			(effects
				(font
					(size 1.27 1.27)
					(thickness 0.15)
				)
			)
		)
		(property "Author" "Antmicro"
			(at 0 0 0)
			(layer "F.Fab")
			(hide yes)
			(effects
				(font
					(size 1 1)
					(thickness 0.15)
				)
			)
		)
		(property "Current" "1A"
			(at 0 0 0)
			(layer "F.Fab")
			(hide yes)
			(effects
				(font
					(size 1 1)
					(thickness 0.15)
				)
			)
		)
		(property "License" "Apache-2.0"
			(at 0 0 0)
			(layer "F.Fab")
			(hide yes)
			(effects
				(font
					(size 1 1)
					(thickness 0.15)
				)
			)
		)
		(property "MPN" "ERJ2GE0R00X"
			(at 0 0 0)
			(layer "F.Fab")
			(hide yes)
			(effects
				(font
					(size 1 1)
					(thickness 0.15)
				)
			)
		)
		(property "Manufacturer" "Panasonic"
			(at 0 0 0)
			(layer "F.Fab")
			(hide yes)
			(effects
				(font
					(size 1 1)
					(thickness 0.15)
				)
			)
		)
		(property "Tolerance" ""
			(at 0 0 0)
			(layer "F.Fab")
			(hide yes)
			(effects
				(font
					(size 1 1)
					(thickness 0.15)
				)
			)
		)
		(property "Val" "0R"
			(at 0 0 0)
			(layer "F.Fab")
			(hide yes)
			(effects
				(font
					(size 1 1)
					(thickness 0.15)
				)
			)
		)
		(sheetname "USB3")
		(sheetfile "usb3.kicad_sch")
		(attr smd)
		(fp_rect
			(start -0.925 -0.47)
			(end 0.925 0.47)
			(stroke
				(width 0.05)
				(type default)
			)
			(fill none)
			(layer "F.CrtYd")
		)
		(fp_rect
			(start -0.5 -0.25)
			(end 0.5 0.25)
			(stroke
				(width 0.15)
				(type solid)
			)
			(fill none)
			(layer "F.Fab")
		)
		(fp_text user "License: Apache-2.0"
			(at -0.95 5.169 0)
			(layer "F.Fab")
			(hide yes)
			(effects
				(font
					(size 0.7 0.7)
					(thickness 0.15)
				)
				(justify left bottom)
			)
		)
		(fp_text user "${REFERENCE}"
			(at -0.95 3.168 0)
			(layer "F.Fab")
			(hide yes)
			(effects
				(font
					(size 0.7 0.7)
					(thickness 0.15)
				)
				(justify left bottom)
			)
		)
		(fp_text user "Author: Antmicro"
			(at -0.95 4.169 0)
			(layer "F.Fab")
			(hide yes)
			(effects
				(font
					(size 0.7 0.7)
					(thickness 0.15)
				)
				(justify left bottom)
			)
		)
		(pad "1" smd roundrect
			(at -0.48 0)
			(size 0.59 0.64)
			(layers "F.Cu" "F.Paste" "F.Mask")
			(roundrect_rratio 0.25)
			(net 165 "USBSS2_RX_P")
			(pintype "passive")
		)
		(pad "2" smd roundrect
			(at 0.48 0)
			(size 0.59 0.64)
			(layers "F.Cu" "F.Paste" "F.Mask")
			(roundrect_rratio 0.25)
			(net 609 "/USB3/USBSS1_C_RX_N")
			(pintype "passive")
		)
	)
	(footprint "antmicro-footprints:C_0402_1005Metric"
		(layer "F.Cu")
		(at 148 112.79)
		(descr "Capacitor SMD 0402")
		(tags "capacitor SMD 0402")
		(property "Reference" "C114"
			(at -1.21 5.51 0)
			(layer "F.SilkS")
			(effects
				(font
					(size 0.7 0.7)
					(thickness 0.15)
				)
				(justify left bottom)
			)
		)
		(property "Value" "C_1u_0402"
			(at 0 1.4 0)
			(layer "F.Fab")
			(effects
				(font
					(size 0.7 0.7)
					(thickness 0.15)
				)
				(justify left bottom)
			)
		)
		(property "Footprint" "antmicro-footprints:C_0402_1005Metric"
			(at 0 0 0)
			(layer "F.Fab")
			(hide yes)
			(effects
				(font
					(size 1.27 1.27)
					(thickness 0.15)
				)
			)
		)
		(property "Datasheet" "https://product.tdk.com/en/search/capacitor/ceramic/mlcc/info?part_no=C1005X6S1A105K050BC"
			(at 0 0 0)
			(layer "F.Fab")
			(hide yes)
			(effects
				(font
					(size 1.27 1.27)
					(thickness 0.15)
				)
			)
		)
		(property "Author" "Antmicro"
			(at 0 0 0)
			(layer "F.Fab")
			(hide yes)
			(effects
				(font
					(size 1 1)
					(thickness 0.15)
				)
			)
		)
		(property "Dielectric" ""
			(at 0 0 0)
			(layer "F.Fab")
			(hide yes)
			(effects
				(font
					(size 1 1)
					(thickness 0.15)
				)
			)
		)
		(property "License" "Apache-2.0"
			(at 0 0 0)
			(layer "F.Fab")
			(hide yes)
			(effects
				(font
					(size 1 1)
					(thickness 0.15)
				)
			)
		)
		(property "MPN" "C1005X6S1A105K050BC"
			(at 0 0 0)
			(layer "F.Fab")
			(hide yes)
			(effects
				(font
					(size 1 1)
					(thickness 0.15)
				)
			)
		)
		(property "Manufacturer" "TDK"
			(at 0 0 0)
			(layer "F.Fab")
			(hide yes)
			(effects
				(font
					(size 1 1)
					(thickness 0.15)
				)
			)
		)
		(property "Val" "1u"
			(at 0 0 0)
			(layer "F.Fab")
			(hide yes)
			(effects
				(font
					(size 1 1)
					(thickness 0.15)
				)
			)
		)
		(property "Voltage" ""
			(at 0 0 0)
			(layer "F.Fab")
			(hide yes)
			(effects
				(font
					(size 1 1)
					(thickness 0.15)
				)
			)
		)
		(sheetname "Peripherals")
		(sheetfile "peripherals.kicad_sch")
		(attr smd)
		(fp_rect
			(start -0.925 -0.47)
			(end 0.925 0.47)
			(stroke
				(width 0.05)
				(type default)
			)
			(fill none)
			(layer "F.CrtYd")
		)
		(fp_line
			(start -0.494 -0.25)
			(end 0.504 -0.25)
			(stroke
				(width 0.15)
				(type solid)
			)
			(layer "F.Fab")
		)
		(fp_line
			(start -0.494 0.248)
			(end -0.494 -0.25)
			(stroke
				(width 0.15)
				(type solid)
			)
			(layer "F.Fab")
		)
		(fp_line
			(start 0.504 -0.25)
			(end 0.504 0.248)
			(stroke
				(width 0.15)
				(type solid)
			)
			(layer "F.Fab")
		)
		(fp_line
			(start 0.504 0.248)
			(end -0.494 0.248)
			(stroke
				(width 0.15)
				(type solid)
			)
			(layer "F.Fab")
		)
		(fp_text user "Author: Antmicro"
			(at -0.932 4.17 0)
			(layer "F.Fab")
			(hide yes)
			(effects
				(font
					(size 0.7 0.7)
					(thickness 0.15)
				)
				(justify left bottom)
			)
		)
		(fp_text user "${REFERENCE}"
			(at -0.932 3.168 0)
			(layer "F.Fab")
			(hide yes)
			(effects
				(font
					(size 0.7 0.7)
					(thickness 0.15)
				)
				(justify left bottom)
			)
		)
		(fp_text user "License: Apache-2.0"
			(at -0.932 5.17 0)
			(layer "F.Fab")
			(hide yes)
			(effects
				(font
					(size 0.7 0.7)
					(thickness 0.15)
				)
				(justify left bottom)
			)
		)
		(pad "1" smd roundrect
			(at -0.48 0)
			(size 0.59 0.64)
			(layers "F.Cu" "F.Paste" "F.Mask")
			(roundrect_rratio 0.25)
			(net 484 "/Peripherals/3V3_STDB_CONN")
			(pintype "passive")
		)
		(pad "2" smd roundrect
			(at 0.48 0)
			(size 0.59 0.64)
			(layers "F.Cu" "F.Paste" "F.Mask")
			(roundrect_rratio 0.25)
			(net 1 "GND")
			(pintype "passive")
		)
	)
	(footprint "antmicro-footprints:R_0402_1005Metric"
		(layer "F.Cu")
		(at 127.9 107.9 -90)
		(descr "Resistor SMD 0402")
		(tags "resistor SMD 0402")
		(property "Reference" "R186"
			(at 3.85 -0.37 -90)
			(layer "F.SilkS")
			(effects
				(font
					(size 0.7 0.7)
					(thickness 0.15)
				)
				(justify left bottom)
			)
		)
		(property "Value" "R_200R_0402"
			(at 0 1.4 -90)
			(layer "F.Fab")
			(effects
				(font
					(size 0.7 0.7)
					(thickness 0.15)
				)
				(justify left bottom)
			)
		)
		(property "Footprint" "antmicro-footprints:R_0402_1005Metric"
			(at 0 0 -90)
			(layer "F.Fab")
			(hide yes)
			(effects
				(font
					(size 1.27 1.27)
					(thickness 0.15)
				)
			)
		)
		(property "Datasheet" "https://www.bourns.com/docs/product-datasheets/cr.pdf"
			(at 0 0 -90)
			(layer "F.Fab")
			(hide yes)
			(effects
				(font
					(size 1.27 1.27)
					(thickness 0.15)
				)
			)
		)
		(property "Author" "Antmicro"
			(at 20 235.8 0)
			(layer "F.Fab")
			(hide yes)
			(effects
				(font
					(size 1 1)
					(thickness 0.15)
				)
			)
		)
		(property "License" "Apache-2.0"
			(at 20 235.8 0)
			(layer "F.Fab")
			(hide yes)
			(effects
				(font
					(size 1 1)
					(thickness 0.15)
				)
			)
		)
		(property "MPN" "CR0402-FX-2000GLF"
			(at 20 235.8 0)
			(layer "F.Fab")
			(hide yes)
			(effects
				(font
					(size 1 1)
					(thickness 0.15)
				)
			)
		)
		(property "Manufacturer" "Bourns"
			(at 20 235.8 0)
			(layer "F.Fab")
			(hide yes)
			(effects
				(font
					(size 1 1)
					(thickness 0.15)
				)
			)
		)
		(property "Tolerance" "1%"
			(at 20 235.8 0)
			(layer "F.Fab")
			(hide yes)
			(effects
				(font
					(size 1 1)
					(thickness 0.15)
				)
			)
		)
		(property "Val" "200R"
			(at 20 235.8 0)
			(layer "F.Fab")
			(hide yes)
			(effects
				(font
					(size 1 1)
					(thickness 0.15)
				)
			)
		)
		(sheetname "M.2")
		(sheetfile "m-2.kicad_sch")
		(attr smd)
		(fp_rect
			(start -0.925 -0.47)
			(end 0.925 0.47)
			(stroke
				(width 0.05)
				(type default)
			)
			(fill none)
			(layer "F.CrtYd")
		)
		(fp_rect
			(start -0.5 -0.25)
			(end 0.5 0.25)
			(stroke
				(width 0.15)
				(type solid)
			)
			(fill none)
			(layer "F.Fab")
		)
		(fp_text user "Author: Antmicro"
			(at -0.95 4.169 -90)
			(layer "F.Fab")
			(hide yes)
			(effects
				(font
					(size 0.7 0.7)
					(thickness 0.15)
				)
				(justify left bottom)
			)
		)
		(fp_text user "License: Apache-2.0"
			(at -0.95 5.169 -90)
			(layer "F.Fab")
			(hide yes)
			(effects
				(font
					(size 0.7 0.7)
					(thickness 0.15)
				)
				(justify left bottom)
			)
		)
		(fp_text user "${REFERENCE}"
			(at -0.95 3.168 -90)
			(layer "F.Fab")
			(hide yes)
			(effects
				(font
					(size 0.7 0.7)
					(thickness 0.15)
				)
				(justify left bottom)
			)
		)
		(pad "1" smd roundrect
			(at -0.48 0 270)
			(size 0.59 0.64)
			(layers "F.Cu" "F.Paste" "F.Mask")
			(roundrect_rratio 0.25)
			(net 184 "Net-(D51-A)")
			(pintype "passive")
		)
		(pad "2" smd roundrect
			(at 0.48 0 270)
			(size 0.59 0.64)
			(layers "F.Cu" "F.Paste" "F.Mask")
			(roundrect_rratio 0.25)
			(net 87 "+3V3")
			(pintype "passive")
		)
	)
	(footprint "antmicro-footprints:Fiducial_1mm_Mask2mm"
		(layer "F.Cu")
		(at 148.25 127.25)
		(descr "Circular Fiducial, 1mm bare copper, 3mm soldermask opening")
		(tags "fiducial")
		(property "Reference" "FID4"
			(at 0 -1.4 0)
			(layer "F.SilkS")
			(hide yes)
			(effects
				(font
					(size 0.7 0.7)
					(thickness 0.15)
				)
				(justify left bottom)
			)
		)
		(property "Value" "Fiducial_1mm_Mask2mm"
			(at 0 2.2 0)
			(layer "F.Fab")
			(effects
				(font
					(size 0.7 0.7)
					(thickness 0.15)
				)
				(justify left bottom)
			)
		)
		(property "Footprint" "antmicro-footprints:Fiducial_1mm_Mask2mm"
			(at 0 0 0)
			(layer "F.Fab")
			(hide yes)
			(effects
				(font
					(size 1.27 1.27)
					(thickness 0.15)
				)
			)
		)
		(attr board_only exclude_from_pos_files exclude_from_bom)
		(fp_circle
			(center 0 0)
			(end 1.24 0)
			(stroke
				(width 0.05)
				(type solid)
			)
			(fill none)
			(layer "F.CrtYd")
		)
		(fp_circle
			(center 0 0)
			(end 0.999 0)
			(stroke
				(width 0.15)
				(type solid)
			)
			(fill none)
			(layer "F.Fab")
		)
		(fp_text user "${REFERENCE}"
			(at -1.25 4.603 0)
			(layer "F.Fab")
			(hide yes)
			(effects
				(font
					(size 0.7 0.7)
					(thickness 0.15)
				)
				(justify left bottom)
			)
		)
		(fp_text user "Author: Antmicro"
			(at -1.25 5.803 0)
			(layer "F.Fab")
			(hide yes)
			(effects
				(font
					(size 0.7 0.7)
					(thickness 0.15)
				)
				(justify left bottom)
			)
		)
		(fp_text user "License: Apache-2.0"
			(at -1.25 7.003 0)
			(layer "F.Fab")
			(hide yes)
			(effects
				(font
					(size 0.7 0.7)
					(thickness 0.15)
				)
				(justify left bottom)
			)
		)
		(pad "" smd circle
			(at 0 0)
			(size 1 1)
			(layers "F.Cu" "F.Mask")
			(solder_mask_margin 0.5)
			(clearance 0.5)
		)
	)
	(footprint "antmicro-footprints:TE_2309413"
		(locked yes)
		(layer "F.Cu")
		(at 92.706 84.0225)
		(descr "260 pin DDR4 SODIMM Right Angle Socket, 9.2 mm (0.362 in) Stack Height, https://www.te.com/global-en/product-2309413-1.html")
		(tags "ddr4 sodimm right angle 9.2mm height jetson som")
		(property "Reference" "J15"
			(at -36.75 -13.25 0)
			(layer "F.SilkS")
			(effects
				(font
					(size 0.7 0.7)
					(thickness 0.15)
				)
				(justify left bottom)
			)
		)
		(property "Value" "Bus_DDR4_SODIMM_CUSTOM_Jetson-Orin-H9.2mm-socket"
			(at -38 14.25 0)
			(layer "F.Fab")
			(effects
				(font
					(size 0.7 0.7)
					(thickness 0.15)
				)
				(justify left bottom)
			)
		)
		(property "Footprint" "antmicro-footprints:TE_2309413"
			(at 0 0 0)
			(layer "F.Fab")
			(hide yes)
			(effects
				(font
					(size 1.27 1.27)
					(thickness 0.15)
				)
			)
		)
		(property "Datasheet" "https://developer.nvidia.com/jetson-orin-nx-series-data-sheet"
			(at 0 0 0)
			(layer "F.Fab")
			(hide yes)
			(effects
				(font
					(size 1.27 1.27)
					(thickness 0.15)
				)
			)
		)
		(property "Author" "Antmicro"
			(at 0 0 0)
			(layer "F.Fab")
			(hide yes)
			(effects
				(font
					(size 1 1)
					(thickness 0.15)
				)
			)
		)
		(property "License" "Apache-2.0"
			(at 0 0 0)
			(layer "F.Fab")
			(hide yes)
			(effects
				(font
					(size 1 1)
					(thickness 0.15)
				)
			)
		)
		(property "MPN" "2309413-1"
			(at 0 0 0)
			(layer "F.Fab")
			(hide yes)
			(effects
				(font
					(size 1 1)
					(thickness 0.15)
				)
			)
		)
		(property "Manufacturer" "TE Connectivity"
			(at 0 0 0)
			(layer "F.Fab")
			(hide yes)
			(effects
				(font
					(size 1 1)
					(thickness 0.15)
				)
			)
		)
		(sheetname "SoM")
		(sheetfile "som.kicad_sch")
		(attr smd)
		(fp_line
			(start -38.906 -1.827)
			(end -38.906 1.973)
			(stroke
				(width 0.15)
				(type solid)
			)
			(layer "F.SilkS")
		)
		(fp_line
			(start -38.906 -1.827)
			(end -37.305 -1.827)
			(stroke
				(width 0.15)
				(type solid)
			)
			(layer "F.SilkS")
		)
		(fp_line
			(start -37.305 -1.827)
			(end -37.305 -2.927)
			(stroke
				(width 0.15)
				(type solid)
			)
			(layer "F.SilkS")
		)
		(fp_line
			(start -36.606 -1.926)
			(end -34.205 -1.926)
			(stroke
				(width 0.15)
				(type solid)
			)
			(layer "F.SilkS")
		)
		(fp_line
			(start -36.606 1.973)
			(end -38.906 1.973)
			(stroke
				(width 0.15)
				(type solid)
			)
			(layer "F.SilkS")
		)
		(fp_line
			(start -36.606 1.973)
			(end -36.606 -1.926)
			(stroke
				(width 0.15)
				(type solid)
			)
			(layer "F.SilkS")
		)
		(fp_line
			(start -36.506 -12.926)
			(end -36.506 -4.276)
			(stroke
				(width 0.15)
				(type solid)
			)
			(layer "F.SilkS")
		)
		(fp_line
			(start -36.506 -4.276)
			(end -37.305 -2.927)
			(stroke
				(width 0.15)
				(type solid)
			)
			(layer "F.SilkS")
		)
		(fp_line
			(start -33.705 -4.026)
			(end -34.205 -1.926)
			(stroke
				(width 0.15)
				(type solid)
			)
			(layer "F.SilkS")
		)
		(fp_line
			(start -33.601 -12.926)
			(end -36.506 -12.926)
			(stroke
				(width 0.15)
				(type solid)
			)
			(layer "F.SilkS")
		)
		(fp_line
			(start 33.694 -4.026)
			(end 34.194 -1.926)
			(stroke
				(width 0.15)
				(type solid)
			)
			(layer "F.SilkS")
		)
		(fp_line
			(start 36.494 -12.926)
			(end 33.84 -12.926)
			(stroke
				(width 0.15)
				(type solid)
			)
			(layer "F.SilkS")
		)
		(fp_line
			(start 36.494 -4.276)
			(end 36.494 -12.926)
			(stroke
				(width 0.15)
				(type solid)
			)
			(layer "F.SilkS")
		)
		(fp_line
			(start 36.494 -4.276)
			(end 37.295 -2.927)
			(stroke
				(width 0.15)
				(type solid)
			)
			(layer "F.SilkS")
		)
		(fp_line
			(start 36.594 2.173)
			(end 36.594 5.974)
			(stroke
				(width 0.15)
				(type solid)
			)
			(layer "F.SilkS")
		)
		(fp_line
			(start 37.295 -1.926)
			(end 34.194 -1.926)
			(stroke
				(width 0.15)
				(type solid)
			)
			(layer "F.SilkS")
		)
		(fp_line
			(start 37.295 -1.926)
			(end 37.295 -2.927)
			(stroke
				(width 0.15)
				(type solid)
			)
			(layer "F.SilkS")
		)
		(fp_line
			(start 38.895 2.173)
			(end 36.594 2.173)
			(stroke
				(width 0.15)
				(type solid)
			)
			(layer "F.SilkS")
		)
		(fp_line
			(start 38.895 5.974)
			(end 36.594 5.974)
			(stroke
				(width 0.15)
				(type solid)
			)
			(layer "F.SilkS")
		)
		(fp_line
			(start 38.895 5.974)
			(end 38.895 2.173)
			(stroke
				(width 0.15)
				(type solid)
			)
			(layer "F.SilkS")
		)
		(fp_line
			(start -39.01 -1.93)
			(end -37.42 -1.93)
			(stroke
				(width 0.05)
				(type solid)
			)
			(layer "F.CrtYd")
		)
		(fp_line
			(start -39.01 2.06)
			(end -39.01 -1.93)
			(stroke
				(width 0.05)
				(type solid)
			)
			(layer "F.CrtYd")
		)
		(fp_line
			(start -37.42 -1.93)
			(end -37.42 -3.04)
			(stroke
				(width 0.05)
				(type solid)
			)
			(layer "F.CrtYd")
		)
		(fp_line
			(start -36.61 -13.04)
			(end 36.59 -13.04)
			(stroke
				(width 0.05)
				(type solid)
			)
			(layer "F.CrtYd")
		)
		(fp_line
			(start -36.61 -4.33)
			(end -37.42 -3.04)
			(stroke
				(width 0.05)
				(type solid)
			)
			(layer "F.CrtYd")
		)
		(fp_line
			(start -36.61 -4.33)
			(end -36.61 -13.04)
			(stroke
				(width 0.05)
				(type solid)
			)
			(layer "F.CrtYd")
		)
		(fp_line
			(start -36.51 -1.84)
			(end -36.51 2.06)
			(stroke
				(width 0.05)
				(type solid)
			)
			(layer "F.CrtYd")
		)
		(fp_line
			(start -36.51 -1.84)
			(end -34.11 -1.84)
			(stroke
				(width 0.05)
				(type solid)
			)
			(layer "F.CrtYd")
		)
		(fp_line
			(start -36.51 2.06)
			(end -39.01 2.06)
			(stroke
				(width 0.05)
				(type solid)
			)
			(layer "F.CrtYd")
		)
		(fp_line
			(start -34.11 -1.84)
			(end -33.86 -2.84)
			(stroke
				(width 0.05)
				(type solid)
			)
			(layer "F.CrtYd")
		)
		(fp_line
			(start 33.84 -2.84)
			(end -33.86 -2.84)
			(stroke
				(width 0.05)
				(type solid)
			)
			(layer "F.CrtYd")
		)
		(fp_line
			(start 34.09 -1.84)
			(end 33.84 -2.84)
			(stroke
				(width 0.05)
				(type solid)
			)
			(layer "F.CrtYd")
		)
		(fp_line
			(start 34.09 -1.84)
			(end 37.38 -1.84)
			(stroke
				(width 0.05)
				(type solid)
			)
			(layer "F.CrtYd")
		)
		(fp_line
			(start 36.59 -13.04)
			(end 36.59 -4.33)
			(stroke
				(width 0.05)
				(type solid)
			)
			(layer "F.CrtYd")
		)
		(fp_line
			(start 36.59 2.16)
			(end 36.59 5.96)
			(stroke
				(width 0.05)
				(type solid)
			)
			(layer "F.CrtYd")
		)
		(fp_line
			(start 37.38 -2.98)
			(end 36.59 -4.33)
			(stroke
				(width 0.05)
				(type solid)
			)
			(layer "F.CrtYd")
		)
		(fp_line
			(start 37.38 -2.98)
			(end 37.38 -1.84)
			(stroke
				(width 0.05)
				(type solid)
			)
			(layer "F.CrtYd")
		)
		(fp_line
			(start 38.88 2.16)
			(end 36.59 2.16)
			(stroke
				(width 0.05)
				(type solid)
			)
			(layer "F.CrtYd")
		)
		(fp_line
			(start 38.88 2.16)
			(end 38.88 5.96)
			(stroke
				(width 0.05)
				(type solid)
			)
			(layer "F.CrtYd")
		)
		(fp_line
			(start 38.88 5.96)
			(end 36.59 5.96)
			(stroke
				(width 0.05)
				(type solid)
			)
			(layer "F.CrtYd")
		)
		(fp_line
			(start -39.006 12.925)
			(end -33.756 12.925)
			(stroke
				(width 0.15)
				(type solid)
			)
			(layer "F.Fab")
		)
		(fp_line
			(start -36.506 -12.926)
			(end -36.506 -2.626)
			(stroke
				(width 0.15)
				(type solid)
			)
			(layer "F.Fab")
		)
		(fp_line
			(start -36.506 -2.626)
			(end -39.006 12.925)
			(stroke
				(width 0.15)
				(type solid)
			)
			(layer "F.Fab")
		)
		(fp_line
			(start -33.756 -4.026)
			(end 33.744 -4.026)
			(stroke
				(width 0.15)
				(type solid)
			)
			(layer "F.Fab")
		)
		(fp_line
			(start -33.756 12.925)
			(end -33.756 -4.026)
			(stroke
				(width 0.15)
				(type solid)
			)
			(layer "F.Fab")
		)
		(fp_line
			(start 33.744 -4.026)
			(end 33.744 12.925)
			(stroke
				(width 0.15)
				(type solid)
			)
			(layer "F.Fab")
		)
		(fp_line
			(start 33.744 12.925)
			(end 38.994 12.925)
			(stroke
				(width 0.15)
				(type solid)
			)
			(layer "F.Fab")
		)
		(fp_line
			(start 36.494 -12.926)
			(end -36.506 -12.926)
			(stroke
				(width 0.15)
				(type solid)
			)
			(layer "F.Fab")
		)
		(fp_line
			(start 36.494 -2.626)
			(end 36.494 -12.926)
			(stroke
				(width 0.15)
				(type solid)
			)
			(layer "F.Fab")
		)
		(fp_line
			(start 38.994 12.925)
			(end 36.494 -2.626)
			(stroke
				(width 0.15)
				(type solid)
			)
			(layer "F.Fab")
		)
		(fp_text user "License: Apache-2.0"
			(at -38 18 0)
			(layer "F.Fab")
			(hide yes)
			(effects
				(font
					(size 0.7 0.7)
					(thickness 0.15)
				)
				(justify left bottom)
			)
		)
		(fp_text user "${REFERENCE}"
			(at -38 15.5 0)
			(layer "F.Fab")
			(hide yes)
			(effects
				(font
					(size 0.7 0.7)
					(thickness 0.15)
				)
				(justify left bottom)
			)
		)
		(fp_text user "Author: Antmicro"
			(at -38 16.75 0)
			(layer "F.Fab")
			(hide yes)
			(effects
				(font
					(size 0.7 0.7)
					(thickness 0.15)
				)
				(justify left bottom)
			)
		)
		(pad "" np_thru_hole circle
			(at -34.406 -7.926)
			(size 1.15 1.15)
			(drill 1.15)
			(layers "*.Cu" "*.Mask")
		)
		(pad "" np_thru_hole circle
			(at 34.395 -7.926)
			(size 1.65 1.65)
			(drill 1.65)
			(layers "*.Cu" "*.Mask")
		)
		(pad "1" smd rect
			(at 33.369 -12.026 90)
			(size 1.75 0.3)
			(layers "F.Cu" "F.Paste" "F.Mask")
			(net 1 "GND")
			(pinfunction "GND")
			(pintype "passive")
		)
		(pad "2" smd rect
			(at 33.119 -3.826 90)
			(size 1.75 0.3)
			(layers "F.Cu" "F.Paste" "F.Mask")
			(net 1 "GND")
			(pinfunction "GND")
			(pintype "passive")
		)
		(pad "3" smd rect
			(at 32.869 -12.026 90)
			(size 1.75 0.3)
			(layers "F.Cu" "F.Paste" "F.Mask")
			(net 2 "CSI1_D0_N")
			(pinfunction "CSI1_D0_N")
			(pintype "passive")
		)
		(pad "4" smd rect
			(at 32.619 -3.826 90)
			(size 1.75 0.3)
			(layers "F.Cu" "F.Paste" "F.Mask")
			(net 3 "CSI0_D0_N")
			(pinfunction "CSI0_D0_N")
			(pintype "passive")
		)
		(pad "5" smd rect
			(at 32.369 -12.026 90)
			(size 1.75 0.3)
			(layers "F.Cu" "F.Paste" "F.Mask")
			(net 4 "CSI1_D0_P")
			(pinfunction "CSI1_D0_P")
			(pintype "passive")
		)
		(pad "6" smd rect
			(at 32.119 -3.826 90)
			(size 1.75 0.3)
			(layers "F.Cu" "F.Paste" "F.Mask")
			(net 5 "CSI0_D0_P")
			(pinfunction "CSI0_D0_P")
			(pintype "passive")
		)
		(pad "7" smd rect
			(at 31.87 -12.026 90)
			(size 1.75 0.3)
			(layers "F.Cu" "F.Paste" "F.Mask")
			(net 1 "GND")
			(pinfunction "GND")
			(pintype "passive")
		)
		(pad "8" smd rect
			(at 31.62 -3.826 90)
			(size 1.75 0.3)
			(layers "F.Cu" "F.Paste" "F.Mask")
			(net 1 "GND")
			(pinfunction "GND")
			(pintype "passive")
		)
		(pad "9" smd rect
			(at 31.37 -12.026 90)
			(size 1.75 0.3)
			(layers "F.Cu" "F.Paste" "F.Mask")
			(net 6 "CSI1_CLK_N")
			(pinfunction "CSI1_CLK_N")
			(pintype "passive")
		)
		(pad "10" smd rect
			(at 31.12 -3.826 90)
			(size 1.75 0.3)
			(layers "F.Cu" "F.Paste" "F.Mask")
			(net 7 "CSI0_CLK_N")
			(pinfunction "CSI0_CLK_N")
			(pintype "passive")
		)
		(pad "11" smd rect
			(at 30.87 -12.026 90)
			(size 1.75 0.3)
			(layers "F.Cu" "F.Paste" "F.Mask")
			(net 8 "CSI1_CLK_P")
			(pinfunction "CSI1_CLK_P")
			(pintype "passive")
		)
		(pad "12" smd rect
			(at 30.62 -3.826 90)
			(size 1.75 0.3)
			(layers "F.Cu" "F.Paste" "F.Mask")
			(net 9 "CSI0_CLK_P")
			(pinfunction "CSI0_CLK_P")
			(pintype "passive")
		)
		(pad "13" smd rect
			(at 30.37 -12.026 90)
			(size 1.75 0.3)
			(layers "F.Cu" "F.Paste" "F.Mask")
			(net 1 "GND")
			(pinfunction "GND")
			(pintype "passive")
		)
		(pad "14" smd rect
			(at 30.12 -3.826 90)
			(size 1.75 0.3)
			(layers "F.Cu" "F.Paste" "F.Mask")
			(net 1 "GND")
			(pinfunction "GND")
			(pintype "passive")
		)
		(pad "15" smd rect
			(at 29.87 -12.026 90)
			(size 1.75 0.3)
			(layers "F.Cu" "F.Paste" "F.Mask")
			(net 10 "CSI1_D1_N")
			(pinfunction "CSI1_D1_N")
			(pintype "passive")
		)
		(pad "16" smd rect
			(at 29.62 -3.826 90)
			(size 1.75 0.3)
			(layers "F.Cu" "F.Paste" "F.Mask")
			(net 11 "CSI0_D1_N")
			(pinfunction "CSI0_D1_N")
			(pintype "passive")
		)
		(pad "17" smd rect
			(at 29.37 -12.026 90)
			(size 1.75 0.3)
			(layers "F.Cu" "F.Paste" "F.Mask")
			(net 12 "CSI1_D1_P")
			(pinfunction "CSI1_D1_P")
			(pintype "passive")
		)
		(pad "18" smd rect
			(at 29.12 -3.826 90)
			(size 1.75 0.3)
			(layers "F.Cu" "F.Paste" "F.Mask")
			(net 13 "CSI0_D1_P")
			(pinfunction "CSI0_D1_P")
			(pintype "passive")
		)
		(pad "19" smd rect
			(at 28.87 -12.026 90)
			(size 1.75 0.3)
			(layers "F.Cu" "F.Paste" "F.Mask")
			(net 1 "GND")
			(pinfunction "GND")
			(pintype "passive")
		)
		(pad "20" smd rect
			(at 28.62 -3.826 90)
			(size 1.75 0.3)
			(layers "F.Cu" "F.Paste" "F.Mask")
			(net 1 "GND")
			(pinfunction "GND")
			(pintype "passive")
		)
		(pad "21" smd rect
			(at 28.37 -12.026 90)
			(size 1.75 0.3)
			(layers "F.Cu" "F.Paste" "F.Mask")
			(net 14 "CSI3_D0_N")
			(pinfunction "CSI3_D0_N")
			(pintype "passive")
		)
		(pad "22" smd rect
			(at 28.12 -3.826 90)
			(size 1.75 0.3)
			(layers "F.Cu" "F.Paste" "F.Mask")
			(net 15 "CSI2_D0_N")
			(pinfunction "CSI2_D0_N")
			(pintype "passive")
		)
		(pad "23" smd rect
			(at 27.87 -12.026 90)
			(size 1.75 0.3)
			(layers "F.Cu" "F.Paste" "F.Mask")
			(net 16 "CSI3_D0_P")
			(pinfunction "CSI3_D0_P")
			(pintype "passive")
		)
		(pad "24" smd rect
			(at 27.62 -3.826 90)
			(size 1.75 0.3)
			(layers "F.Cu" "F.Paste" "F.Mask")
			(net 17 "CSI2_D0_P")
			(pinfunction "CSI2_D0_P")
			(pintype "passive")
		)
		(pad "25" smd rect
			(at 27.37 -12.026 90)
			(size 1.75 0.3)
			(layers "F.Cu" "F.Paste" "F.Mask")
			(net 1 "GND")
			(pinfunction "GND")
			(pintype "passive")
		)
		(pad "26" smd rect
			(at 27.12 -3.826 90)
			(size 1.75 0.3)
			(layers "F.Cu" "F.Paste" "F.Mask")
			(net 1 "GND")
			(pinfunction "GND")
			(pintype "passive")
		)
		(pad "27" smd rect
			(at 26.87 -12.026 90)
			(size 1.75 0.3)
			(layers "F.Cu" "F.Paste" "F.Mask")
			(net 18 "CSI3_CLK_N")
			(pinfunction "CSI3_CLK_N")
			(pintype "passive")
		)
		(pad "28" smd rect
			(at 26.62 -3.826 90)
			(size 1.75 0.3)
			(layers "F.Cu" "F.Paste" "F.Mask")
			(net 19 "CSI2_CLK_N")
			(pinfunction "CSI2_CLK_N")
			(pintype "passive")
		)
		(pad "29" smd rect
			(at 26.37 -12.026 90)
			(size 1.75 0.3)
			(layers "F.Cu" "F.Paste" "F.Mask")
			(net 20 "CSI3_CLK_P")
			(pinfunction "CSI3_CLK_P")
			(pintype "passive")
		)
		(pad "30" smd rect
			(at 26.12 -3.826 90)
			(size 1.75 0.3)
			(layers "F.Cu" "F.Paste" "F.Mask")
			(net 21 "CSI2_CLK_P")
			(pinfunction "CSI2_CLK_P")
			(pintype "passive")
		)
		(pad "31" smd rect
			(at 25.87 -12.026 90)
			(size 1.75 0.3)
			(layers "F.Cu" "F.Paste" "F.Mask")
			(net 1 "GND")
			(pinfunction "GND")
			(pintype "passive")
		)
		(pad "32" smd rect
			(at 25.62 -3.826 90)
			(size 1.75 0.3)
			(layers "F.Cu" "F.Paste" "F.Mask")
			(net 1 "GND")
			(pinfunction "GND")
			(pintype "passive")
		)
		(pad "33" smd rect
			(at 25.37 -12.026 90)
			(size 1.75 0.3)
			(layers "F.Cu" "F.Paste" "F.Mask")
			(net 22 "CSI3_D1_N")
			(pinfunction "CSI3_D1_N")
			(pintype "passive")
		)
		(pad "34" smd rect
			(at 25.12 -3.826 90)
			(size 1.75 0.3)
			(layers "F.Cu" "F.Paste" "F.Mask")
			(net 23 "CSI2_D1_N")
			(pinfunction "CSI2_D1_N")
			(pintype "passive")
		)
		(pad "35" smd rect
			(at 24.87 -12.026 90)
			(size 1.75 0.3)
			(layers "F.Cu" "F.Paste" "F.Mask")
			(net 24 "CSI3_D1_P")
			(pinfunction "CSI3_D1_P")
			(pintype "passive")
		)
		(pad "36" smd rect
			(at 24.62 -3.826 90)
			(size 1.75 0.3)
			(layers "F.Cu" "F.Paste" "F.Mask")
			(net 25 "CSI2_D1_P")
			(pinfunction "CSI2_D1_P")
			(pintype "passive")
		)
		(pad "37" smd rect
			(at 24.37 -12.026 90)
			(size 1.75 0.3)
			(layers "F.Cu" "F.Paste" "F.Mask")
			(net 1 "GND")
			(pinfunction "GND")
			(pintype "passive")
		)
		(pad "38" smd rect
			(at 24.12 -3.826 90)
			(size 1.75 0.3)
			(layers "F.Cu" "F.Paste" "F.Mask")
			(net 1 "GND")
			(pinfunction "GND")
			(pintype "passive")
		)
		(pad "39" smd rect
			(at 23.87 -12.026 90)
			(size 1.75 0.3)
			(layers "F.Cu" "F.Paste" "F.Mask")
			(net 107 "USBSS1_RX_N")
			(pinfunction "USBSS1_RX_N")
			(pintype "passive")
		)
		(pad "40" smd rect
			(at 23.62 -3.826 90)
			(size 1.75 0.3)
			(layers "F.Cu" "F.Paste" "F.Mask")
			(net 113 "PCIE2_RX0_N")
			(pinfunction "PCIE2_RX0_N")
			(pintype "passive")
		)
		(pad "41" smd rect
			(at 23.37 -12.026 90)
			(size 1.75 0.3)
			(layers "F.Cu" "F.Paste" "F.Mask")
			(net 114 "USBSS1_RX_P")
			(pinfunction "USBSS1_RX_P")
			(pintype "passive")
		)
		(pad "42" smd rect
			(at 23.12 -3.826 90)
			(size 1.75 0.3)
			(layers "F.Cu" "F.Paste" "F.Mask")
			(net 131 "PCIE2_RX0_P")
			(pinfunction "PCIE2_RX0_P")
			(pintype "passive")
		)
		(pad "43" smd rect
			(at 22.87 -12.026 90)
			(size 1.75 0.3)
			(layers "F.Cu" "F.Paste" "F.Mask")
			(net 1 "GND")
			(pinfunction "GND")
			(pintype "passive")
		)
		(pad "44" smd rect
			(at 22.62 -3.826 90)
			(size 1.75 0.3)
			(layers "F.Cu" "F.Paste" "F.Mask")
			(net 1 "GND")
			(pinfunction "GND")
			(pintype "passive")
		)
		(pad "45" smd rect
			(at 22.37 -12.026 90)
			(size 1.75 0.3)
			(layers "F.Cu" "F.Paste" "F.Mask")
			(net 132 "USBSS1_TX_N")
			(pinfunction "USBSS1_TX_N")
			(pintype "passive")
		)
		(pad "46" smd rect
			(at 22.12 -3.826 90)
			(size 1.75 0.3)
			(layers "F.Cu" "F.Paste" "F.Mask")
			(net 156 "PCIE2_TX0_N")
			(pinfunction "PCIE2_TX0_N")
			(pintype "passive")
		)
		(pad "47" smd rect
			(at 21.87 -12.026 90)
			(size 1.75 0.3)
			(layers "F.Cu" "F.Paste" "F.Mask")
			(net 157 "USBSS1_TX_P")
			(pinfunction "USBSS1_TX_P")
			(pintype "passive")
		)
		(pad "48" smd rect
			(at 21.62 -3.826 90)
			(size 1.75 0.3)
			(layers "F.Cu" "F.Paste" "F.Mask")
			(net 158 "PCIE2_TX0_P")
			(pinfunction "PCIE2_TX0_P")
			(pintype "passive")
		)
		(pad "49" smd rect
			(at 21.37 -12.026 90)
			(size 1.75 0.3)
			(layers "F.Cu" "F.Paste" "F.Mask")
			(net 1 "GND")
			(pinfunction "GND")
			(pintype "passive")
		)
		(pad "50" smd rect
			(at 21.12 -3.826 90)
			(size 1.75 0.3)
			(layers "F.Cu" "F.Paste" "F.Mask")
			(net 1 "GND")
			(pinfunction "GND")
			(pintype "passive")
		)
		(pad "51" smd rect
			(at 20.87 -12.026 90)
			(size 1.75 0.3)
			(layers "F.Cu" "F.Paste" "F.Mask")
			(net 159 "USBSS2_RX_N")
			(pinfunction "USBSS2_RX_N")
			(pintype "passive")
		)
		(pad "52" smd rect
			(at 20.62 -3.826 90)
			(size 1.75 0.3)
			(layers "F.Cu" "F.Paste" "F.Mask")
			(net 163 "PCIE2_CLK_N")
			(pinfunction "PCIE2_CLK_N")
			(pintype "passive")
		)
		(pad "53" smd rect
			(at 20.37 -12.026 90)
			(size 1.75 0.3)
			(layers "F.Cu" "F.Paste" "F.Mask")
			(net 165 "USBSS2_RX_P")
			(pinfunction "USBSS2_RX_P")
			(pintype "passive")
		)
		(pad "54" smd rect
			(at 20.12 -3.826 90)
			(size 1.75 0.3)
			(layers "F.Cu" "F.Paste" "F.Mask")
			(net 166 "PCIE2_CLK_P")
			(pinfunction "PCIE2_CLK_P")
			(pintype "passive")
		)
		(pad "55" smd rect
			(at 19.87 -12.026 90)
			(size 1.75 0.3)
			(layers "F.Cu" "F.Paste" "F.Mask")
			(net 1 "GND")
			(pinfunction "GND")
			(pintype "passive")
		)
		(pad "56" smd rect
			(at 19.62 -3.826 90)
			(size 1.75 0.3)
			(layers "F.Cu" "F.Paste" "F.Mask")
			(net 1 "GND")
			(pinfunction "GND")
			(pintype "passive")
		)
		(pad "57" smd rect
			(at 19.37 -12.026 90)
			(size 1.75 0.3)
			(layers "F.Cu" "F.Paste" "F.Mask")
			(net 167 "USBSS2_TX_N")
			(pinfunction "USBSS2_TX_N")
			(pintype "passive")
		)
		(pad "58" smd rect
			(at 19.12 -3.826 90)
			(size 1.75 0.3)
			(layers "F.Cu" "F.Paste" "F.Mask")
			(net 172 "PCIE2_RX1_N")
			(pinfunction "PCIE3_RX0_N")
			(pintype "passive")
		)
		(pad "59" smd rect
			(at 18.87 -12.026 90)
			(size 1.75 0.3)
			(layers "F.Cu" "F.Paste" "F.Mask")
			(net 173 "USBSS2_TX_P")
			(pinfunction "USBSS2_TX_P")
			(pintype "passive")
		)
		(pad "60" smd rect
			(at 18.62 -3.826 90)
			(size 1.75 0.3)
			(layers "F.Cu" "F.Paste" "F.Mask")
			(net 175 "PCIE2_RX1_P")
			(pinfunction "PCIE3_RX0_P")
			(pintype "passive")
		)
		(pad "61" smd rect
			(at 18.37 -12.026 90)
			(size 1.75 0.3)
			(layers "F.Cu" "F.Paste" "F.Mask")
			(net 1 "GND")
			(pinfunction "GND")
			(pintype "passive")
		)
		(pad "62" smd rect
			(at 18.12 -3.826 90)
			(size 1.75 0.3)
			(layers "F.Cu" "F.Paste" "F.Mask")
			(net 1 "GND")
			(pinfunction "GND")
			(pintype "passive")
		)
		(pad "63" smd rect
			(at 17.87 -12.026 90)
			(size 1.75 0.3)
			(layers "F.Cu" "F.Paste" "F.Mask")
			(net 274 "DP1_TXD0_HDMI_TX2_N")
			(pinfunction "DP1_TXD0_N")
			(pintype "passive")
		)
		(pad "64" smd rect
			(at 17.62 -3.826 90)
			(size 1.75 0.3)
			(layers "F.Cu" "F.Paste" "F.Mask")
			(net 357 "PCIE2_TX1_N")
			(pinfunction "PCIE3_TX0_N")
			(pintype "passive")
		)
		(pad "65" smd rect
			(at 17.37 -12.026 90)
			(size 1.75 0.3)
			(layers "F.Cu" "F.Paste" "F.Mask")
			(net 367 "DP1_TXD0_HDMI_TX2_P")
			(pinfunction "DP1_TXD0_P")
			(pintype "passive")
		)
		(pad "66" smd rect
			(at 17.12 -3.826 90)
			(size 1.75 0.3)
			(layers "F.Cu" "F.Paste" "F.Mask")
			(net 370 "PCIE2_TX1_P")
			(pinfunction "PCIE3_TX0_P")
			(pintype "passive")
		)
		(pad "67" smd rect
			(at 16.87 -12.026 90)
			(size 1.75 0.3)
			(layers "F.Cu" "F.Paste" "F.Mask")
			(net 1 "GND")
			(pinfunction "GND")
			(pintype "passive")
		)
		(pad "68" smd rect
			(at 16.62 -3.826 90)
			(size 1.75 0.3)
			(layers "F.Cu" "F.Paste" "F.Mask")
			(net 1 "GND")
			(pinfunction "GND")
			(pintype "passive")
		)
		(pad "69" smd rect
			(at 16.37 -12.026 90)
			(size 1.75 0.3)
			(layers "F.Cu" "F.Paste" "F.Mask")
			(net 375 "DP1_TXD1_HDMI_TX1_N")
			(pinfunction "DP1_TXD1_N")
			(pintype "passive")
		)
		(pad "70" smd rect
			(at 16.12 -3.826 90)
			(size 1.75 0.3)
			(layers "F.Cu" "F.Paste" "F.Mask")
			(net 733 "unconnected-(J15B-DSI_D0_N-Pad70)")
			(pinfunction "DSI_D0_N")
			(pintype "passive+no_connect")
		)
		(pad "71" smd rect
			(at 15.87 -12.026 90)
			(size 1.75 0.3)
			(layers "F.Cu" "F.Paste" "F.Mask")
			(net 417 "DP1_TXD1_HDMI_TX1_P")
			(pinfunction "DP1_TXD1_P")
			(pintype "passive")
		)
		(pad "72" smd rect
			(at 15.62 -3.826 90)
			(size 1.75 0.3)
			(layers "F.Cu" "F.Paste" "F.Mask")
			(net 734 "unconnected-(J15B-DSI_D0_P-Pad72)")
			(pinfunction "DSI_D0_P")
			(pintype "passive+no_connect")
		)
		(pad "73" smd rect
			(at 15.37 -12.026 90)
			(size 1.75 0.3)
			(layers "F.Cu" "F.Paste" "F.Mask")
			(net 1 "GND")
			(pinfunction "GND")
			(pintype "passive")
		)
		(pad "74" smd rect
			(at 15.12 -3.826 90)
			(size 1.75 0.3)
			(layers "F.Cu" "F.Paste" "F.Mask")
			(net 1 "GND")
			(pinfunction "GND")
			(pintype "passive")
		)
		(pad "75" smd rect
			(at 14.87 -12.026 90)
			(size 1.75 0.3)
			(layers "F.Cu" "F.Paste" "F.Mask")
			(net 418 "DP1_TXD2_HDMI_TX0_N")
			(pinfunction "DP1_TXD2_N")
			(pintype "passive")
		)
		(pad "76" smd rect
			(at 14.62 -3.826 90)
			(size 1.75 0.3)
			(layers "F.Cu" "F.Paste" "F.Mask")
			(net 735 "unconnected-(J15B-DSI_CLK_N-Pad76)")
			(pinfunction "DSI_CLK_N")
			(pintype "passive+no_connect")
		)
		(pad "77" smd rect
			(at 14.37 -12.026 90)
			(size 1.75 0.3)
			(layers "F.Cu" "F.Paste" "F.Mask")
			(net 419 "DP1_TXD2_HDMI_TX0_P")
			(pinfunction "DP1_TXD2_P")
			(pintype "passive")
		)
		(pad "78" smd rect
			(at 14.12 -3.826 90)
			(size 1.75 0.3)
			(layers "F.Cu" "F.Paste" "F.Mask")
			(net 736 "unconnected-(J15B-DSI_CLK_P-Pad78)")
			(pinfunction "DSI_CLK_P")
			(pintype "passive+no_connect")
		)
		(pad "79" smd rect
			(at 13.87 -12.026 90)
			(size 1.75 0.3)
			(layers "F.Cu" "F.Paste" "F.Mask")
			(net 1 "GND")
			(pinfunction "GND")
			(pintype "passive")
		)
		(pad "80" smd rect
			(at 13.62 -3.826 90)
			(size 1.75 0.3)
			(layers "F.Cu" "F.Paste" "F.Mask")
			(net 1 "GND")
			(pinfunction "GND")
			(pintype "passive")
		)
		(pad "81" smd rect
			(at 13.37 -12.026 90)
			(size 1.75 0.3)
			(layers "F.Cu" "F.Paste" "F.Mask")
			(net 420 "DP1_TXD3_HDMI_TXC_N")
			(pinfunction "DP1_TXD3_N")
			(pintype "passive")
		)
		(pad "82" smd rect
			(at 13.12 -3.826 90)
			(size 1.75 0.3)
			(layers "F.Cu" "F.Paste" "F.Mask")
			(net 737 "unconnected-(J15B-DSI_D1_N-Pad82)")
			(pinfunction "DSI_D1_N")
			(pintype "passive+no_connect")
		)
		(pad "83" smd rect
			(at 12.87 -12.026 90)
			(size 1.75 0.3)
			(layers "F.Cu" "F.Paste" "F.Mask")
			(net 422 "DP1_TXD3_HDMI_TXC_P")
			(pinfunction "DP1_TXD3_P")
			(pintype "passive")
		)
		(pad "84" smd rect
			(at 12.62 -3.826 90)
			(size 1.75 0.3)
			(layers "F.Cu" "F.Paste" "F.Mask")
			(net 738 "unconnected-(J15B-DSI_D1_P-Pad84)")
			(pinfunction "DSI_D1_P")
			(pintype "passive+no_connect")
		)
		(pad "85" smd rect
			(at 12.37 -12.026 90)
			(size 1.75 0.3)
			(layers "F.Cu" "F.Paste" "F.Mask")
			(net 1 "GND")
			(pinfunction "GND")
			(pintype "passive")
		)
		(pad "86" smd rect
			(at 12.12 -3.826 90)
			(size 1.75 0.3)
			(layers "F.Cu" "F.Paste" "F.Mask")
			(net 1 "GND")
			(pinfunction "GND")
			(pintype "passive")
		)
		(pad "87" smd rect
			(at 11.87 -12.026 90)
			(size 1.75 0.3)
			(layers "F.Cu" "F.Paste" "F.Mask")
			(net 116 "USB_FLASH_ID")
			(pinfunction "USB_VBUS_EN0/GPIO00")
			(pintype "passive")
		)
		(pad "88" smd rect
			(at 11.62 -3.826 90)
			(size 1.75 0.3)
			(layers "F.Cu" "F.Paste" "F.Mask")
			(net 739 "unconnected-(J15E-DP0_HPD-Pad88)")
			(pinfunction "DP0_HPD")
			(pintype "passive+no_connect")
		)
		(pad "89" smd rect
			(at 11.37 -12.026 90)
			(size 1.75 0.3)
			(layers "F.Cu" "F.Paste" "F.Mask")
			(net 30 "SPIO_MOSI")
			(pinfunction "SPI0_MOSI")
			(pintype "passive")
		)
		(pad "90" smd rect
			(at 11.12 -3.826 90)
			(size 1.75 0.3)
			(layers "F.Cu" "F.Paste" "F.Mask")
			(net 740 "unconnected-(J15E-DP0_AUX_N-Pad90)")
			(pinfunction "DP0_AUX_N")
			(pintype "passive+no_connect")
		)
		(pad "91" smd rect
			(at 10.87 -12.026 90)
			(size 1.75 0.3)
			(layers "F.Cu" "F.Paste" "F.Mask")
			(net 31 "SPIO_SCK")
			(pinfunction "SPI0_SCK")
			(pintype "passive")
		)
		(pad "92" smd rect
			(at 10.62 -3.826 90)
			(size 1.75 0.3)
			(layers "F.Cu" "F.Paste" "F.Mask")
			(net 741 "unconnected-(J15E-DP0_AUX_P-Pad92)")
			(pinfunction "DP0_AUX_P")
			(pintype "passive+no_connect")
		)
		(pad "93" smd rect
			(at 10.37 -12.026 90)
			(size 1.75 0.3)
			(layers "F.Cu" "F.Paste" "F.Mask")
			(net 32 "SPIO_MISO")
			(pinfunction "SPI0_MISO")
			(pintype "passive")
		)
		(pad "94" smd rect
			(at 10.12 -3.826 90)
			(size 1.75 0.3)
			(layers "F.Cu" "F.Paste" "F.Mask")
			(net 742 "Net-(J15E-HDMI_CEC)")
			(pinfunction "HDMI_CEC")
			(pintype "passive")
		)
		(pad "95" smd rect
			(at 9.87 -12.026 90)
			(size 1.75 0.3)
			(layers "F.Cu" "F.Paste" "F.Mask")
			(net 33 "~{SPI0_CS0}")
			(pinfunction "~{SPI0_CS0}")
			(pintype "passive")
		)
		(pad "96" smd rect
			(at 9.62 -3.826 90)
			(size 1.75 0.3)
			(layers "F.Cu" "F.Paste" "F.Mask")
			(net 428 "DP1_HPD")
			(pinfunction "DP1_HPD")
			(pintype "passive")
		)
		(pad "97" smd rect
			(at 9.37 -12.026 90)
			(size 1.75 0.3)
			(layers "F.Cu" "F.Paste" "F.Mask")
			(net 34 "~{SPI0_CS1}")
			(pinfunction "~{SPI0_CS1}")
			(pintype "passive")
		)
		(pad "98" smd rect
			(at 9.12 -3.826 90)
			(size 1.75 0.3)
			(layers "F.Cu" "F.Paste" "F.Mask")
			(net 430 "DP1_HDMI_AUX_N")
			(pinfunction "DP1_AUX_N")
			(pintype "passive")
		)
		(pad "99" smd rect
			(at 8.87 -12.026 90)
			(size 1.75 0.3)
			(layers "F.Cu" "F.Paste" "F.Mask")
			(net 517 "UART0_TXD")
			(pinfunction "UART0_TXD")
			(pintype "passive")
		)
		(pad "100" smd rect
			(at 8.62 -3.826 90)
			(size 1.75 0.3)
			(layers "F.Cu" "F.Paste" "F.Mask")
			(net 429 "DP1_HDMI_AUX_P")
			(pinfunction "DP1_AUX_P")
			(pintype "passive")
		)
		(pad "101" smd rect
			(at 8.37 -12.026 90)
			(size 1.75 0.3)
			(layers "F.Cu" "F.Paste" "F.Mask")
			(net 516 "UART0_RXD")
			(pinfunction "UART0_RXD")
			(pintype "passive")
		)
		(pad "102" smd rect
			(at 8.12 -3.826 90)
			(size 1.75 0.3)
			(layers "F.Cu" "F.Paste" "F.Mask")
			(net 1 "GND")
			(pinfunction "GND")
			(pintype "passive")
		)
		(pad "103" smd rect
			(at 7.869 -12.026 90)
			(size 1.75 0.3)
			(layers "F.Cu" "F.Paste" "F.Mask")
			(net 118 "UART0_RTS")
			(pinfunction "~{UART0_RTS}")
			(pintype "passive")
		)
		(pad "104" smd rect
			(at 7.619 -3.826 90)
			(size 1.75 0.3)
			(layers "F.Cu" "F.Paste" "F.Mask")
			(net 37 "SPI1_MOSI")
			(pinfunction "SPI1_MOSI")
			(pintype "passive")
		)
		(pad "105" smd rect
			(at 7.369 -12.026 90)
			(size 1.75 0.3)
			(layers "F.Cu" "F.Paste" "F.Mask")
			(net 119 "UART0_CTS")
			(pinfunction "~{UART0_CTS}")
			(pintype "passive")
		)
		(pad "106" smd rect
			(at 7.119 -3.826 90)
			(size 1.75 0.3)
			(layers "F.Cu" "F.Paste" "F.Mask")
			(net 38 "SPI1_SCK")
			(pinfunction "SPI1_SCK")
			(pintype "passive")
		)
		(pad "107" smd rect
			(at 6.869 -12.026 90)
			(size 1.75 0.3)
			(layers "F.Cu" "F.Paste" "F.Mask")
			(net 1 "GND")
			(pinfunction "GND")
			(pintype "passive")
		)
		(pad "108" smd rect
			(at 6.619 -3.826 90)
			(size 1.75 0.3)
			(layers "F.Cu" "F.Paste" "F.Mask")
			(net 39 "SPI1_MISO")
			(pinfunction "SPI1_MISO")
			(pintype "passive")
		)
		(pad "109" smd rect
			(at 6.369 -12.026 90)
			(size 1.75 0.3)
			(layers "F.Cu" "F.Paste" "F.Mask")
			(net 40 "USB0_D_N")
			(pinfunction "USB0_D_N")
			(pintype "passive")
		)
		(pad "110" smd rect
			(at 6.119 -3.826 90)
			(size 1.75 0.3)
			(layers "F.Cu" "F.Paste" "F.Mask")
			(net 41 "~{SPI1_CS0}")
			(pinfunction "~{SPI1_CS0}")
			(pintype "passive")
		)
		(pad "111" smd rect
			(at 5.869 -12.026 90)
			(size 1.75 0.3)
			(layers "F.Cu" "F.Paste" "F.Mask")
			(net 433 "USB0_D_P")
			(pinfunction "USB0_D_P")
			(pintype "passive")
		)
		(pad "112" smd rect
			(at 5.619 -3.826 90)
			(size 1.75 0.3)
			(layers "F.Cu" "F.Paste" "F.Mask")
			(net 42 "~{SPI1_CS1}")
			(pinfunction "~{SPI1_CS1}")
			(pintype "passive")
		)
		(pad "113" smd rect
			(at 5.369 -12.026 90)
			(size 1.75 0.3)
			(layers "F.Cu" "F.Paste" "F.Mask")
			(net 1 "GND")
			(pinfunction "GND")
			(pintype "passive")
		)
		(pad "114" smd rect
			(at 5.12 -3.826 90)
			(size 1.75 0.3)
			(layers "F.Cu" "F.Paste" "F.Mask")
			(net 743 "Net-(J15B-CAM0_PWDN)")
			(pinfunction "CAM0_PWDN")
			(pintype "passive")
		)
		(pad "115" smd rect
			(at 4.87 -12.026 90)
			(size 1.75 0.3)
			(layers "F.Cu" "F.Paste" "F.Mask")
			(net 434 "USB1_D_N")
			(pinfunction "USB1_D_N")
			(pintype "passive")
		)
		(pad "116" smd rect
			(at 4.62 -3.826 90)
			(size 1.75 0.3)
			(layers "F.Cu" "F.Paste" "F.Mask")
			(net 744 "Net-(J15B-CAM0_MCLK)")
			(pinfunction "CAM0_MCLK")
			(pintype "passive")
		)
		(pad "117" smd rect
			(at 4.37 -12.026 90)
			(size 1.75 0.3)
			(layers "F.Cu" "F.Paste" "F.Mask")
			(net 436 "USB1_D_P")
			(pinfunction "USB1_D_P")
			(pintype "passive")
		)
		(pad "118" smd rect
			(at 4.12 -3.826 90)
			(size 1.75 0.3)
			(layers "F.Cu" "F.Paste" "F.Mask")
			(net 43 "GPIO01")
			(pinfunction "GPIO01/CLK")
			(pintype "passive")
		)
		(pad "119" smd rect
			(at 3.87 -12.026 90)
			(size 1.75 0.3)
			(layers "F.Cu" "F.Paste" "F.Mask")
			(net 1 "GND")
			(pinfunction "GND")
			(pintype "passive")
		)
		(pad "120" smd rect
			(at 3.62 -3.826 90)
			(size 1.75 0.3)
			(layers "F.Cu" "F.Paste" "F.Mask")
			(net 745 "Net-(J15B-CAM1_PWDN)")
			(pinfunction "CAM1_PWDN")
			(pintype "passive")
		)
		(pad "121" smd rect
			(at 3.37 -12.026 90)
			(size 1.75 0.3)
			(layers "F.Cu" "F.Paste" "F.Mask")
			(net 437 "USB2_D_N")
			(pinfunction "USB2_D_N")
			(pintype "passive")
		)
		(pad "122" smd rect
			(at 3.12 -3.826 90)
			(size 1.75 0.3)
			(layers "F.Cu" "F.Paste" "F.Mask")
			(net 746 "Net-(J15B-CAM1_MCLK)")
			(pinfunction "CAM1_MCLK")
			(pintype "passive")
		)
		(pad "123" smd rect
			(at 2.87 -12.026 90)
			(size 1.75 0.3)
			(layers "F.Cu" "F.Paste" "F.Mask")
			(net 439 "USB2_D_P")
			(pinfunction "USB2_D_P")
			(pintype "passive")
		)
		(pad "124" smd rect
			(at 2.62 -3.826 90)
			(size 1.75 0.3)
			(layers "F.Cu" "F.Paste" "F.Mask")
			(net 747 "Net-(J15H-GPIO02)")
			(pinfunction "GPIO02")
			(pintype "passive")
		)
		(pad "125" smd rect
			(at 2.37 -12.026 90)
			(size 1.75 0.3)
			(layers "F.Cu" "F.Paste" "F.Mask")
			(net 1 "GND")
			(pinfunction "GND")
			(pintype "passive")
		)
		(pad "126" smd rect
			(at 2.12 -3.826 90)
			(size 1.75 0.3)
			(layers "F.Cu" "F.Paste" "F.Mask")
			(net 440 "USER_LED0")
			(pinfunction "GPIO03")
			(pintype "passive")
		)
		(pad "127" smd rect
			(at 1.87 -12.026 90)
			(size 1.75 0.3)
			(layers "F.Cu" "F.Paste" "F.Mask")
			(net 44 "USER_LED1")
			(pinfunction "GPIO04")
			(pintype "passive")
		)
		(pad "128" smd rect
			(at 1.62 -3.826 90)
			(size 1.75 0.3)
			(layers "F.Cu" "F.Paste" "F.Mask")
			(net 45 "USER_BTN0")
			(pinfunction "GPIO05")
			(pintype "passive")
		)
		(pad "129" smd rect
			(at 1.37 -12.026 90)
			(size 1.75 0.3)
			(layers "F.Cu" "F.Paste" "F.Mask")
			(net 1 "GND")
			(pinfunction "GND")
			(pintype "passive")
		)
		(pad "130" smd rect
			(at 1.12 -3.826 90)
			(size 1.75 0.3)
			(layers "F.Cu" "F.Paste" "F.Mask")
			(net 46 "USER_BTN1")
			(pinfunction "GPIO06")
			(pintype "passive")
		)
		(pad "131" smd rect
			(at 0.869 -12.026 90)
			(size 1.75 0.3)
			(layers "F.Cu" "F.Paste" "F.Mask")
			(net 47 "PCIE0_RX0_N")
			(pinfunction "PCIE0_RX0_N")
			(pintype "passive")
		)
		(pad "132" smd rect
			(at 0.619 -3.826 90)
			(size 1.75 0.3)
			(layers "F.Cu" "F.Paste" "F.Mask")
			(net 1 "GND")
			(pinfunction "GND")
			(pintype "passive")
		)
		(pad "133" smd rect
			(at 0.369 -12.026 90)
			(size 1.75 0.3)
			(layers "F.Cu" "F.Paste" "F.Mask")
			(net 48 "PCIE0_RX0_P")
			(pinfunction "PCIE0_RX0_P")
			(pintype "passive")
		)
		(pad "134" smd rect
			(at 0.119 -3.826 90)
			(size 1.75 0.3)
			(layers "F.Cu" "F.Paste" "F.Mask")
			(net 441 "PCIE0_TX0_N")
			(pinfunction "PCIE0_TX0_N")
			(pintype "passive")
		)
		(pad "135" smd rect
			(at -0.131 -12.026 90)
			(size 1.75 0.3)
			(layers "F.Cu" "F.Paste" "F.Mask")
			(net 1 "GND")
			(pinfunction "GND")
			(pintype "passive")
		)
		(pad "136" smd rect
			(at -0.38 -3.826 90)
			(size 1.75 0.3)
			(layers "F.Cu" "F.Paste" "F.Mask")
			(net 442 "PCIE0_TX0_P")
			(pinfunction "PCIE0_TX0_P")
			(pintype "passive")
		)
		(pad "137" smd rect
			(at -0.63 -12.026 90)
			(size 1.75 0.3)
			(layers "F.Cu" "F.Paste" "F.Mask")
			(net 49 "PCIE0_RX1_N")
			(pinfunction "PCIE0_RX1_N")
			(pintype "passive")
		)
		(pad "138" smd rect
			(at -0.88 -3.826 90)
			(size 1.75 0.3)
			(layers "F.Cu" "F.Paste" "F.Mask")
			(net 1 "GND")
			(pinfunction "GND")
			(pintype "passive")
		)
		(pad "139" smd rect
			(at -1.131 -12.026 90)
			(size 1.75 0.3)
			(layers "F.Cu" "F.Paste" "F.Mask")
			(net 50 "PCIE0_RX1_P")
			(pinfunction "PCIE0_RX1_P")
			(pintype "passive")
		)
		(pad "140" smd rect
			(at -1.381 -3.826 90)
			(size 1.75 0.3)
			(layers "F.Cu" "F.Paste" "F.Mask")
			(net 443 "PCIE0_TX1_N")
			(pinfunction "PCIE0_TX1_N")
			(pintype "passive")
		)
		(pad "141" smd rect
			(at -1.631 -12.026 90)
			(size 1.75 0.3)
			(layers "F.Cu" "F.Paste" "F.Mask")
			(net 1 "GND")
			(pinfunction "GND")
			(pintype "passive")
		)
		(pad "142" smd rect
			(at -1.881 -3.826 90)
			(size 1.75 0.3)
			(layers "F.Cu" "F.Paste" "F.Mask")
			(net 444 "PCIE0_TX1_P")
			(pinfunction "PCIE0_TX1_P")
			(pintype "passive")
		)
		(pad "143" smd rect
			(at -2.13 -12.026 90)
			(size 1.75 0.3)
			(layers "F.Cu" "F.Paste" "F.Mask")
			(net 100 "CAN_RX")
			(pinfunction "CAN_RX")
			(pintype "passive")
		)
		(pad "144" smd rect
			(at -2.38 -3.826 90)
			(size 1.75 0.3)
			(layers "F.Cu" "F.Paste" "F.Mask")
			(net 1 "GND")
			(pinfunction "GND")
			(pintype "passive")
		)
		(pad "145" smd rect
			(at -4.63 -12.026 90)
			(size 1.75 0.3)
			(layers "F.Cu" "F.Paste" "F.Mask")
			(net 101 "CAN_TX")
			(pinfunction "CAN_TX")
			(pintype "passive")
		)
		(pad "146" smd rect
			(at -4.88 -3.826 90)
			(size 1.75 0.3)
			(layers "F.Cu" "F.Paste" "F.Mask")
			(net 1 "GND")
			(pinfunction "GND")
			(pintype "passive")
		)
		(pad "147" smd rect
			(at -5.13 -12.026 90)
			(size 1.75 0.3)
			(layers "F.Cu" "F.Paste" "F.Mask")
			(net 1 "GND")
			(pinfunction "GND")
			(pintype "passive")
		)
		(pad "148" smd rect
			(at -5.38 -3.826 90)
			(size 1.75 0.3)
			(layers "F.Cu" "F.Paste" "F.Mask")
			(net 445 "PCIE0_TX2_N")
			(pinfunction "PCIE0_TX2_N")
			(pintype "passive")
		)
		(pad "149" smd rect
			(at -5.63 -12.026 90)
			(size 1.75 0.3)
			(layers "F.Cu" "F.Paste" "F.Mask")
			(net 51 "PCIE0_RX2_N")
			(pinfunction "PCIE0_RX2_N")
			(pintype "passive")
		)
		(pad "150" smd rect
			(at -5.88 -3.826 90)
			(size 1.75 0.3)
			(layers "F.Cu" "F.Paste" "F.Mask")
			(net 446 "PCIE0_TX2_P")
			(pinfunction "PCIE0_TX2_P")
			(pintype "passive")
		)
		(pad "151" smd rect
			(at -6.13 -12.026 90)
			(size 1.75 0.3)
			(layers "F.Cu" "F.Paste" "F.Mask")
			(net 52 "PCIE0_RX2_P")
			(pinfunction "PCIE0_RX2_P")
			(pintype "passive")
		)
		(pad "152" smd rect
			(at -6.38 -3.826 90)
			(size 1.75 0.3)
			(layers "F.Cu" "F.Paste" "F.Mask")
			(net 1 "GND")
			(pinfunction "GND")
			(pintype "passive")
		)
		(pad "153" smd rect
			(at -6.63 -12.026 90)
			(size 1.75 0.3)
			(layers "F.Cu" "F.Paste" "F.Mask")
			(net 1 "GND")
			(pinfunction "GND")
			(pintype "passive")
		)
		(pad "154" smd rect
			(at -6.88 -3.826 90)
			(size 1.75 0.3)
			(layers "F.Cu" "F.Paste" "F.Mask")
			(net 447 "PCIE0_TX3_N")
			(pinfunction "PCIE0_TX3_N")
			(pintype "passive")
		)
		(pad "155" smd rect
			(at -7.13 -12.026 90)
			(size 1.75 0.3)
			(layers "F.Cu" "F.Paste" "F.Mask")
			(net 53 "PCIE0_RX3_N")
			(pinfunction "PCIE0_RX3_N")
			(pintype "passive")
		)
		(pad "156" smd rect
			(at -7.38 -3.826 90)
			(size 1.75 0.3)
			(layers "F.Cu" "F.Paste" "F.Mask")
			(net 448 "PCIE0_TX3_P")
			(pinfunction "PCIE0_TX3_P")
			(pintype "passive")
		)
		(pad "157" smd rect
			(at -7.63 -12.026 90)
			(size 1.75 0.3)
			(layers "F.Cu" "F.Paste" "F.Mask")
			(net 54 "PCIE0_RX3_P")
			(pinfunction "PCIE0_RX3_P")
			(pintype "passive")
		)
		(pad "158" smd rect
			(at -7.88 -3.826 90)
			(size 1.75 0.3)
			(layers "F.Cu" "F.Paste" "F.Mask")
			(net 1 "GND")
			(pinfunction "GND")
			(pintype "passive")
		)
		(pad "159" smd rect
			(at -8.131 -12.026 90)
			(size 1.75 0.3)
			(layers "F.Cu" "F.Paste" "F.Mask")
			(net 1 "GND")
			(pinfunction "GND")
			(pintype "passive")
		)
		(pad "160" smd rect
			(at -8.381 -3.826 90)
			(size 1.75 0.3)
			(layers "F.Cu" "F.Paste" "F.Mask")
			(net 55 "PCIE0_CLK_N")
			(pinfunction "PCIE0_CLK_N")
			(pintype "passive")
		)
		(pad "161" smd rect
			(at -8.631 -12.026 90)
			(size 1.75 0.3)
			(layers "F.Cu" "F.Paste" "F.Mask")
			(net 56 "USBSS0_RX_N")
			(pinfunction "USBSS0_RX_N")
			(pintype "passive")
		)
		(pad "162" smd rect
			(at -8.881 -3.826 90)
			(size 1.75 0.3)
			(layers "F.Cu" "F.Paste" "F.Mask")
			(net 57 "PCIE0_CLK_P")
			(pinfunction "PCIE0_CLK_P")
			(pintype "passive")
		)
		(pad "163" smd rect
			(at -9.131 -12.026 90)
			(size 1.75 0.3)
			(layers "F.Cu" "F.Paste" "F.Mask")
			(net 58 "USBSS0_RX_P")
			(pinfunction "USBSS0_RX_P")
			(pintype "passive")
		)
		(pad "164" smd rect
			(at -9.381 -3.826 90)
			(size 1.75 0.3)
			(layers "F.Cu" "F.Paste" "F.Mask")
			(net 1 "GND")
			(pinfunction "GND")
			(pintype "passive")
		)
		(pad "165" smd rect
			(at -9.631 -12.026 90)
			(size 1.75 0.3)
			(layers "F.Cu" "F.Paste" "F.Mask")
			(net 1 "GND")
			(pinfunction "GND")
			(pintype "passive")
		)
		(pad "166" smd rect
			(at -9.881 -3.826 90)
			(size 1.75 0.3)
			(layers "F.Cu" "F.Paste" "F.Mask")
			(net 59 "USBSS0_TX_N")
			(pinfunction "USBSS0_TX_N")
			(pintype "passive")
		)
		(pad "167" smd rect
			(at -10.131 -12.026 90)
			(size 1.75 0.3)
			(layers "F.Cu" "F.Paste" "F.Mask")
			(net 60 "PCIE1_RX0_N")
			(pinfunction "PCIE1_RX0_N")
			(pintype "passive")
		)
		(pad "168" smd rect
			(at -10.381 -3.826 90)
			(size 1.75 0.3)
			(layers "F.Cu" "F.Paste" "F.Mask")
			(net 449 "USBSS0_TX_P")
			(pinfunction "USBSS0_TX_P")
			(pintype "passive")
		)
		(pad "169" smd rect
			(at -10.631 -12.026 90)
			(size 1.75 0.3)
			(layers "F.Cu" "F.Paste" "F.Mask")
			(net 61 "PCIE1_RX0_P")
			(pinfunction "PCIE1_RX0_P")
			(pintype "passive")
		)
		(pad "170" smd rect
			(at -10.881 -3.826 90)
			(size 1.75 0.3)
			(layers "F.Cu" "F.Paste" "F.Mask")
			(net 1 "GND")
			(pinfunction "GND")
			(pintype "passive")
		)
		(pad "171" smd rect
			(at -11.131 -12.026 90)
			(size 1.75 0.3)
			(layers "F.Cu" "F.Paste" "F.Mask")
			(net 1 "GND")
			(pinfunction "GND")
			(pintype "passive")
		)
		(pad "172" smd rect
			(at -11.381 -3.826 90)
			(size 1.75 0.3)
			(layers "F.Cu" "F.Paste" "F.Mask")
			(net 450 "PCIE1_TX0_N")
			(pinfunction "PCIE1_TX0_N")
			(pintype "passive")
		)
		(pad "173" smd rect
			(at -11.631 -12.026 90)
			(size 1.75 0.3)
			(layers "F.Cu" "F.Paste" "F.Mask")
			(net 62 "PCIE1_CLK_N")
			(pinfunction "PCIE1_CLK_N")
			(pintype "passive")
		)
		(pad "174" smd rect
			(at -11.881 -3.826 90)
			(size 1.75 0.3)
			(layers "F.Cu" "F.Paste" "F.Mask")
			(net 451 "PCIE1_TX0_P")
			(pinfunction "PCIE1_TX0_P")
			(pintype "passive")
		)
		(pad "175" smd rect
			(at -12.131 -12.026 90)
			(size 1.75 0.3)
			(layers "F.Cu" "F.Paste" "F.Mask")
			(net 63 "PCIE1_CLK_P")
			(pinfunction "PCIE1_CLK_P")
			(pintype "passive")
		)
		(pad "176" smd rect
			(at -12.381 -3.826 90)
			(size 1.75 0.3)
			(layers "F.Cu" "F.Paste" "F.Mask")
			(net 1 "GND")
			(pinfunction "GND")
			(pintype "passive")
		)
		(pad "177" smd rect
			(at -12.631 -12.026 90)
			(size 1.75 0.3)
			(layers "F.Cu" "F.Paste" "F.Mask")
			(net 1 "GND")
			(pinfunction "GND")
			(pintype "passive")
		)
		(pad "178" smd rect
			(at -12.881 -3.826 90)
			(size 1.75 0.3)
			(layers "F.Cu" "F.Paste" "F.Mask")
			(net 452 "/SoM/~{MOD_SLEEP}")
			(pinfunction "~{MOD_SLEEP}")
			(pintype "passive")
		)
		(pad "179" smd rect
			(at -13.131 -12.026 90)
			(size 1.75 0.3)
			(layers "F.Cu" "F.Paste" "F.Mask")
			(net 453 "PCIE_WAKE*")
			(pinfunction "~{PCIE_WAKE}")
			(pintype "passive")
		)
		(pad "180" smd rect
			(at -13.381 -3.826 90)
			(size 1.75 0.3)
			(layers "F.Cu" "F.Paste" "F.Mask")
			(net 454 "PCIE0_CLKREQ*")
			(pinfunction "~{PCIE0_CLKREQ}")
			(pintype "passive")
		)
		(pad "181" smd rect
			(at -13.631 -12.026 90)
			(size 1.75 0.3)
			(layers "F.Cu" "F.Paste" "F.Mask")
			(net 455 "PCIE0_RST*")
			(pinfunction "~{PCIE0_RST}")
			(pintype "passive")
		)
		(pad "182" smd rect
			(at -13.881 -3.826 90)
			(size 1.75 0.3)
			(layers "F.Cu" "F.Paste" "F.Mask")
			(net 64 "PCIE1_CLKREQ*")
			(pinfunction "~{PCIE1_CLKREQ}")
			(pintype "passive")
		)
		(pad "183" smd rect
			(at -14.131 -12.026 90)
			(size 1.75 0.3)
			(layers "F.Cu" "F.Paste" "F.Mask")
			(net 65 "PCIE1_RST*")
			(pinfunction "~{PCIE1_RST}")
			(pintype "passive")
		)
		(pad "184" smd rect
			(at -14.381 -3.826 90)
			(size 1.75 0.3)
			(layers "F.Cu" "F.Paste" "F.Mask")
			(net 66 "GBE_MDI0_N")
			(pinfunction "GBE_MDI0_N")
			(pintype "passive")
		)
		(pad "185" smd rect
			(at -14.631 -12.026 90)
			(size 1.75 0.3)
			(layers "F.Cu" "F.Paste" "F.Mask")
			(net 252 "SYS_SCL")
			(pinfunction "I2C0_SCL")
			(pintype "passive")
		)
		(pad "186" smd rect
			(at -14.881 -3.826 90)
			(size 1.75 0.3)
			(layers "F.Cu" "F.Paste" "F.Mask")
			(net 67 "GBE_MDI0_P")
			(pinfunction "GBE_MDI0_P")
			(pintype "passive")
		)
		(pad "187" smd rect
			(at -15.131 -12.026 90)
			(size 1.75 0.3)
			(layers "F.Cu" "F.Paste" "F.Mask")
			(net 251 "SYS_SDA")
			(pinfunction "I2C0_SDA")
			(pintype "passive")
		)
		(pad "188" smd rect
			(at -15.381 -3.826 90)
			(size 1.75 0.3)
			(layers "F.Cu" "F.Paste" "F.Mask")
			(net 457 "GBE_LED_LINK")
			(pinfunction "GBE_LED_LINK")
			(pintype "passive")
		)
		(pad "189" smd rect
			(at -15.631 -12.026 90)
			(size 1.75 0.3)
			(layers "F.Cu" "F.Paste" "F.Mask")
			(net 659 "I2C1_SCL")
			(pinfunction "I2C1_SCL")
			(pintype "passive")
		)
		(pad "190" smd rect
			(at -15.881 -3.826 90)
			(size 1.75 0.3)
			(layers "F.Cu" "F.Paste" "F.Mask")
			(net 68 "GBE_MDI1_N")
			(pinfunction "GBE_MDI1_N")
			(pintype "passive")
		)
		(pad "191" smd rect
			(at -16.13 -12.026 90)
			(size 1.75 0.3)
			(layers "F.Cu" "F.Paste" "F.Mask")
			(net 660 "I2C1_SDA")
			(pinfunction "I2C1_SDA")
			(pintype "passive")
		)
		(pad "192" smd rect
			(at -16.38 -3.826 90)
			(size 1.75 0.3)
			(layers "F.Cu" "F.Paste" "F.Mask")
			(net 69 "GBE_MDI1_P")
			(pinfunction "GBE_MDI1_P")
			(pintype "passive")
		)
		(pad "193" smd rect
			(at -16.63 -12.026 90)
			(size 1.75 0.3)
			(layers "F.Cu" "F.Paste" "F.Mask")
			(net 70 "I2S0_SDOUT")
			(pinfunction "I2S0_DOUT")
			(pintype "passive")
		)
		(pad "194" smd rect
			(at -16.88 -3.826 90)
			(size 1.75 0.3)
			(layers "F.Cu" "F.Paste" "F.Mask")
			(net 459 "GBE_LED_ACT")
			(pinfunction "GBE_LED_ACT")
			(pintype "passive")
		)
		(pad "195" smd rect
			(at -17.13 -12.026 90)
			(size 1.75 0.3)
			(layers "F.Cu" "F.Paste" "F.Mask")
			(net 71 "I2S0_SDIN")
			(pinfunction "I2S0_DIN")
			(pintype "passive")
		)
		(pad "196" smd rect
			(at -17.38 -3.826 90)
			(size 1.75 0.3)
			(layers "F.Cu" "F.Paste" "F.Mask")
			(net 72 "GBE_MDI2_N")
			(pinfunction "GBE_MDI2_N")
			(pintype "passive")
		)
		(pad "197" smd rect
			(at -17.63 -12.026 90)
			(size 1.75 0.3)
			(layers "F.Cu" "F.Paste" "F.Mask")
			(net 73 "I2S0_LRCK")
			(pinfunction "I2S0_FS")
			(pintype "passive")
		)
		(pad "198" smd rect
			(at -17.88 -3.826 90)
			(size 1.75 0.3)
			(layers "F.Cu" "F.Paste" "F.Mask")
			(net 74 "GBE_MDI2_P")
			(pinfunction "GBE_MDI2_P")
			(pintype "passive")
		)
		(pad "199" smd rect
			(at -18.13 -12.026 90)
			(size 1.75 0.3)
			(layers "F.Cu" "F.Paste" "F.Mask")
			(net 75 "I2S0_SCLK")
			(pinfunction "I2S0_SCLK")
			(pintype "passive")
		)
		(pad "200" smd rect
			(at -18.38 -3.826 90)
			(size 1.75 0.3)
			(layers "F.Cu" "F.Paste" "F.Mask")
			(net 1 "GND")
			(pinfunction "GND")
			(pintype "passive")
		)
		(pad "201" smd rect
			(at -18.63 -12.026 90)
			(size 1.75 0.3)
			(layers "F.Cu" "F.Paste" "F.Mask")
			(net 1 "GND")
			(pinfunction "GND")
			(pintype "passive")
		)
		(pad "202" smd rect
			(at -18.88 -3.826 90)
			(size 1.75 0.3)
			(layers "F.Cu" "F.Paste" "F.Mask")
			(net 76 "GBE_MDI3_N")
			(pinfunction "GBE_MDI3_N")
			(pintype "passive")
		)
		(pad "203" smd rect
			(at -19.13 -12.026 90)
			(size 1.75 0.3)
			(layers "F.Cu" "F.Paste" "F.Mask")
			(net 460 "UART1_TXD")
			(pinfunction "UART1_TXD")
			(pintype "passive")
		)
		(pad "204" smd rect
			(at -19.38 -3.826 90)
			(size 1.75 0.3)
			(layers "F.Cu" "F.Paste" "F.Mask")
			(net 77 "GBE_MDI3_P")
			(pinfunction "GBE_MDI3_P")
			(pintype "passive")
		)
		(pad "205" smd rect
			(at -19.63 -12.026 90)
			(size 1.75 0.3)
			(layers "F.Cu" "F.Paste" "F.Mask")
			(net 461 "UART1_RXD")
			(pinfunction "UART1_RXD")
			(pintype "passive")
		)
		(pad "206" smd rect
			(at -19.88 -3.826 90)
			(size 1.75 0.3)
			(layers "F.Cu" "F.Paste" "F.Mask")
			(net 102 "GPIO07")
			(pinfunction "GPIO07/PWM")
			(pintype "passive")
		)
		(pad "207" smd rect
			(at -20.13 -12.026 90)
			(size 1.75 0.3)
			(layers "F.Cu" "F.Paste" "F.Mask")
			(net 748 "unconnected-(J15C-~{UART1_RTS}-Pad207)")
			(pinfunction "~{UART1_RTS}")
			(pintype "passive+no_connect")
		)
		(pad "208" smd rect
			(at -20.38 -3.826 90)
			(size 1.75 0.3)
			(layers "F.Cu" "F.Paste" "F.Mask")
			(net 463 "FAN_TACH")
			(pinfunction "Fan_Tach/GPIO08")
			(pintype "passive")
		)
		(pad "209" smd rect
			(at -20.63 -12.026 90)
			(size 1.75 0.3)
			(layers "F.Cu" "F.Paste" "F.Mask")
			(net 749 "unconnected-(J15C-~{UART1_CTS}-Pad209)")
			(pinfunction "~{UART1_CTS}")
			(pintype "passive+no_connect")
		)
		(pad "210" smd rect
			(at -20.88 -3.826 90)
			(size 1.75 0.3)
			(layers "F.Cu" "F.Paste" "F.Mask")
			(net 750 "Net-(J15A-CLK_32K_OUT)")
			(pinfunction "CLK_32K_OUT")
			(pintype "passive")
		)
		(pad "211" smd rect
			(at -21.13 -12.026 90)
			(size 1.75 0.3)
			(layers "F.Cu" "F.Paste" "F.Mask")
			(net 78 "GPIO09")
			(pinfunction "GPIO09/AUD_MCLK")
			(pintype "passive")
		)
		(pad "212" smd rect
			(at -21.38 -3.826 90)
			(size 1.75 0.3)
			(layers "F.Cu" "F.Paste" "F.Mask")
			(net 714 "GPIO010")
			(pinfunction "GPIO10")
			(pintype "passive")
		)
		(pad "213" smd rect
			(at -21.63 -12.026 90)
			(size 1.75 0.3)
			(layers "F.Cu" "F.Paste" "F.Mask")
			(net 81 "SCL_CAM")
			(pinfunction "CAM_I2C_SCL")
			(pintype "passive")
		)
		(pad "214" smd rect
			(at -21.88 -3.826 90)
			(size 1.75 0.3)
			(layers "F.Cu" "F.Paste" "F.Mask")
			(net 80 "/SoM/~{FORCE_RECOVERY}")
			(pinfunction "~{FORCE_RECOVERY}")
			(pintype "passive")
		)
		(pad "215" smd rect
			(at -22.13 -12.026 90)
			(size 1.75 0.3)
			(layers "F.Cu" "F.Paste" "F.Mask")
			(net 79 "SDA_CAM")
			(pinfunction "CAM_I2C_SDA")
			(pintype "passive")
		)
		(pad "216" smd rect
			(at -22.38 -3.826 90)
			(size 1.75 0.3)
			(layers "F.Cu" "F.Paste" "F.Mask")
			(net 82 "GPIO11")
			(pinfunction "GPIO11/CLK")
			(pintype "passive")
		)
		(pad "217" smd rect
			(at -22.63 -12.026 90)
			(size 1.75 0.3)
			(layers "F.Cu" "F.Paste" "F.Mask")
			(net 789 "MODULE_ID")
			(pinfunction "GND(MODULE_ID)")
			(pintype "passive")
		)
		(pad "218" smd rect
			(at -22.88 -3.826 90)
			(size 1.75 0.3)
			(layers "F.Cu" "F.Paste" "F.Mask")
			(net 752 "Net-(J15H-GPIO12{slash}PWM)")
			(pinfunction "GPIO12/PWM")
			(pintype "passive")
		)
		(pad "219" smd rect
			(at -23.13 -12.026 90)
			(size 1.75 0.3)
			(layers "F.Cu" "F.Paste" "F.Mask")
			(net 103 "PCIE2_RST*")
			(pinfunction "~{PCIE2_RST}")
			(pintype "passive")
		)
		(pad "220" smd rect
			(at -23.38 -3.826 90)
			(size 1.75 0.3)
			(layers "F.Cu" "F.Paste" "F.Mask")
			(net 467 "I2S1_SDOUT")
			(pinfunction "I2S1_DOUT")
			(pintype "passive")
		)
		(pad "221" smd rect
			(at -23.63 -12.026 90)
			(size 1.75 0.3)
			(layers "F.Cu" "F.Paste" "F.Mask")
			(net 104 "PCIE2_CLKREQ*")
			(pinfunction "~{PCIE2_CLKREQ}")
			(pintype "passive")
		)
		(pad "222" smd rect
			(at -23.88 -3.826 90)
			(size 1.75 0.3)
			(layers "F.Cu" "F.Paste" "F.Mask")
			(net 468 "I2S1_SDIN")
			(pinfunction "I2S1_DIN")
			(pintype "passive")
		)
		(pad "223" smd rect
			(at -24.13 -12.026 90)
			(size 1.75 0.3)
			(layers "F.Cu" "F.Paste" "F.Mask")
			(net 120 "PCIE3_RST*")
			(pinfunction "~{PCIE3_RST}")
			(pintype "passive")
		)
		(pad "224" smd rect
			(at -24.38 -3.826 90)
			(size 1.75 0.3)
			(layers "F.Cu" "F.Paste" "F.Mask")
			(net 469 "I2S1_LRCK")
			(pinfunction "I2S1_FS")
			(pintype "passive")
		)
		(pad "225" smd rect
			(at -24.63 -12.026 90)
			(size 1.75 0.3)
			(layers "F.Cu" "F.Paste" "F.Mask")
			(net 128 "PCIE3_CLKREQ*")
			(pinfunction "~{PCIE3_CLKREQ}")
			(pintype "passive")
		)
		(pad "226" smd rect
			(at -24.88 -3.826 90)
			(size 1.75 0.3)
			(layers "F.Cu" "F.Paste" "F.Mask")
			(net 470 "I2S1_SCLK")
			(pinfunction "I2S1_SCLK")
			(pintype "passive")
		)
		(pad "227" smd rect
			(at -25.13 -12.026 90)
			(size 1.75 0.3)
			(layers "F.Cu" "F.Paste" "F.Mask")
			(net 471 "PCIE3_CLK_N")
			(pinfunction "PCIE3_CLK_N")
			(pintype "passive")
		)
		(pad "228" smd rect
			(at -25.38 -3.826 90)
			(size 1.75 0.3)
			(layers "F.Cu" "F.Paste" "F.Mask")
			(net 753 "Net-(J15H-GPIO13{slash}PWM)")
			(pinfunction "GPIO13/PWM")
			(pintype "passive")
		)
		(pad "229" smd rect
			(at -25.63 -12.026 90)
			(size 1.75 0.3)
			(layers "F.Cu" "F.Paste" "F.Mask")
			(net 472 "PCIE3_CLK_P")
			(pinfunction "PCIE3_CLK_P")
			(pintype "passive")
		)
		(pad "230" smd rect
			(at -25.88 -3.826 90)
			(size 1.75 0.3)
			(layers "F.Cu" "F.Paste" "F.Mask")
			(net 473 "FAN_PWM")
			(pinfunction "GPIO14/PWM")
			(pintype "passive")
		)
		(pad "231" smd rect
			(at -26.13 -12.026 90)
			(size 1.75 0.3)
			(layers "F.Cu" "F.Paste" "F.Mask")
			(net 1 "GND")
			(pinfunction "GND")
			(pintype "passive")
		)
		(pad "232" smd rect
			(at -26.38 -3.826 90)
			(size 1.75 0.3)
			(layers "F.Cu" "F.Paste" "F.Mask")
			(net 129 "I2C2_SCL")
			(pinfunction "I2C2_SCL")
			(pintype "passive")
		)
		(pad "233" smd rect
			(at -26.63 -12.026 90)
			(size 1.75 0.3)
			(layers "F.Cu" "F.Paste" "F.Mask")
			(net 474 "~{SHUTDOWN_REQ}")
			(pinfunction "~{SHUTDOWN_REQ}")
			(pintype "passive")
		)
		(pad "234" smd rect
			(at -26.88 -3.826 90)
			(size 1.75 0.3)
			(layers "F.Cu" "F.Paste" "F.Mask")
			(net 130 "I2C2_SDA")
			(pinfunction "I2C2_SDA")
			(pintype "passive")
		)
		(pad "235" smd rect
			(at -27.13 -12.026 90)
			(size 1.75 0.3)
			(layers "F.Cu" "F.Paste" "F.Mask")
			(net 85 "/SoM/PMIC_BBAT")
			(pinfunction "PMIC_BBAT")
			(pintype "passive")
		)
		(pad "236" smd rect
			(at -27.38 -3.826 90)
			(size 1.75 0.3)
			(layers "F.Cu" "F.Paste" "F.Mask")
			(net 168 "/SoM/DEBUG_TXD_1V8")
			(pinfunction "UART2_TXD")
			(pintype "passive")
		)
		(pad "237" smd rect
			(at -27.63 -12.026 90)
			(size 1.75 0.3)
			(layers "F.Cu" "F.Paste" "F.Mask")
			(net 476 "POWER_EN")
			(pinfunction "POWER_EN")
			(pintype "passive")
		)
		(pad "238" smd rect
			(at -27.88 -3.826 90)
			(size 1.75 0.3)
			(layers "F.Cu" "F.Paste" "F.Mask")
			(net 327 "/SoM/DEBUG_RXD_1V8")
			(pinfunction "UART2_RXD")
			(pintype "passive")
		)
		(pad "239" smd rect
			(at -28.13 -12.026 90)
			(size 1.75 0.3)
			(layers "F.Cu" "F.Paste" "F.Mask")
			(net 86 "~{RESET}")
			(pinfunction "~{SYS_RESET}")
			(pintype "passive")
		)
		(pad "240" smd rect
			(at -28.38 -3.826 90)
			(size 1.75 0.3)
			(layers "F.Cu" "F.Paste" "F.Mask")
			(net 478 "/SoM/SLEEP{slash}~{WAKE}")
			(pinfunction "SLEEP/~{WAKE}")
			(pintype "passive")
		)
		(pad "241" smd rect
			(at -28.63 -12.026 90)
			(size 1.75 0.3)
			(layers "F.Cu" "F.Paste" "F.Mask")
			(net 1 "GND")
			(pinfunction "GND")
			(pintype "passive")
		)
		(pad "242" smd rect
			(at -28.88 -3.826 90)
			(size 1.75 0.3)
			(layers "F.Cu" "F.Paste" "F.Mask")
			(net 1 "GND")
			(pinfunction "GND")
			(pintype "passive")
		)
		(pad "243" smd rect
			(at -29.13 -12.026 90)
			(size 1.75 0.3)
			(layers "F.Cu" "F.Paste" "F.Mask")
			(net 1 "GND")
			(pinfunction "GND")
			(pintype "passive")
		)
		(pad "244" smd rect
			(at -29.38 -3.826 90)
			(size 1.75 0.3)
			(layers "F.Cu" "F.Paste" "F.Mask")
			(net 1 "GND")
			(pinfunction "GND")
			(pintype "passive")
		)
		(pad "245" smd rect
			(at -29.63 -12.026 90)
			(size 1.75 0.3)
			(layers "F.Cu" "F.Paste" "F.Mask")
			(net 1 "GND")
			(pinfunction "GND")
			(pintype "passive")
		)
		(pad "246" smd rect
			(at -29.88 -3.826 90)
			(size 1.75 0.3)
			(layers "F.Cu" "F.Paste" "F.Mask")
			(net 1 "GND")
			(pinfunction "GND")
			(pintype "passive")
		)
		(pad "247" smd rect
			(at -30.13 -12.026 90)
			(size 1.75 0.3)
			(layers "F.Cu" "F.Paste" "F.Mask")
			(net 1 "GND")
			(pinfunction "GND")
			(pintype "passive")
		)
		(pad "248" smd rect
			(at -30.38 -3.826 90)
			(size 1.75 0.3)
			(layers "F.Cu" "F.Paste" "F.Mask")
			(net 1 "GND")
			(pinfunction "GND")
			(pintype "passive")
		)
		(pad "249" smd rect
			(at -30.63 -12.026 90)
			(size 1.75 0.3)
			(layers "F.Cu" "F.Paste" "F.Mask")
			(net 1 "GND")
			(pinfunction "GND")
			(pintype "passive")
		)
		(pad "250" smd rect
			(at -30.88 -3.826 90)
			(size 1.75 0.3)
			(layers "F.Cu" "F.Paste" "F.Mask")
			(net 1 "GND")
			(pinfunction "GND")
			(pintype "passive")
		)
		(pad "251" smd rect
			(at -31.13 -12.026 90)
			(size 1.75 0.3)
			(layers "F.Cu" "F.Paste" "F.Mask")
			(net 438 "/SoM/SoM_VIN")
			(pinfunction "VDD_IN")
			(pintype "passive")
		)
		(pad "252" smd rect
			(at -31.38 -3.826 90)
			(size 1.75 0.3)
			(layers "F.Cu" "F.Paste" "F.Mask")
			(net 438 "/SoM/SoM_VIN")
			(pinfunction "VDD_IN")
			(pintype "passive")
		)
		(pad "253" smd rect
			(at -31.63 -12.026 90)
			(size 1.75 0.3)
			(layers "F.Cu" "F.Paste" "F.Mask")
			(net 438 "/SoM/SoM_VIN")
			(pinfunction "VDD_IN")
			(pintype "passive")
		)
		(pad "254" smd rect
			(at -31.88 -3.826 90)
			(size 1.75 0.3)
			(layers "F.Cu" "F.Paste" "F.Mask")
			(net 438 "/SoM/SoM_VIN")
			(pinfunction "VDD_IN")
			(pintype "passive")
		)
		(pad "255" smd rect
			(at -32.131 -12.026 90)
			(size 1.75 0.3)
			(layers "F.Cu" "F.Paste" "F.Mask")
			(net 438 "/SoM/SoM_VIN")
			(pinfunction "VDD_IN")
			(pintype "passive")
		)
		(pad "256" smd rect
			(at -32.381 -3.826 90)
			(size 1.75 0.3)
			(layers "F.Cu" "F.Paste" "F.Mask")
			(net 438 "/SoM/SoM_VIN")
			(pinfunction "VDD_IN")
			(pintype "passive")
		)
		(pad "257" smd rect
			(at -32.631 -12.026 90)
			(size 1.75 0.3)
			(layers "F.Cu" "F.Paste" "F.Mask")
			(net 438 "/SoM/SoM_VIN")
			(pinfunction "VDD_IN")
			(pintype "passive")
		)
		(pad "258" smd rect
			(at -32.881 -3.826 90)
			(size 1.75 0.3)
			(layers "F.Cu" "F.Paste" "F.Mask")
			(net 438 "/SoM/SoM_VIN")
			(pinfunction "VDD_IN")
			(pintype "passive")
		)
		(pad "259" smd rect
			(at -33.131 -12.026 90)
			(size 1.75 0.3)
			(layers "F.Cu" "F.Paste" "F.Mask")
			(net 438 "/SoM/SoM_VIN")
			(pinfunction "VDD_IN")
			(pintype "passive")
		)
		(pad "260" smd rect
			(at -33.381 -3.826 90)
			(size 1.75 0.3)
			(layers "F.Cu" "F.Paste" "F.Mask")
			(net 438 "/SoM/SoM_VIN")
			(pinfunction "VDD_IN")
			(pintype "passive")
		)
		(pad "261" smd rect
			(at -37.756 0.073 180)
			(size 2 3.5)
			(layers "F.Cu" "F.Paste" "F.Mask")
			(net 754 "unconnected-(J15A-MP-Pad261)")
			(pinfunction "MP")
			(pintype "passive+no_connect")
		)
		(pad "262" smd rect
			(at 37.744 4.073 180)
			(size 2 3.5)
			(layers "F.Cu" "F.Paste" "F.Mask")
			(net 755 "unconnected-(J15A-MP-Pad262)")
			(pinfunction "MP")
			(pintype "passive+no_connect")
		)
	)
	(footprint "antmicro-footprints:SOT-523"
		(layer "F.Cu")
		(at 101.3 89.75 90)
		(property "Reference" "Q1"
			(at -0.325 -2.65 180)
			(layer "F.SilkS")
			(effects
				(font
					(size 0.7 0.7)
					(thickness 0.15)
				)
				(justify left bottom)
			)
		)
		(property "Value" "PJE138K"
			(at 0.1 1.824 90)
			(layer "F.Fab")
			(effects
				(font
					(size 0.7 0.7)
					(thickness 0.15)
				)
				(justify left bottom)
			)
		)
		(property "Footprint" "antmicro-footprints:SOT-523"
			(at 0 0 90)
			(layer "F.Fab")
			(hide yes)
			(effects
				(font
					(size 1.27 1.27)
					(thickness 0.15)
				)
			)
		)
		(property "Datasheet" "https://www.mouser.com/datasheet/2/1057/PJE138K-1876698.pdf"
			(at 0 0 90)
			(layer "F.Fab")
			(hide yes)
			(effects
				(font
					(size 1.27 1.27)
					(thickness 0.15)
				)
			)
		)
		(property "Author" "Antmicro"
			(at 191.05 -11.55 0)
			(layer "F.Fab")
			(hide yes)
			(effects
				(font
					(size 1 1)
					(thickness 0.15)
				)
			)
		)
		(property "License" "Apache-2.0"
			(at 191.05 -11.55 0)
			(layer "F.Fab")
			(hide yes)
			(effects
				(font
					(size 1 1)
					(thickness 0.15)
				)
			)
		)
		(property "MPN" "PJE138K_R1_00001"
			(at 191.05 -11.55 0)
			(layer "F.Fab")
			(hide yes)
			(effects
				(font
					(size 1 1)
					(thickness 0.15)
				)
			)
		)
		(property "Manufacturer" "PANJIT"
			(at 191.05 -11.55 0)
			(layer "F.Fab")
			(hide yes)
			(effects
				(font
					(size 1 1)
					(thickness 0.15)
				)
			)
		)
		(sheetname "HDMI")
		(sheetfile "hdmi.kicad_sch")
		(attr smd)
		(fp_line
			(start -0.277 -0.551)
			(end -0.277 -0.75)
			(stroke
				(width 0.15)
				(type solid)
			)
			(layer "F.SilkS")
		)
		(fp_line
			(start -0.725 -0.551)
			(end -0.277 -0.551)
			(stroke
				(width 0.15)
				(type solid)
			)
			(layer "F.SilkS")
		)
		(fp_line
			(start -0.927 -0.351)
			(end -0.725 -0.551)
			(stroke
				(width 0.15)
				(type solid)
			)
			(layer "F.SilkS")
		)
		(fp_line
			(start -0.927 -0.051)
			(end -0.927 -0.351)
			(stroke
				(width 0.15)
				(type solid)
			)
			(layer "F.SilkS")
		)
		(fp_circle
			(center -0.9652 0.9652)
			(end -0.9152 0.9652)
			(stroke
				(width 0.15)
				(type solid)
			)
			(fill solid)
			(layer "F.SilkS")
		)
		(fp_line
			(start 1.1 -1.16)
			(end 1.1 1.15)
			(stroke
				(width 0.05)
				(type solid)
			)
			(layer "F.CrtYd")
		)
		(fp_line
			(start -1.12 -1.16)
			(end 1.1 -1.16)
			(stroke
				(width 0.05)
				(type solid)
			)
			(layer "F.CrtYd")
		)
		(fp_line
			(start -1.12 -1.16)
			(end -1.12 1.15)
			(stroke
				(width 0.05)
				(type solid)
			)
			(layer "F.CrtYd")
		)
		(fp_line
			(start -1.12 1.15)
			(end 1.1 1.15)
			(stroke
				(width 0.05)
				(type solid)
			)
			(layer "F.CrtYd")
		)
		(fp_line
			(start 0.8 -0.425)
			(end -0.652 -0.425)
			(stroke
				(width 0.15)
				(type solid)
			)
			(layer "F.Fab")
		)
		(fp_line
			(start 0.8 -0.425)
			(end 0.8 0.424)
			(stroke
				(width 0.15)
				(type solid)
			)
			(layer "F.Fab")
		)
		(fp_line
			(start -0.652 -0.425)
			(end -0.802 -0.276)
			(stroke
				(width 0.15)
				(type solid)
			)
			(layer "F.Fab")
		)
		(fp_line
			(start -0.802 -0.276)
			(end -0.802 0.424)
			(stroke
				(width 0.15)
				(type solid)
			)
			(layer "F.Fab")
		)
		(fp_line
			(start 0.8 0.424)
			(end -0.802 0.424)
			(stroke
				(width 0.15)
				(type solid)
			)
			(layer "F.Fab")
		)
		(fp_circle
			(center -0.9652 0.9652)
			(end -0.9144 0.9652)
			(stroke
				(width 0.15)
				(type solid)
			)
			(fill none)
			(layer "F.Fab")
		)
		(fp_text user "License: Apache-2.0"
			(at -1.12 5.024 90)
			(layer "F.Fab")
			(hide yes)
			(effects
				(font
					(size 0.7 0.7)
					(thickness 0.15)
				)
				(justify left bottom)
			)
		)
		(fp_text user "${REFERENCE}"
			(at -1.12 3.824 90)
			(layer "F.Fab")
			(hide yes)
			(effects
				(font
					(size 0.7 0.7)
					(thickness 0.15)
				)
				(justify left bottom)
			)
		)
		(fp_text user "Author: Antmicro"
			(at -1.12 6.224 90)
			(layer "F.Fab")
			(hide yes)
			(effects
				(font
					(size 0.7 0.7)
					(thickness 0.15)
				)
				(justify left bottom)
			)
		)
		(pad "1" smd rect
			(at -0.5 0.65 90)
			(size 0.4 0.51)
			(layers "F.Cu" "F.Paste" "F.Mask")
			(net 112 "+1V8")
			(pinfunction "G")
			(pintype "passive")
		)
		(pad "2" smd rect
			(at 0.498 0.65 90)
			(size 0.4 0.51)
			(layers "F.Cu" "F.Paste" "F.Mask")
			(net 621 "Net-(Q1-S)")
			(pinfunction "S")
			(pintype "passive")
		)
		(pad "3" smd rect
			(at 0 -0.652 90)
			(size 0.4 0.51)
			(layers "F.Cu" "F.Paste" "F.Mask")
			(net 622 "Net-(Q1-D)")
			(pinfunction "D")
			(pintype "passive")
		)
	)
	(footprint "antmicro-footprints:XDFN-2_1x0.60mm"
		(layer "F.Cu")
		(at 137.8 84.15 -90)
		(property "Reference" "D48"
			(at 0.298 -0.402 180)
			(layer "F.SilkS")
			(effects
				(font
					(size 0.7 0.7)
					(thickness 0.15)
				)
				(justify left bottom)
			)
		)
		(property "Value" "TPD1E0B04_XDFN-2"
			(at 0 1.5 -90)
			(layer "F.Fab")
			(effects
				(font
					(size 0.7 0.7)
					(thickness 0.15)
				)
				(justify left bottom)
			)
		)
		(property "Footprint" "antmicro-footprints:XDFN-2_1x0.60mm"
			(at 0 0 -90)
			(layer "F.Fab")
			(hide yes)
			(effects
				(font
					(size 1.27 1.27)
					(thickness 0.15)
				)
			)
		)
		(property "Datasheet" "https://www.ti.com/general/docs/suppproductinfo.tsp?distId=26&gotoUrl=https://www.ti.com/lit/gpn/tpd1e0b04"
			(at 0 0 -90)
			(layer "F.Fab")
			(hide yes)
			(effects
				(font
					(size 1.27 1.27)
					(thickness 0.15)
				)
			)
		)
		(property "MPN" "TPD1E0B04DPYR"
			(at 53.65 221.95 0)
			(layer "F.Fab")
			(hide yes)
			(effects
				(font
					(size 1 1)
					(thickness 0.15)
				)
			)
		)
		(property "Manufacturer" "Texas Instruments"
			(at 53.65 221.95 0)
			(layer "F.Fab")
			(hide yes)
			(effects
				(font
					(size 1 1)
					(thickness 0.15)
				)
			)
		)
		(property "Author" "Antmicro"
			(at 53.65 221.95 0)
			(layer "F.Fab")
			(hide yes)
			(effects
				(font
					(size 1 1)
					(thickness 0.15)
				)
			)
		)
		(property "License" "Apache-2.0"
			(at 53.65 221.95 0)
			(layer "F.Fab")
			(hide yes)
			(effects
				(font
					(size 1 1)
					(thickness 0.15)
				)
			)
		)
		(sheetname "Peripherals")
		(sheetfile "peripherals.kicad_sch")
		(attr smd)
		(fp_rect
			(start -0.725 -0.475)
			(end 0.725 0.475)
			(stroke
				(width 0.05)
				(type solid)
			)
			(fill none)
			(layer "F.CrtYd")
		)
		(fp_rect
			(start -0.55 -0.35)
			(end 0.55 0.35)
			(stroke
				(width 0.15)
				(type solid)
			)
			(fill none)
			(layer "F.Fab")
		)
		(fp_text user "${REFERENCE}"
			(at -0.8 3.2 -90)
			(layer "F.Fab")
			(hide yes)
			(effects
				(font
					(size 0.7 0.7)
					(thickness 0.15)
				)
				(justify left bottom)
			)
		)
		(fp_text user "License: Apache-2.0"
			(at -0.8 5.6 -90)
			(layer "F.Fab")
			(hide yes)
			(effects
				(font
					(size 0.7 0.7)
					(thickness 0.15)
				)
				(justify left bottom)
			)
		)
		(fp_text user "Author: Antmicro"
			(at -0.8 4.4 -90)
			(layer "F.Fab")
			(hide yes)
			(effects
				(font
					(size 0.7 0.7)
					(thickness 0.15)
				)
				(justify left bottom)
			)
		)
		(pad "1" smd roundrect
			(at -0.351 0 270)
			(size 0.3 0.5)
			(layers "F.Cu" "F.Paste" "F.Mask")
			(roundrect_rratio 0.25)
			(net 413 "/Peripherals/PCIE2_TX1_CONN_P")
			(pinfunction "C")
			(pintype "passive")
		)
		(pad "2" smd roundrect
			(at 0.349 0 270)
			(size 0.3 0.5)
			(layers "F.Cu" "F.Paste" "F.Mask")
			(roundrect_rratio 0.25)
			(net 1 "GND")
			(pinfunction "A")
			(pintype "passive")
		)
	)
	(footprint "antmicro-footprints:R_0402_1005Metric"
		(layer "F.Cu")
		(at 101.35 91.4)
		(descr "Resistor SMD 0402")
		(tags "resistor SMD 0402")
		(property "Reference" "R49"
			(at -1.05 1.35 0)
			(layer "F.SilkS")
			(effects
				(font
					(size 0.7 0.7)
					(thickness 0.15)
				)
				(justify left bottom)
			)
		)
		(property "Value" "R_10k_0402"
			(at 0 1.4 0)
			(layer "F.Fab")
			(effects
				(font
					(size 0.7 0.7)
					(thickness 0.15)
				)
				(justify left bottom)
			)
		)
		(property "Footprint" "antmicro-footprints:R_0402_1005Metric"
			(at 0 0 0)
			(layer "F.Fab")
			(hide yes)
			(effects
				(font
					(size 1.27 1.27)
					(thickness 0.15)
				)
			)
		)
		(property "Datasheet" "https://www.bourns.com/docs/product-datasheets/cr.pdf"
			(at 0 0 0)
			(layer "F.Fab")
			(hide yes)
			(effects
				(font
					(size 1.27 1.27)
					(thickness 0.15)
				)
			)
		)
		(property "Author" "Antmicro"
			(at 0 0 0)
			(layer "F.Fab")
			(hide yes)
			(effects
				(font
					(size 1 1)
					(thickness 0.15)
				)
			)
		)
		(property "License" "Apache-2.0"
			(at 0 0 0)
			(layer "F.Fab")
			(hide yes)
			(effects
				(font
					(size 1 1)
					(thickness 0.15)
				)
			)
		)
		(property "MPN" "CR0402-FX-1002GLF"
			(at 0 0 0)
			(layer "F.Fab")
			(hide yes)
			(effects
				(font
					(size 1 1)
					(thickness 0.15)
				)
			)
		)
		(property "Manufacturer" "Bourns"
			(at 0 0 0)
			(layer "F.Fab")
			(hide yes)
			(effects
				(font
					(size 1 1)
					(thickness 0.15)
				)
			)
		)
		(property "Tolerance" "1%"
			(at 0 0 0)
			(layer "F.Fab")
			(hide yes)
			(effects
				(font
					(size 1 1)
					(thickness 0.15)
				)
			)
		)
		(property "Val" "10k"
			(at 0 0 0)
			(layer "F.Fab")
			(hide yes)
			(effects
				(font
					(size 1 1)
					(thickness 0.15)
				)
			)
		)
		(sheetname "HDMI")
		(sheetfile "hdmi.kicad_sch")
		(attr smd)
		(fp_rect
			(start -0.925 -0.47)
			(end 0.925 0.47)
			(stroke
				(width 0.05)
				(type default)
			)
			(fill none)
			(layer "F.CrtYd")
		)
		(fp_rect
			(start -0.5 -0.25)
			(end 0.5 0.25)
			(stroke
				(width 0.15)
				(type solid)
			)
			(fill none)
			(layer "F.Fab")
		)
		(fp_text user "License: Apache-2.0"
			(at -0.95 5.169 0)
			(layer "F.Fab")
			(hide yes)
			(effects
				(font
					(size 0.7 0.7)
					(thickness 0.15)
				)
				(justify left bottom)
			)
		)
		(fp_text user "Author: Antmicro"
			(at -0.95 4.169 0)
			(layer "F.Fab")
			(hide yes)
			(effects
				(font
					(size 0.7 0.7)
					(thickness 0.15)
				)
				(justify left bottom)
			)
		)
		(fp_text user "${REFERENCE}"
			(at -0.95 3.168 0)
			(layer "F.Fab")
			(hide yes)
			(effects
				(font
					(size 0.7 0.7)
					(thickness 0.15)
				)
				(justify left bottom)
			)
		)
		(pad "1" smd roundrect
			(at -0.48 0)
			(size 0.59 0.64)
			(layers "F.Cu" "F.Paste" "F.Mask")
			(roundrect_rratio 0.25)
			(net 622 "Net-(Q1-D)")
			(pintype "passive")
		)
		(pad "2" smd roundrect
			(at 0.48 0)
			(size 0.59 0.64)
			(layers "F.Cu" "F.Paste" "F.Mask")
			(roundrect_rratio 0.25)
			(net 87 "+3V3")
			(pintype "passive")
		)
	)
	(footprint "antmicro-footprints:TP_SMD_0.75mm"
		(layer "F.Cu")
		(at 96.95 83.1 180)
		(property "Reference" "TP5"
			(at -0.25 -0.4 180)
			(layer "F.SilkS")
			(effects
				(font
					(size 0.7 0.7)
					(thickness 0.15)
				)
				(justify left bottom)
			)
		)
		(property "Value" "TP_0.75mm_SMD"
			(at 0 1.2 180)
			(layer "F.Fab")
			(effects
				(font
					(size 0.7 0.7)
					(thickness 0.15)
				)
				(justify left bottom)
			)
		)
		(property "Footprint" "antmicro-footprints:TP_SMD_0.75mm"
			(at 0 0 180)
			(layer "F.Fab")
			(hide yes)
			(effects
				(font
					(size 1.27 1.27)
					(thickness 0.15)
				)
			)
		)
		(property "Author" "Antmicro"
			(at 193.9 166.2 0)
			(layer "F.Fab")
			(hide yes)
			(effects
				(font
					(size 1 1)
					(thickness 0.15)
				)
			)
		)
		(property "License" "Apache-2.0"
			(at 193.9 166.2 0)
			(layer "F.Fab")
			(hide yes)
			(effects
				(font
					(size 1 1)
					(thickness 0.15)
				)
			)
		)
		(property "MPN" ""
			(at 193.9 166.2 0)
			(layer "F.Fab")
			(hide yes)
			(effects
				(font
					(size 1 1)
					(thickness 0.15)
				)
			)
		)
		(property "Manufacturer" ""
			(at 193.9 166.2 0)
			(layer "F.Fab")
			(hide yes)
			(effects
				(font
					(size 1 1)
					(thickness 0.15)
				)
			)
		)
		(sheetname "SoM")
		(sheetfile "som.kicad_sch")
		(attr exclude_from_pos_files exclude_from_bom)
		(fp_circle
			(center 0 0)
			(end 0.475 0)
			(stroke
				(width 0.05)
				(type default)
			)
			(fill none)
			(layer "F.CrtYd")
		)
		(fp_text user "${REFERENCE}"
			(at -0.4 2.7 180)
			(layer "F.Fab")
			(hide yes)
			(effects
				(font
					(size 0.7 0.7)
					(thickness 0.15)
				)
				(justify left bottom)
			)
		)
		(fp_text user "Author: Antmicro"
			(at -0.4 3.901 180)
			(layer "F.Fab")
			(hide yes)
			(effects
				(font
					(size 0.7 0.7)
					(thickness 0.15)
				)
				(justify left bottom)
			)
		)
		(fp_text user "License: Apache-2.0"
			(at -0.4 5.101 180)
			(layer "F.Fab")
			(hide yes)
			(effects
				(font
					(size 0.7 0.7)
					(thickness 0.15)
				)
				(justify left bottom)
			)
		)
		(pad "1" smd circle
			(at 0 0 180)
			(size 0.75 0.75)
			(layers "F.Cu" "F.Mask")
			(net 744 "Net-(J15B-CAM0_MCLK)")
			(pinfunction "1")
			(pintype "passive")
		)
	)
	(footprint "antmicro-footprints:R_0402_1005Metric"
		(layer "F.Cu")
		(at 65.91 94.35)
		(descr "Resistor SMD 0402")
		(tags "resistor SMD 0402")
		(property "Reference" "R237"
			(at -1.12 -1.46 0)
			(layer "F.SilkS")
			(effects
				(font
					(size 0.7 0.7)
					(thickness 0.15)
				)
				(justify left bottom)
			)
		)
		(property "Value" "R_499k_0402"
			(at -1.011843 1.772047 0)
			(layer "F.Fab")
			(effects
				(font
					(size 0.7 0.7)
					(thickness 0.15)
				)
				(justify left bottom)
			)
		)
		(property "Footprint" "antmicro-footprints:R_0402_1005Metric"
			(at 0 0 0)
			(layer "F.Fab")
			(hide yes)
			(effects
				(font
					(size 1.27 1.27)
					(thickness 0.15)
				)
			)
		)
		(property "Datasheet" "https://www.mouser.com/datasheet/2/54/cr-1858361.pdf"
			(at 0 0 0)
			(layer "F.Fab")
			(hide yes)
			(effects
				(font
					(size 1.27 1.27)
					(thickness 0.15)
				)
			)
		)
		(property "Author" "Antmicro"
			(at 0 0 0)
			(layer "F.Fab")
			(hide yes)
			(effects
				(font
					(size 1 1)
					(thickness 0.15)
				)
			)
		)
		(property "License" "Apache-2.0"
			(at 0 0 0)
			(layer "F.Fab")
			(hide yes)
			(effects
				(font
					(size 1 1)
					(thickness 0.15)
				)
			)
		)
		(property "MPN" "CR0402-FX-4993GLF"
			(at 0 0 0)
			(layer "F.Fab")
			(hide yes)
			(effects
				(font
					(size 1 1)
					(thickness 0.15)
				)
			)
		)
		(property "Manufacturer" "Bourns"
			(at 0 0 0)
			(layer "F.Fab")
			(hide yes)
			(effects
				(font
					(size 1 1)
					(thickness 0.15)
				)
			)
		)
		(property "Tolerance" "1%"
			(at 0 0 0)
			(layer "F.Fab")
			(hide yes)
			(effects
				(font
					(size 1 1)
					(thickness 0.15)
				)
			)
		)
		(property "Val" "499k"
			(at 0 0 0)
			(layer "F.Fab")
			(hide yes)
			(effects
				(font
					(size 1 1)
					(thickness 0.15)
				)
			)
		)
		(sheetname "Supply")
		(sheetfile "supply.kicad_sch")
		(attr smd)
		(fp_rect
			(start -0.925 -0.47)
			(end 0.925 0.47)
			(stroke
				(width 0.05)
				(type default)
			)
			(fill none)
			(layer "F.CrtYd")
		)
		(fp_rect
			(start -0.5 -0.25)
			(end 0.5 0.25)
			(stroke
				(width 0.15)
				(type solid)
			)
			(fill none)
			(layer "F.Fab")
		)
		(fp_text user "${REFERENCE}"
			(at -0.95 3.168 0)
			(layer "F.Fab")
			(hide yes)
			(effects
				(font
					(size 0.7 0.7)
					(thickness 0.15)
				)
				(justify left bottom)
			)
		)
		(fp_text user "License: Apache-2.0"
			(at -0.95 5.169 0)
			(layer "F.Fab")
			(hide yes)
			(effects
				(font
					(size 0.7 0.7)
					(thickness 0.15)
				)
				(justify left bottom)
			)
		)
		(fp_text user "Author: Antmicro"
			(at -0.95 4.169 0)
			(layer "F.Fab")
			(hide yes)
			(effects
				(font
					(size 0.7 0.7)
					(thickness 0.15)
				)
				(justify left bottom)
			)
		)
		(pad "1" smd roundrect
			(at -0.48 0)
			(size 0.59 0.64)
			(layers "F.Cu" "F.Paste" "F.Mask")
			(roundrect_rratio 0.25)
			(net 1 "GND")
			(pintype "passive")
		)
		(pad "2" smd roundrect
			(at 0.48 0)
			(size 0.59 0.64)
			(layers "F.Cu" "F.Paste" "F.Mask")
			(roundrect_rratio 0.25)
			(net 764 "/Supply/5V_MODE1")
			(pintype "passive")
		)
	)
	(footprint "antmicro-footprints:C_0402_1005Metric"
		(layer "F.Cu")
		(at 62.55 102.925 180)
		(descr "Capacitor SMD 0402")
		(tags "capacitor SMD 0402")
		(property "Reference" "C35"
			(at 1.11 -1.325 180)
			(layer "F.SilkS")
			(effects
				(font
					(size 0.7 0.7)
					(thickness 0.15)
				)
				(justify left bottom)
			)
		)
		(property "Value" "C_10u_0402"
			(at -1.022927 2.155213 180)
			(layer "F.Fab")
			(effects
				(font
					(size 0.7 0.7)
					(thickness 0.15)
				)
				(justify left bottom)
			)
		)
		(property "Footprint" "antmicro-footprints:C_0402_1005Metric"
			(at 0 0 180)
			(layer "F.Fab")
			(hide yes)
			(effects
				(font
					(size 1.27 1.27)
					(thickness 0.15)
				)
			)
		)
		(property "Datasheet" "https://www.yageo.com/en/Chart/Download/pdf/CC0402MRX5R5BB106"
			(at 0 0 180)
			(layer "F.Fab")
			(hide yes)
			(effects
				(font
					(size 1.27 1.27)
					(thickness 0.15)
				)
			)
		)
		(property "Author" "Antmicro"
			(at 125.1 205.85 0)
			(layer "F.Fab")
			(hide yes)
			(effects
				(font
					(size 1 1)
					(thickness 0.15)
				)
			)
		)
		(property "Dielectric" ""
			(at 125.1 205.85 0)
			(layer "F.Fab")
			(hide yes)
			(effects
				(font
					(size 1 1)
					(thickness 0.15)
				)
			)
		)
		(property "License" "Apache-2.0"
			(at 125.1 205.85 0)
			(layer "F.Fab")
			(hide yes)
			(effects
				(font
					(size 1 1)
					(thickness 0.15)
				)
			)
		)
		(property "MPN" "CC0402MRX5R5BB106"
			(at 125.1 205.85 0)
			(layer "F.Fab")
			(hide yes)
			(effects
				(font
					(size 1 1)
					(thickness 0.15)
				)
			)
		)
		(property "Manufacturer" "YAGEO"
			(at 125.1 205.85 0)
			(layer "F.Fab")
			(hide yes)
			(effects
				(font
					(size 1 1)
					(thickness 0.15)
				)
			)
		)
		(property "Val" "10u"
			(at 125.1 205.85 0)
			(layer "F.Fab")
			(hide yes)
			(effects
				(font
					(size 1 1)
					(thickness 0.15)
				)
			)
		)
		(property "Voltage" ""
			(at 125.1 205.85 0)
			(layer "F.Fab")
			(hide yes)
			(effects
				(font
					(size 1 1)
					(thickness 0.15)
				)
			)
		)
		(sheetname "USB Debug, DP")
		(sheetfile "usb.kicad_sch")
		(attr smd)
		(fp_rect
			(start -0.925 -0.47)
			(end 0.925 0.47)
			(stroke
				(width 0.05)
				(type default)
			)
			(fill none)
			(layer "F.CrtYd")
		)
		(fp_line
			(start 0.504 0.248)
			(end -0.494 0.248)
			(stroke
				(width 0.15)
				(type solid)
			)
			(layer "F.Fab")
		)
		(fp_line
			(start 0.504 -0.25)
			(end 0.504 0.248)
			(stroke
				(width 0.15)
				(type solid)
			)
			(layer "F.Fab")
		)
		(fp_line
			(start -0.494 0.248)
			(end -0.494 -0.25)
			(stroke
				(width 0.15)
				(type solid)
			)
			(layer "F.Fab")
		)
		(fp_line
			(start -0.494 -0.25)
			(end 0.504 -0.25)
			(stroke
				(width 0.15)
				(type solid)
			)
			(layer "F.Fab")
		)
		(fp_text user "License: Apache-2.0"
			(at -0.939 5.799 180)
			(layer "F.Fab")
			(hide yes)
			(effects
				(font
					(size 0.7 0.7)
					(thickness 0.15)
				)
				(justify left bottom)
			)
		)
		(fp_text user "${REFERENCE}"
			(at -0.939 4.599 180)
			(layer "F.Fab")
			(hide yes)
			(effects
				(font
					(size 0.7 0.7)
					(thickness 0.15)
				)
				(justify left bottom)
			)
		)
		(fp_text user "Author: Antmicro"
			(at -0.939 3.399 180)
			(layer "F.Fab")
			(hide yes)
			(effects
				(font
					(size 0.7 0.7)
					(thickness 0.15)
				)
				(justify left bottom)
			)
		)
		(pad "1" smd roundrect
			(at -0.48 0 180)
			(size 0.59 0.64)
			(layers "F.Cu" "F.Paste" "F.Mask")
			(roundrect_rratio 0.25)
			(net 1 "GND")
			(pintype "passive")
		)
		(pad "2" smd roundrect
			(at 0.48 0 180)
			(size 0.59 0.64)
			(layers "F.Cu" "F.Paste" "F.Mask")
			(roundrect_rratio 0.25)
			(net 99 "+5V")
			(pintype "passive")
		)
	)
	(footprint "antmicro-footprints:Spacer_Drill3.7mm_H2.5mm_9774025151R"
		(layer "F.Cu")
		(at 79.25 95.15)
		(descr "Spacer M=3 h=2.5mm fi=5.1mm")
		(property "Reference" "SP7"
			(at -0.95 4.35 0)
			(layer "F.SilkS")
			(effects
				(font
					(size 0.7 0.7)
					(thickness 0.15)
				)
				(justify left bottom)
			)
		)
		(property "Value" "Spacer_Drill3.7mm_H2.5mm_9774025151R"
			(at -2.75 4.25 0)
			(layer "F.Fab")
			(effects
				(font
					(size 0.7 0.7)
					(thickness 0.15)
				)
				(justify left bottom)
			)
		)
		(property "Footprint" "antmicro-footprints:Spacer_Drill3.7mm_H2.5mm_9774025151R"
			(at 0 0 0)
			(layer "F.Fab")
			(hide yes)
			(effects
				(font
					(size 1.27 1.27)
					(thickness 0.15)
				)
			)
		)
		(property "Datasheet" "https://www.we-online.com/components/products/datasheet/9774025151R.pdf"
			(at 0 0 0)
			(layer "F.Fab")
			(hide yes)
			(effects
				(font
					(size 1.27 1.27)
					(thickness 0.15)
				)
			)
		)
		(property "Author" "Antmicro"
			(at 0 0 0)
			(layer "F.Fab")
			(hide yes)
			(effects
				(font
					(size 1 1)
					(thickness 0.15)
				)
			)
		)
		(property "License" "Apache-2.0"
			(at 0 0 0)
			(layer "F.Fab")
			(hide yes)
			(effects
				(font
					(size 1 1)
					(thickness 0.15)
				)
			)
		)
		(property "MPN" "9774025151R"
			(at 0 0 0)
			(layer "F.Fab")
			(hide yes)
			(effects
				(font
					(size 1 1)
					(thickness 0.15)
				)
			)
		)
		(property "Manufacturer" "Würth Elektronik"
			(at 0 0 0)
			(layer "F.Fab")
			(hide yes)
			(effects
				(font
					(size 1 1)
					(thickness 0.15)
				)
			)
		)
		(sheetname "M.2")
		(sheetfile "m-2.kicad_sch")
		(solder_paste_ratio -1)
		(attr smd)
		(fp_circle
			(center 0 0)
			(end 3.05 0)
			(stroke
				(width 0.05)
				(type solid)
			)
			(fill none)
			(layer "F.CrtYd")
		)
		(fp_circle
			(center 0 0)
			(end 2.6 0)
			(stroke
				(width 0.15)
				(type solid)
			)
			(fill none)
			(layer "F.Fab")
		)
		(fp_text user "${REFERENCE}"
			(at -2.75 5.5 0)
			(layer "F.Fab")
			(hide yes)
			(effects
				(font
					(size 0.7 0.7)
					(thickness 0.15)
				)
				(justify left bottom)
			)
		)
		(fp_text user "License: Apache-2.0"
			(at -2.75 8.25 0)
			(layer "F.Fab")
			(hide yes)
			(effects
				(font
					(size 0.7 0.7)
					(thickness 0.15)
				)
				(justify left bottom)
			)
		)
		(fp_text user "Author: Antmicro"
			(at -2.75 6.75 0)
			(layer "F.Fab")
			(hide yes)
			(effects
				(font
					(size 0.7 0.7)
					(thickness 0.15)
				)
				(justify left bottom)
			)
		)
		(pad "" smd custom
			(at -1.7 -1.7)
			(size 0.62 0.62)
			(layers "F.Paste")
			(thermal_bridge_angle 90)
			(options
				(clearance outline)
				(anchor circle)
			)
			(primitives
				(gr_arc
					(start -0.250195 1.279127)
					(mid 0.285453 0.294389)
					(end 1.266786 -0.24747)
					(width 0.2)
				)
				(gr_arc
					(start -0.34334 1.279127)
					(mid 0.218448 0.232562)
					(end 1.259603 -0.339191)
					(width 0.2)
				)
				(gr_arc
					(start -0.436309 1.279127)
					(mid 0.152481 0.169693)
					(end 1.255279 -0.431435)
					(width 0.2)
				)
				(gr_arc
					(start -0.529126 1.279127)
					(mid 0.087543 0.105785)
					(end 1.253811 -0.524161)
					(width 0.2)
				)
				(gr_arc
					(start -0.621807 1.279127)
					(mid 0.0309 0.033527)
					(end 1.275473 -0.621136)
					(width 0.2)
				)
				(gr_arc
					(start -0.71437 1.279127)
					(mid -0.037759 -0.026651)
					(end 1.263664 -0.711602)
					(width 0.2)
				)
				(gr_arc
					(start -0.806826 1.279127)
					(mid -0.105837 -0.087395)
					(end 1.253435 -0.802342)
					(width 0.2)
				)
				(gr_arc
					(start -0.899187 1.279127)
					(mid -0.165236 -0.156885)
					(end 1.267475 -0.897258)
					(width 0.2)
				)
				(gr_arc
					(start -0.991463 1.279127)
					(mid -0.228522 -0.222449)
					(end 1.270645 -0.990112)
					(width 0.2)
				)
				(gr_arc
					(start -1.083663 1.279127)
					(mid -0.294507 -0.285313)
					(end 1.266278 -1.081674)
					(width 0.2)
				)
				(gr_line
					(start 1.279127 -0.250195)
					(end 1.279127 -1.083663)
					(width 0.2)
				)
				(gr_line
					(start -0.250195 1.279127)
					(end -1.083663 1.279127)
					(width 0.2)
				)
			)
		)
		(pad "" smd custom
			(at -1.7 1.7 90)
			(size 0.62 0.62)
			(layers "F.Paste")
			(thermal_bridge_angle 90)
			(options
				(clearance outline)
				(anchor circle)
			)
			(primitives
				(gr_arc
					(start -0.250195 1.279127)
					(mid 0.285453 0.294389)
					(end 1.266786 -0.24747)
					(width 0.2)
				)
				(gr_arc
					(start -0.34334 1.279127)
					(mid 0.218448 0.232562)
					(end 1.259603 -0.339191)
					(width 0.2)
				)
				(gr_arc
					(start -0.436309 1.279127)
					(mid 0.152481 0.169693)
					(end 1.255279 -0.431435)
					(width 0.2)
				)
				(gr_arc
					(start -0.529126 1.279127)
					(mid 0.087543 0.105785)
					(end 1.253811 -0.524161)
					(width 0.2)
				)
				(gr_arc
					(start -0.621807 1.279127)
					(mid 0.0309 0.033527)
					(end 1.275473 -0.621136)
					(width 0.2)
				)
				(gr_arc
					(start -0.71437 1.279127)
					(mid -0.037759 -0.026651)
					(end 1.263664 -0.711602)
					(width 0.2)
				)
				(gr_arc
					(start -0.806826 1.279127)
					(mid -0.105837 -0.087395)
					(end 1.253435 -0.802342)
					(width 0.2)
				)
				(gr_arc
					(start -0.899187 1.279127)
					(mid -0.165236 -0.156885)
					(end 1.267475 -0.897258)
					(width 0.2)
				)
				(gr_arc
					(start -0.991463 1.279127)
					(mid -0.228522 -0.222449)
					(end 1.270645 -0.990112)
					(width 0.2)
				)
				(gr_arc
					(start -1.083663 1.279127)
					(mid -0.294507 -0.285313)
					(end 1.266278 -1.081674)
					(width 0.2)
				)
				(gr_line
					(start 1.279127 -0.250195)
					(end 1.279127 -1.083663)
					(width 0.2)
				)
				(gr_line
					(start -0.250195 1.279127)
					(end -1.083663 1.279127)
					(width 0.2)
				)
			)
		)
		(pad "" smd custom
			(at 1.7 -1.7 270)
			(size 0.62 0.62)
			(layers "F.Paste")
			(thermal_bridge_angle 90)
			(options
				(clearance outline)
				(anchor circle)
			)
			(primitives
				(gr_arc
					(start -0.250195 1.279127)
					(mid 0.285453 0.294389)
					(end 1.266786 -0.24747)
					(width 0.2)
				)
				(gr_arc
					(start -0.34334 1.279127)
					(mid 0.218448 0.232562)
					(end 1.259603 -0.339191)
					(width 0.2)
				)
				(gr_arc
					(start -0.436309 1.279127)
					(mid 0.152481 0.169693)
					(end 1.255279 -0.431435)
					(width 0.2)
				)
				(gr_arc
					(start -0.529126 1.279127)
					(mid 0.087543 0.105785)
					(end 1.253811 -0.524161)
					(width 0.2)
				)
				(gr_arc
					(start -0.621807 1.279127)
					(mid 0.0309 0.033527)
					(end 1.275473 -0.621136)
					(width 0.2)
				)
				(gr_arc
					(start -0.71437 1.279127)
					(mid -0.037759 -0.026651)
					(end 1.263664 -0.711602)
					(width 0.2)
				)
				(gr_arc
					(start -0.806826 1.279127)
					(mid -0.105837 -0.087395)
					(end 1.253435 -0.802342)
					(width 0.2)
				)
				(gr_arc
					(start -0.899187 1.279127)
					(mid -0.165236 -0.156885)
					(end 1.267475 -0.897258)
					(width 0.2)
				)
				(gr_arc
					(start -0.991463 1.279127)
					(mid -0.228522 -0.222449)
					(end 1.270645 -0.990112)
					(width 0.2)
				)
				(gr_arc
					(start -1.083663 1.279127)
					(mid -0.294507 -0.285313)
					(end 1.266278 -1.081674)
					(width 0.2)
				)
				(gr_line
					(start 1.279127 -0.250195)
					(end 1.279127 -1.083663)
					(width 0.2)
				)
				(gr_line
					(start -0.250195 1.279127)
					(end -1.083663 1.279127)
					(width 0.2)
				)
			)
		)
		(pad "" smd custom
			(at 1.7 1.7 180)
			(size 0.62 0.62)
			(layers "F.Paste")
			(thermal_bridge_angle 90)
			(options
				(clearance outline)
				(anchor circle)
			)
			(primitives
				(gr_arc
					(start -0.250195 1.279127)
					(mid 0.285453 0.294389)
					(end 1.266786 -0.24747)
					(width 0.2)
				)
				(gr_arc
					(start -0.34334 1.279127)
					(mid 0.218448 0.232562)
					(end 1.259603 -0.339191)
					(width 0.2)
				)
				(gr_arc
					(start -0.436309 1.279127)
					(mid 0.152481 0.169693)
					(end 1.255279 -0.431435)
					(width 0.2)
				)
				(gr_arc
					(start -0.529126 1.279127)
					(mid 0.087543 0.105785)
					(end 1.253811 -0.524161)
					(width 0.2)
				)
				(gr_arc
					(start -0.621807 1.279127)
					(mid 0.0309 0.033527)
					(end 1.275473 -0.621136)
					(width 0.2)
				)
				(gr_arc
					(start -0.71437 1.279127)
					(mid -0.037759 -0.026651)
					(end 1.263664 -0.711602)
					(width 0.2)
				)
				(gr_arc
					(start -0.806826 1.279127)
					(mid -0.105837 -0.087395)
					(end 1.253435 -0.802342)
					(width 0.2)
				)
				(gr_arc
					(start -0.899187 1.279127)
					(mid -0.165236 -0.156885)
					(end 1.267475 -0.897258)
					(width 0.2)
				)
				(gr_arc
					(start -0.991463 1.279127)
					(mid -0.228522 -0.222449)
					(end 1.270645 -0.990112)
					(width 0.2)
				)
				(gr_arc
					(start -1.083663 1.279127)
					(mid -0.294507 -0.285313)
					(end 1.266278 -1.081674)
					(width 0.2)
				)
				(gr_line
					(start 1.279127 -0.250195)
					(end 1.279127 -1.083663)
					(width 0.2)
				)
				(gr_line
					(start -0.250195 1.279127)
					(end -1.083663 1.279127)
					(width 0.2)
				)
			)
		)
		(pad "1" thru_hole circle
			(at 0 0)
			(size 6 6)
			(drill 3.7)
			(layers "*.Cu" "*.Mask")
			(remove_unused_layers no)
			(net 1 "GND")
			(pintype "passive")
		)
	)
	(footprint "antmicro-footprints:C_0402_1005Metric"
		(layer "F.Cu")
		(at 75.42 86.34)
		(descr "Capacitor SMD 0402")
		(tags "capacitor SMD 0402")
		(property "Reference" "C125"
			(at -2.097516 -2.367303 0)
			(layer "F.SilkS")
			(effects
				(font
					(size 0.7 0.7)
					(thickness 0.15)
				)
				(justify left bottom)
			)
		)
		(property "Value" "C_100n_0402"
			(at -1.022927 2.155213 0)
			(layer "F.Fab")
			(effects
				(font
					(size 0.7 0.7)
					(thickness 0.15)
				)
				(justify left bottom)
			)
		)
		(property "Footprint" "antmicro-footprints:C_0402_1005Metric"
			(at 0 0 0)
			(layer "F.Fab")
			(hide yes)
			(effects
				(font
					(size 1.27 1.27)
					(thickness 0.15)
				)
			)
		)
		(property "Datasheet" "https://www.murata.com/products/productdetail?partno=GRM155R61H104KE14%23"
			(at 0 0 0)
			(layer "F.Fab")
			(hide yes)
			(effects
				(font
					(size 1.27 1.27)
					(thickness 0.15)
				)
			)
		)
		(property "Author" "Antmicro"
			(at 0 0 0)
			(layer "F.Fab")
			(hide yes)
			(effects
				(font
					(size 1 1)
					(thickness 0.15)
				)
			)
		)
		(property "Dielectric" "X5R"
			(at 0 0 0)
			(layer "F.Fab")
			(hide yes)
			(effects
				(font
					(size 1 1)
					(thickness 0.15)
				)
			)
		)
		(property "License" "Apache-2.0"
			(at 0 0 0)
			(layer "F.Fab")
			(hide yes)
			(effects
				(font
					(size 1 1)
					(thickness 0.15)
				)
			)
		)
		(property "MPN" "GRM155R61H104KE14D"
			(at 0 0 0)
			(layer "F.Fab")
			(hide yes)
			(effects
				(font
					(size 1 1)
					(thickness 0.15)
				)
			)
		)
		(property "Manufacturer" "Murata"
			(at 0 0 0)
			(layer "F.Fab")
			(hide yes)
			(effects
				(font
					(size 1 1)
					(thickness 0.15)
				)
			)
		)
		(property "Val" "100n"
			(at 0 0 0)
			(layer "F.Fab")
			(hide yes)
			(effects
				(font
					(size 1 1)
					(thickness 0.15)
				)
			)
		)
		(property "Voltage" "50V"
			(at 0 0 0)
			(layer "F.Fab")
			(hide yes)
			(effects
				(font
					(size 1 1)
					(thickness 0.15)
				)
			)
		)
		(sheetname "Supply")
		(sheetfile "supply.kicad_sch")
		(attr smd)
		(fp_rect
			(start -0.925 -0.47)
			(end 0.925 0.47)
			(stroke
				(width 0.05)
				(type default)
			)
			(fill none)
			(layer "F.CrtYd")
		)
		(fp_line
			(start -0.494 -0.25)
			(end 0.504 -0.25)
			(stroke
				(width 0.15)
				(type solid)
			)
			(layer "F.Fab")
		)
		(fp_line
			(start -0.494 0.248)
			(end -0.494 -0.25)
			(stroke
				(width 0.15)
				(type solid)
			)
			(layer "F.Fab")
		)
		(fp_line
			(start 0.504 -0.25)
			(end 0.504 0.248)
			(stroke
				(width 0.15)
				(type solid)
			)
			(layer "F.Fab")
		)
		(fp_line
			(start 0.504 0.248)
			(end -0.494 0.248)
			(stroke
				(width 0.15)
				(type solid)
			)
			(layer "F.Fab")
		)
		(fp_text user "License: Apache-2.0"
			(at -0.939 5.799 0)
			(layer "F.Fab")
			(hide yes)
			(effects
				(font
					(size 0.7 0.7)
					(thickness 0.15)
				)
				(justify left bottom)
			)
		)
		(fp_text user "Author: Antmicro"
			(at -0.939 3.399 0)
			(layer "F.Fab")
			(hide yes)
			(effects
				(font
					(size 0.7 0.7)
					(thickness 0.15)
				)
				(justify left bottom)
			)
		)
		(fp_text user "${REFERENCE}"
			(at -0.939 4.599 0)
			(layer "F.Fab")
			(hide yes)
			(effects
				(font
					(size 0.7 0.7)
					(thickness 0.15)
				)
				(justify left bottom)
			)
		)
		(pad "1" smd roundrect
			(at -0.48 0)
			(size 0.59 0.64)
			(layers "F.Cu" "F.Paste" "F.Mask")
			(roundrect_rratio 0.25)
			(net 758 "/Supply/3V3_PHASE")
			(pintype "passive")
		)
		(pad "2" smd roundrect
			(at 0.48 0)
			(size 0.59 0.64)
			(layers "F.Cu" "F.Paste" "F.Mask")
			(roundrect_rratio 0.25)
			(net 358 "/Supply/3V3_BOOT")
			(pintype "passive")
		)
	)
	(footprint "antmicro-footprints:XDFN-2_1x0.60mm"
		(layer "F.Cu")
		(at 136.27 91.26 90)
		(property "Reference" "D19"
			(at -0.3 0.4 0)
			(layer "F.SilkS")
			(effects
				(font
					(size 0.7 0.7)
					(thickness 0.15)
				)
				(justify left bottom)
			)
		)
		(property "Value" "TPD1E0B04_XDFN-2"
			(at 0 1.5 90)
			(layer "F.Fab")
			(effects
				(font
					(size 0.7 0.7)
					(thickness 0.15)
				)
				(justify left bottom)
			)
		)
		(property "Footprint" "antmicro-footprints:XDFN-2_1x0.60mm"
			(at 0 0 90)
			(layer "F.Fab")
			(hide yes)
			(effects
				(font
					(size 1.27 1.27)
					(thickness 0.15)
				)
			)
		)
		(property "Datasheet" "https://www.ti.com/general/docs/suppproductinfo.tsp?distId=26&gotoUrl=https://www.ti.com/lit/gpn/tpd1e0b04"
			(at 0 0 90)
			(layer "F.Fab")
			(hide yes)
			(effects
				(font
					(size 1.27 1.27)
					(thickness 0.15)
				)
			)
		)
		(property "MPN" "TPD1E0B04DPYR"
			(at 227.53 -45.01 0)
			(layer "F.Fab")
			(hide yes)
			(effects
				(font
					(size 1 1)
					(thickness 0.15)
				)
			)
		)
		(property "Manufacturer" "Texas Instruments"
			(at 227.53 -45.01 0)
			(layer "F.Fab")
			(hide yes)
			(effects
				(font
					(size 1 1)
					(thickness 0.15)
				)
			)
		)
		(property "Author" "Antmicro"
			(at 227.53 -45.01 0)
			(layer "F.Fab")
			(hide yes)
			(effects
				(font
					(size 1 1)
					(thickness 0.15)
				)
			)
		)
		(property "License" "Apache-2.0"
			(at 227.53 -45.01 0)
			(layer "F.Fab")
			(hide yes)
			(effects
				(font
					(size 1 1)
					(thickness 0.15)
				)
			)
		)
		(sheetname "Peripherals")
		(sheetfile "peripherals.kicad_sch")
		(attr smd)
		(fp_rect
			(start -0.725 -0.475)
			(end 0.725 0.475)
			(stroke
				(width 0.05)
				(type solid)
			)
			(fill none)
			(layer "F.CrtYd")
		)
		(fp_rect
			(start -0.55 -0.35)
			(end 0.55 0.35)
			(stroke
				(width 0.15)
				(type solid)
			)
			(fill none)
			(layer "F.Fab")
		)
		(fp_text user "${REFERENCE}"
			(at -0.8 3.2 90)
			(layer "F.Fab")
			(hide yes)
			(effects
				(font
					(size 0.7 0.7)
					(thickness 0.15)
				)
				(justify left bottom)
			)
		)
		(fp_text user "Author: Antmicro"
			(at -0.8 4.4 90)
			(layer "F.Fab")
			(hide yes)
			(effects
				(font
					(size 0.7 0.7)
					(thickness 0.15)
				)
				(justify left bottom)
			)
		)
		(fp_text user "License: Apache-2.0"
			(at -0.8 5.6 90)
			(layer "F.Fab")
			(hide yes)
			(effects
				(font
					(size 0.7 0.7)
					(thickness 0.15)
				)
				(justify left bottom)
			)
		)
		(pad "1" smd roundrect
			(at -0.351 0 90)
			(size 0.3 0.5)
			(layers "F.Cu" "F.Paste" "F.Mask")
			(roundrect_rratio 0.25)
			(net 416 "/Peripherals/USBSS2_TX_CONN_N")
			(pinfunction "C")
			(pintype "passive")
		)
		(pad "2" smd roundrect
			(at 0.349 0 90)
			(size 0.3 0.5)
			(layers "F.Cu" "F.Paste" "F.Mask")
			(roundrect_rratio 0.25)
			(net 1 "GND")
			(pinfunction "A")
			(pintype "passive")
		)
	)
	(footprint "antmicro-footprints:C_0402_1005Metric"
		(layer "F.Cu")
		(at 136.35 82.95 180)
		(descr "Capacitor SMD 0402")
		(tags "capacitor SMD 0402")
		(property "Reference" "C112"
			(at 3.6 -0.4 180)
			(layer "F.SilkS")
			(effects
				(font
					(size 0.7 0.7)
					(thickness 0.15)
				)
				(justify left bottom)
			)
		)
		(property "Value" "C_220n_0402"
			(at 0 1.4 180)
			(layer "F.Fab")
			(effects
				(font
					(size 0.7 0.7)
					(thickness 0.15)
				)
				(justify left bottom)
			)
		)
		(property "Footprint" "antmicro-footprints:C_0402_1005Metric"
			(at 0 0 180)
			(layer "F.Fab")
			(hide yes)
			(effects
				(font
					(size 1.27 1.27)
					(thickness 0.15)
				)
			)
		)
		(property "Datasheet" "https://www.yageo.com/en/Chart/Download/pdf/CC0402KRX5R6BB224"
			(at 0 0 180)
			(layer "F.Fab")
			(hide yes)
			(effects
				(font
					(size 1.27 1.27)
					(thickness 0.15)
				)
			)
		)
		(property "Author" "Antmicro"
			(at 272.7 165.9 0)
			(layer "F.Fab")
			(hide yes)
			(effects
				(font
					(size 1 1)
					(thickness 0.15)
				)
			)
		)
		(property "Dielectric" ""
			(at 272.7 165.9 0)
			(layer "F.Fab")
			(hide yes)
			(effects
				(font
					(size 1 1)
					(thickness 0.15)
				)
			)
		)
		(property "License" "Apache-2.0"
			(at 272.7 165.9 0)
			(layer "F.Fab")
			(hide yes)
			(effects
				(font
					(size 1 1)
					(thickness 0.15)
				)
			)
		)
		(property "MPN" "CC0402KRX5R6BB224"
			(at 272.7 165.9 0)
			(layer "F.Fab")
			(hide yes)
			(effects
				(font
					(size 1 1)
					(thickness 0.15)
				)
			)
		)
		(property "Manufacturer" "YAGEO"
			(at 272.7 165.9 0)
			(layer "F.Fab")
			(hide yes)
			(effects
				(font
					(size 1 1)
					(thickness 0.15)
				)
			)
		)
		(property "Val" "220n"
			(at 272.7 165.9 0)
			(layer "F.Fab")
			(hide yes)
			(effects
				(font
					(size 1 1)
					(thickness 0.15)
				)
			)
		)
		(property "Voltage" ""
			(at 272.7 165.9 0)
			(layer "F.Fab")
			(hide yes)
			(effects
				(font
					(size 1 1)
					(thickness 0.15)
				)
			)
		)
		(sheetname "Peripherals")
		(sheetfile "peripherals.kicad_sch")
		(attr smd)
		(fp_rect
			(start -0.925 -0.47)
			(end 0.925 0.47)
			(stroke
				(width 0.05)
				(type default)
			)
			(fill none)
			(layer "F.CrtYd")
		)
		(fp_line
			(start 0.504 0.248)
			(end -0.494 0.248)
			(stroke
				(width 0.15)
				(type solid)
			)
			(layer "F.Fab")
		)
		(fp_line
			(start 0.504 -0.25)
			(end 0.504 0.248)
			(stroke
				(width 0.15)
				(type solid)
			)
			(layer "F.Fab")
		)
		(fp_line
			(start -0.494 0.248)
			(end -0.494 -0.25)
			(stroke
				(width 0.15)
				(type solid)
			)
			(layer "F.Fab")
		)
		(fp_line
			(start -0.494 -0.25)
			(end 0.504 -0.25)
			(stroke
				(width 0.15)
				(type solid)
			)
			(layer "F.Fab")
		)
		(fp_text user "${REFERENCE}"
			(at -0.932 3.168 180)
			(layer "F.Fab")
			(hide yes)
			(effects
				(font
					(size 0.7 0.7)
					(thickness 0.15)
				)
				(justify left bottom)
			)
		)
		(fp_text user "License: Apache-2.0"
			(at -0.932 5.17 180)
			(layer "F.Fab")
			(hide yes)
			(effects
				(font
					(size 0.7 0.7)
					(thickness 0.15)
				)
				(justify left bottom)
			)
		)
		(fp_text user "Author: Antmicro"
			(at -0.932 4.17 180)
			(layer "F.Fab")
			(hide yes)
			(effects
				(font
					(size 0.7 0.7)
					(thickness 0.15)
				)
				(justify left bottom)
			)
		)
		(pad "1" smd roundrect
			(at -0.48 0 180)
			(size 0.59 0.64)
			(layers "F.Cu" "F.Paste" "F.Mask")
			(roundrect_rratio 0.25)
			(net 415 "/Peripherals/PCIE2_TX1_CONN_N")
			(pintype "passive")
		)
		(pad "2" smd roundrect
			(at 0.48 0 180)
			(size 0.59 0.64)
			(layers "F.Cu" "F.Paste" "F.Mask")
			(roundrect_rratio 0.25)
			(net 357 "PCIE2_TX1_N")
			(pintype "passive")
		)
	)
	(footprint "antmicro-footprints:C_0603_1608Metric_EIA"
		(layer "F.Cu")
		(at 71.25 91.67 -90)
		(descr "Capacitor SMD 0603, IPC-7351 Density Level A")
		(tags "Capacitor 0603")
		(property "Reference" "C126"
			(at -6.406396 -14.35 -90)
			(layer "F.SilkS")
			(effects
				(font
					(size 0.7 0.7)
					(thickness 0.15)
				)
				(justify left bottom)
			)
		)
		(property "Value" "C_22u_16V_0603"
			(at -1.42757 1.770288 -90)
			(layer "F.Fab")
			(effects
				(font
					(size 0.7 0.7)
					(thickness 0.15)
				)
				(justify left bottom)
			)
		)
		(property "Footprint" "antmicro-footprints:C_0603_1608Metric_EIA"
			(at 0 0 -90)
			(layer "F.Fab")
			(hide yes)
			(effects
				(font
					(size 1.27 1.27)
					(thickness 0.15)
				)
			)
		)
		(property "Datasheet" "https://product.samsungsem.com/mlcc/CL10A226MO7JZN.do"
			(at 0 0 -90)
			(layer "F.Fab")
			(hide yes)
			(effects
				(font
					(size 1.27 1.27)
					(thickness 0.15)
				)
			)
		)
		(property "Description" "SMD Multilayer Ceramic Capacitor"
			(at 0 0 -90)
			(layer "F.Fab")
			(hide yes)
			(effects
				(font
					(size 1.27 1.27)
					(thickness 0.15)
				)
			)
		)
		(property "Manufacturer" "Samsung Electro-Mechanics"
			(at 0 0 -90)
			(unlocked yes)
			(layer "F.Fab")
			(hide yes)
			(effects
				(font
					(size 1 1)
					(thickness 0.15)
				)
			)
		)
		(property "MPN" "CL10A226MO7JZNC"
			(at 0 0 -90)
			(unlocked yes)
			(layer "F.Fab")
			(hide yes)
			(effects
				(font
					(size 1 1)
					(thickness 0.15)
				)
			)
		)
		(property "Val" "22u"
			(at 0 0 -90)
			(unlocked yes)
			(layer "F.Fab")
			(hide yes)
			(effects
				(font
					(size 1 1)
					(thickness 0.15)
				)
			)
		)
		(property "License" "Apache-2.0"
			(at 0 0 -90)
			(unlocked yes)
			(layer "F.Fab")
			(hide yes)
			(effects
				(font
					(size 1 1)
					(thickness 0.15)
				)
			)
		)
		(property "Author" "Antmicro"
			(at 0 0 -90)
			(unlocked yes)
			(layer "F.Fab")
			(hide yes)
			(effects
				(font
					(size 1 1)
					(thickness 0.15)
				)
			)
		)
		(property "Voltage" "16V"
			(at 0 0 -90)
			(unlocked yes)
			(layer "F.Fab")
			(hide yes)
			(effects
				(font
					(size 1 1)
					(thickness 0.15)
				)
			)
		)
		(property "Dielectric" ""
			(at 0 0 -90)
			(unlocked yes)
			(layer "F.Fab")
			(hide yes)
			(effects
				(font
					(size 1 1)
					(thickness 0.15)
				)
			)
		)
		(sheetname "Supply")
		(sheetfile "supply.kicad_sch")
		(attr smd)
		(fp_line
			(start -0.15 0.55)
			(end 0.15 0.55)
			(stroke
				(width 0.15)
				(type solid)
			)
			(layer "F.SilkS")
		)
		(fp_line
			(start -0.15 -0.55)
			(end 0.15 -0.55)
			(stroke
				(width 0.15)
				(type solid)
			)
			(layer "F.SilkS")
		)
		(fp_rect
			(start -1.25 -0.65)
			(end 1.25 0.65)
			(stroke
				(width 0.05)
				(type solid)
			)
			(fill none)
			(layer "F.CrtYd")
		)
		(fp_rect
			(start -0.8 -0.45)
			(end 0.8 0.45)
			(stroke
				(width 0.15)
				(type solid)
			)
			(fill none)
			(layer "F.Fab")
		)
		(fp_text user "License: Apache-2.0"
			(at -1.682 5.895 -90)
			(layer "F.Fab")
			(hide yes)
			(effects
				(font
					(size 0.7 0.7)
					(thickness 0.15)
				)
				(justify left bottom)
			)
		)
		(fp_text user "${REFERENCE}"
			(at -1.682 3.895 -90)
			(layer "F.Fab")
			(hide yes)
			(effects
				(font
					(size 0.7 0.7)
					(thickness 0.15)
				)
				(justify left bottom)
			)
		)
		(fp_text user "Author: Antmicro"
			(at -1.682 4.894 -90)
			(layer "F.Fab")
			(hide yes)
			(effects
				(font
					(size 0.7 0.7)
					(thickness 0.15)
				)
				(justify left bottom)
			)
		)
		(pad "1" smd roundrect
			(at -0.7 0 270)
			(size 0.8 1.1)
			(layers "F.Cu" "F.Paste" "F.Mask")
			(roundrect_rratio 0.2)
			(net 1 "GND")
			(pintype "passive")
		)
		(pad "2" smd roundrect
			(at 0.7 0 270)
			(size 0.8 1.1)
			(layers "F.Cu" "F.Paste" "F.Mask")
			(roundrect_rratio 0.2)
			(net 641 "/Supply/3V3_OUT")
			(pintype "passive")
		)
	)
	(footprint "antmicro-footprints:C_0402_1005Metric"
		(layer "F.Cu")
		(at 69.9 108.7 180)
		(descr "Capacitor SMD 0402")
		(tags "capacitor SMD 0402")
		(property "Reference" "C55"
			(at 1 -1.33 180)
			(layer "F.SilkS")
			(effects
				(font
					(size 0.7 0.7)
					(thickness 0.15)
				)
				(justify left bottom)
			)
		)
		(property "Value" "C_100n_0402"
			(at 0 1.4 180)
			(layer "F.Fab")
			(effects
				(font
					(size 0.7 0.7)
					(thickness 0.15)
				)
				(justify left bottom)
			)
		)
		(property "Footprint" "antmicro-footprints:C_0402_1005Metric"
			(at 0 0 180)
			(layer "F.Fab")
			(hide yes)
			(effects
				(font
					(size 1.27 1.27)
					(thickness 0.15)
				)
			)
		)
		(property "Datasheet" "https://www.murata.com/products/productdetail?partno=GRM155R61H104KE14%23"
			(at 0 0 180)
			(layer "F.Fab")
			(hide yes)
			(effects
				(font
					(size 1.27 1.27)
					(thickness 0.15)
				)
			)
		)
		(property "Author" "Antmicro"
			(at 139.8 217.4 0)
			(layer "F.Fab")
			(hide yes)
			(effects
				(font
					(size 1 1)
					(thickness 0.15)
				)
			)
		)
		(property "Dielectric" "X5R"
			(at 139.8 217.4 0)
			(layer "F.Fab")
			(hide yes)
			(effects
				(font
					(size 1 1)
					(thickness 0.15)
				)
			)
		)
		(property "License" "Apache-2.0"
			(at 139.8 217.4 0)
			(layer "F.Fab")
			(hide yes)
			(effects
				(font
					(size 1 1)
					(thickness 0.15)
				)
			)
		)
		(property "MPN" "GRM155R61H104KE14D"
			(at 139.8 217.4 0)
			(layer "F.Fab")
			(hide yes)
			(effects
				(font
					(size 1 1)
					(thickness 0.15)
				)
			)
		)
		(property "Manufacturer" "Murata"
			(at 139.8 217.4 0)
			(layer "F.Fab")
			(hide yes)
			(effects
				(font
					(size 1 1)
					(thickness 0.15)
				)
			)
		)
		(property "Val" "100n"
			(at 139.8 217.4 0)
			(layer "F.Fab")
			(hide yes)
			(effects
				(font
					(size 1 1)
					(thickness 0.15)
				)
			)
		)
		(property "Voltage" "50V"
			(at 139.8 217.4 0)
			(layer "F.Fab")
			(hide yes)
			(effects
				(font
					(size 1 1)
					(thickness 0.15)
				)
			)
		)
		(sheetname "USB Debug, DP")
		(sheetfile "usb.kicad_sch")
		(attr smd)
		(fp_rect
			(start -0.925 -0.47)
			(end 0.925 0.47)
			(stroke
				(width 0.05)
				(type default)
			)
			(fill none)
			(layer "F.CrtYd")
		)
		(fp_line
			(start 0.504 0.248)
			(end -0.494 0.248)
			(stroke
				(width 0.15)
				(type solid)
			)
			(layer "F.Fab")
		)
		(fp_line
			(start 0.504 -0.25)
			(end 0.504 0.248)
			(stroke
				(width 0.15)
				(type solid)
			)
			(layer "F.Fab")
		)
		(fp_line
			(start -0.494 0.248)
			(end -0.494 -0.25)
			(stroke
				(width 0.15)
				(type solid)
			)
			(layer "F.Fab")
		)
		(fp_line
			(start -0.494 -0.25)
			(end 0.504 -0.25)
			(stroke
				(width 0.15)
				(type solid)
			)
			(layer "F.Fab")
		)
		(fp_text user "${REFERENCE}"
			(at -0.932 3.168 180)
			(layer "F.Fab")
			(hide yes)
			(effects
				(font
					(size 0.7 0.7)
					(thickness 0.15)
				)
				(justify left bottom)
			)
		)
		(fp_text user "Author: Antmicro"
			(at -0.932 4.17 180)
			(layer "F.Fab")
			(hide yes)
			(effects
				(font
					(size 0.7 0.7)
					(thickness 0.15)
				)
				(justify left bottom)
			)
		)
		(fp_text user "License: Apache-2.0"
			(at -0.932 5.17 180)
			(layer "F.Fab")
			(hide yes)
			(effects
				(font
					(size 0.7 0.7)
					(thickness 0.15)
				)
				(justify left bottom)
			)
		)
		(pad "1" smd roundrect
			(at -0.48 0 180)
			(size 0.59 0.64)
			(layers "F.Cu" "F.Paste" "F.Mask")
			(roundrect_rratio 0.25)
			(net 87 "+3V3")
			(pintype "passive")
		)
		(pad "2" smd roundrect
			(at 0.48 0 180)
			(size 0.59 0.64)
			(layers "F.Cu" "F.Paste" "F.Mask")
			(roundrect_rratio 0.25)
			(net 1 "GND")
			(pintype "passive")
		)
	)
	(footprint "antmicro-footprints:USB-C_Receptacle_WE_632723300011"
		(layer "F.Cu")
		(at 113.40008 123.835)
		(property "Reference" "J5"
			(at 3.19992 -5.405 0)
			(layer "F.SilkS")
			(effects
				(font
					(size 0.7 0.7)
					(thickness 0.15)
				)
				(justify left bottom)
			)
		)
		(property "Value" "USB-C_WE_632723300011"
			(at 6.03 6.14 90)
			(layer "F.Fab")
			(effects
				(font
					(size 0.7 0.7)
					(thickness 0.15)
				)
				(justify left bottom)
			)
		)
		(property "Footprint" "antmicro-footprints:USB-C_Receptacle_WE_632723300011"
			(at 0 0 0)
			(layer "F.Fab")
			(hide yes)
			(effects
				(font
					(size 1.27 1.27)
					(thickness 0.15)
				)
			)
		)
		(property "Datasheet" "https://www.we-online.com/components/products/datasheet/632723300011.pdf"
			(at 0 0 0)
			(layer "F.Fab")
			(hide yes)
			(effects
				(font
					(size 1.27 1.27)
					(thickness 0.15)
				)
			)
		)
		(property "Author" "Antmicro"
			(at 0 0 0)
			(layer "F.Fab")
			(hide yes)
			(effects
				(font
					(size 1 1)
					(thickness 0.15)
				)
			)
		)
		(property "License" "Apache-2.0"
			(at 0 0 0)
			(layer "F.Fab")
			(hide yes)
			(effects
				(font
					(size 1 1)
					(thickness 0.15)
				)
			)
		)
		(property "MPN" "632723300011"
			(at 0 0 0)
			(layer "F.Fab")
			(hide yes)
			(effects
				(font
					(size 1 1)
					(thickness 0.15)
				)
			)
		)
		(property "Manufacturer" "Würth Elektronik"
			(at 0 0 0)
			(layer "F.Fab")
			(hide yes)
			(effects
				(font
					(size 1 1)
					(thickness 0.15)
				)
			)
		)
		(sheetname "USB3")
		(sheetfile "usb3.kicad_sch")
		(attr smd)
		(fp_line
			(start -4.4 -4.899)
			(end -4.4 -4.2)
			(stroke
				(width 0.15)
				(type solid)
			)
			(layer "F.SilkS")
		)
		(fp_line
			(start -4.4 -4.899)
			(end -2.999 -4.899)
			(stroke
				(width 0.15)
				(type solid)
			)
			(layer "F.SilkS")
		)
		(fp_line
			(start -4.4 -2.2)
			(end -4.4 0.6)
			(stroke
				(width 0.15)
				(type solid)
			)
			(layer "F.SilkS")
		)
		(fp_line
			(start -4.4 2.4)
			(end -4.4 3.201)
			(stroke
				(width 0.15)
				(type solid)
			)
			(layer "F.SilkS")
		)
		(fp_line
			(start 3 -4.899)
			(end 4.401 -4.899)
			(stroke
				(width 0.15)
				(type solid)
			)
			(layer "F.SilkS")
		)
		(fp_line
			(start 4.401 -4.2)
			(end 4.401 -4.899)
			(stroke
				(width 0.15)
				(type solid)
			)
			(layer "F.SilkS")
		)
		(fp_line
			(start 4.401 -2.2)
			(end 4.401 0.6)
			(stroke
				(width 0.15)
				(type solid)
			)
			(layer "F.SilkS")
		)
		(fp_line
			(start 4.401 2.4)
			(end 4.401 3.201)
			(stroke
				(width 0.15)
				(type solid)
			)
			(layer "F.SilkS")
		)
		(fp_circle
			(center -3.299 -5.598)
			(end -3.249 -5.598)
			(stroke
				(width 0.15)
				(type solid)
			)
			(fill solid)
			(layer "F.SilkS")
		)
		(fp_line
			(start -4.9 -5.4)
			(end -3.4 -5.4)
			(stroke
				(width 0.05)
				(type solid)
			)
			(layer "F.CrtYd")
		)
		(fp_line
			(start -4.9 6.5)
			(end -4.9 -5.4)
			(stroke
				(width 0.05)
				(type solid)
			)
			(layer "F.CrtYd")
		)
		(fp_line
			(start -3.4 -6.6)
			(end 3.4 -6.6)
			(stroke
				(width 0.05)
				(type solid)
			)
			(layer "F.CrtYd")
		)
		(fp_line
			(start -3.4 -5.4)
			(end -3.4 -6.6)
			(stroke
				(width 0.05)
				(type solid)
			)
			(layer "F.CrtYd")
		)
		(fp_line
			(start 3.4 -6.6)
			(end 3.4 -5.4)
			(stroke
				(width 0.05)
				(type solid)
			)
			(layer "F.CrtYd")
		)
		(fp_line
			(start 3.4 -5.4)
			(end 4.9 -5.4)
			(stroke
				(width 0.05)
				(type solid)
			)
			(layer "F.CrtYd")
		)
		(fp_line
			(start 4.9 -5.4)
			(end 4.9 6.5)
			(stroke
				(width 0.05)
				(type solid)
			)
			(layer "F.CrtYd")
		)
		(fp_line
			(start 4.9 6.5)
			(end -4.9 6.5)
			(stroke
				(width 0.05)
				(type solid)
			)
			(layer "F.CrtYd")
		)
		(fp_line
			(start -4.499 -5)
			(end -4.499 6.001)
			(stroke
				(width 0.15)
				(type solid)
			)
			(layer "F.Fab")
		)
		(fp_line
			(start -4.499 6.001)
			(end 4.499 6.001)
			(stroke
				(width 0.15)
				(type solid)
			)
			(layer "F.Fab")
		)
		(fp_line
			(start -2.999 -6.3)
			(end -2.999 -5)
			(stroke
				(width 0.15)
				(type solid)
			)
			(layer "F.Fab")
		)
		(fp_line
			(start -2.999 -5)
			(end -4.499 -5)
			(stroke
				(width 0.15)
				(type solid)
			)
			(layer "F.Fab")
		)
		(fp_line
			(start -2.979 -6.158)
			(end -2.859 -6.278)
			(stroke
				(width 0.15)
				(type solid)
			)
			(layer "F.Fab")
		)
		(fp_line
			(start 3 -6.3)
			(end -2.999 -6.3)
			(stroke
				(width 0.15)
				(type solid)
			)
			(layer "F.Fab")
		)
		(fp_line
			(start 3 -5)
			(end 3 -6.3)
			(stroke
				(width 0.15)
				(type solid)
			)
			(layer "F.Fab")
		)
		(fp_line
			(start 4.499 -5)
			(end 3 -5)
			(stroke
				(width 0.15)
				(type solid)
			)
			(layer "F.Fab")
		)
		(fp_line
			(start 4.499 6.001)
			(end 4.499 -5)
			(stroke
				(width 0.15)
				(type solid)
			)
			(layer "F.Fab")
		)
		(fp_text user "License: Apache-2.0"
			(at -5.272 8.495 0)
			(layer "F.Fab")
			(hide yes)
			(effects
				(font
					(size 0.7 0.7)
					(thickness 0.15)
				)
				(justify left bottom)
			)
		)
		(fp_text user "Author: Antmicro"
			(at -5.272 10.895 0)
			(layer "F.Fab")
			(hide yes)
			(effects
				(font
					(size 0.7 0.7)
					(thickness 0.15)
				)
				(justify left bottom)
			)
		)
		(fp_text user "${REFERENCE}"
			(at -5.272 9.695 0)
			(layer "F.Fab")
			(hide yes)
			(effects
				(font
					(size 0.7 0.7)
					(thickness 0.15)
				)
				(justify left bottom)
			)
		)
		(pad "" smd roundrect
			(at 0 -1.055)
			(size 0.2 1)
			(layers "F.Cu" "F.Paste" "F.Mask")
			(roundrect_rratio 0.25)
		)
		(pad "" smd roundrect
			(at 0 2.045)
			(size 0.2 1)
			(layers "F.Cu" "F.Paste" "F.Mask")
			(roundrect_rratio 0.25)
		)
		(pad "A1" smd roundrect
			(at -2.75 -5.635)
			(size 0.3 1.2)
			(layers "F.Cu" "F.Paste" "F.Mask")
			(roundrect_rratio 0.25)
			(net 1 "GND")
			(pinfunction "GND")
			(pintype "power_in")
		)
		(pad "A2" smd roundrect
			(at -2.25 -5.635)
			(size 0.3 1.2)
			(layers "F.Cu" "F.Paste" "F.Mask")
			(roundrect_rratio 0.25)
			(net 265 "/USB3/USBC1_CONN_TX1_N")
			(pinfunction "TX_{1}+")
			(pintype "bidirectional")
		)
		(pad "A3" smd roundrect
			(at -1.75 -5.635)
			(size 0.3 1.2)
			(layers "F.Cu" "F.Paste" "F.Mask")
			(roundrect_rratio 0.25)
			(net 267 "/USB3/USBC1_CONN_TX1_P")
			(pinfunction "TX_{1}-")
			(pintype "bidirectional")
		)
		(pad "A4" smd roundrect
			(at -1.25 -5.635)
			(size 0.3 1.2)
			(layers "F.Cu" "F.Paste" "F.Mask")
			(roundrect_rratio 0.25)
			(net 270 "/USB3/USBC1_VBUS")
			(pinfunction "VBUS")
			(pintype "passive")
		)
		(pad "A5" smd roundrect
			(at -0.75 -5.635)
			(size 0.3 1.2)
			(layers "F.Cu" "F.Paste" "F.Mask")
			(roundrect_rratio 0.25)
			(net 282 "/USB3/USBC1_CC1")
			(pinfunction "CC_{1}")
			(pintype "bidirectional")
		)
		(pad "A6" smd roundrect
			(at -0.25 -5.635)
			(size 0.3 1.2)
			(layers "F.Cu" "F.Paste" "F.Mask")
			(roundrect_rratio 0.25)
			(net 433 "USB0_D_P")
			(pinfunction "D_{A}+")
			(pintype "bidirectional")
		)
		(pad "A7" smd roundrect
			(at 0.25 -5.635)
			(size 0.3 1.2)
			(layers "F.Cu" "F.Paste" "F.Mask")
			(roundrect_rratio 0.25)
			(net 40 "USB0_D_N")
			(pinfunction "D_{A}-")
			(pintype "bidirectional")
		)
		(pad "A8" smd roundrect
			(at 0.75 -5.635)
			(size 0.3 1.2)
			(layers "F.Cu" "F.Paste" "F.Mask")
			(roundrect_rratio 0.25)
			(net 548 "unconnected-(J5-SBU_{1}-PadA8)")
			(pinfunction "SBU_{1}")
			(pintype "bidirectional+no_connect")
		)
		(pad "A9" smd roundrect
			(at 1.25 -5.635)
			(size 0.3 1.2)
			(layers "F.Cu" "F.Paste" "F.Mask")
			(roundrect_rratio 0.25)
			(net 270 "/USB3/USBC1_VBUS")
			(pinfunction "VBUS")
			(pintype "passive")
		)
		(pad "A10" smd roundrect
			(at 1.75 -5.635)
			(size 0.3 1.2)
			(layers "F.Cu" "F.Paste" "F.Mask")
			(roundrect_rratio 0.25)
			(net 369 "/USB3/USBC1_RX2_N")
			(pinfunction "RX_{2}-")
			(pintype "bidirectional")
		)
		(pad "A11" smd roundrect
			(at 2.25 -5.635)
			(size 0.3 1.2)
			(layers "F.Cu" "F.Paste" "F.Mask")
			(roundrect_rratio 0.25)
			(net 390 "/USB3/USBC1_RX2_P")
			(pinfunction "RX_{2}+")
			(pintype "bidirectional")
		)
		(pad "A12" smd roundrect
			(at 2.75 -5.635)
			(size 0.3 1.2)
			(layers "F.Cu" "F.Paste" "F.Mask")
			(roundrect_rratio 0.25)
			(net 1 "GND")
			(pinfunction "GND")
			(pintype "passive")
		)
		(pad "B1" thru_hole circle
			(at 2.8 -4.385)
			(size 0.65 0.65)
			(drill 0.3)
			(layers "*.Cu" "*.Mask")
			(remove_unused_layers no)
			(net 1 "GND")
			(pinfunction "GND")
			(pintype "passive")
		)
		(pad "B2" thru_hole circle
			(at 2.4 -3.685)
			(size 0.65 0.65)
			(drill 0.3)
			(layers "*.Cu" "*.Mask")
			(remove_unused_layers no)
			(net 263 "/USB3/USBC1_CONN_TX2_N")
			(pinfunction "TX_{2}+")
			(pintype "bidirectional")
		)
		(pad "B3" thru_hole circle
			(at 1.6 -3.685)
			(size 0.65 0.65)
			(drill 0.3)
			(layers "*.Cu" "*.Mask")
			(remove_unused_layers no)
			(net 269 "/USB3/USBC1_CONN_TX2_P")
			(pinfunction "TX_{2}-")
			(pintype "bidirectional")
		)
		(pad "B4" thru_hole circle
			(at 1.2 -4.385)
			(size 0.65 0.65)
			(drill 0.3)
			(layers "*.Cu" "*.Mask")
			(remove_unused_layers no)
			(net 270 "/USB3/USBC1_VBUS")
			(pinfunction "VBUS")
			(pintype "passive")
		)
		(pad "B5" thru_hole circle
			(at 0.8 -3.685)
			(size 0.65 0.65)
			(drill 0.3)
			(layers "*.Cu" "*.Mask")
			(remove_unused_layers no)
			(net 283 "/USB3/USBC1_CC2")
			(pinfunction "CC_{2}")
			(pintype "bidirectional")
		)
		(pad "B6" thru_hole circle
			(at 0.4 -4.385)
			(size 0.65 0.65)
			(drill 0.3)
			(layers "*.Cu" "*.Mask")
			(remove_unused_layers no)
			(net 433 "USB0_D_P")
			(pinfunction "D_{B}+")
			(pintype "bidirectional")
		)
		(pad "B7" thru_hole circle
			(at -0.4 -4.385)
			(size 0.65 0.65)
			(drill 0.3)
			(layers "*.Cu" "*.Mask")
			(remove_unused_layers no)
			(net 40 "USB0_D_N")
			(pinfunction "D_{B}-")
			(pintype "bidirectional")
		)
		(pad "B8" thru_hole circle
			(at -0.8 -3.685)
			(size 0.65 0.65)
			(drill 0.3)
			(layers "*.Cu" "*.Mask")
			(remove_unused_layers no)
			(net 550 "unconnected-(J5-SBU_{2}-PadB8)")
			(pinfunction "SBU_{2}")
			(pintype "bidirectional+no_connect")
		)
		(pad "B9" thru_hole circle
			(at -1.2 -4.385)
			(size 0.65 0.65)
			(drill 0.3)
			(layers "*.Cu" "*.Mask")
			(remove_unused_layers no)
			(net 270 "/USB3/USBC1_VBUS")
			(pinfunction "VBUS")
			(pintype "passive")
		)
		(pad "B10" thru_hole circle
			(at -1.6 -3.685)
			(size 0.65 0.65)
			(drill 0.3)
			(layers "*.Cu" "*.Mask")
			(remove_unused_layers no)
			(net 366 "/USB3/USBC1_RX1_N")
			(pinfunction "RX_{1}-")
			(pintype "bidirectional")
		)
		(pad "B11" thru_hole circle
			(at -2.4 -3.685)
			(size 0.65 0.65)
			(drill 0.3)
			(layers "*.Cu" "*.Mask")
			(remove_unused_layers no)
			(net 368 "/USB3/USBC1_RX1_P")
			(pinfunction "RX_{1}+")
			(pintype "bidirectional")
		)
		(pad "B12" thru_hole circle
			(at -2.8 -4.385)
			(size 0.65 0.65)
			(drill 0.3)
			(layers "*.Cu" "*.Mask")
			(remove_unused_layers no)
			(net 1 "GND")
			(pinfunction "GND")
			(pintype "passive")
		)
		(pad "SH" thru_hole oval
			(at -4.27 -3.235)
			(size 1 1.6)
			(drill oval 0.6 1.2)
			(layers "*.Cu" "*.Mask")
			(remove_unused_layers no)
			(net 1 "GND")
			(pinfunction "SH")
			(pintype "passive")
		)
		(pad "SH" thru_hole oval
			(at -4.27 1.495)
			(size 1 1.6)
			(drill oval 0.6 1.2)
			(layers "*.Cu" "*.Mask")
			(remove_unused_layers no)
			(net 1 "GND")
			(pinfunction "SH")
			(pintype "passive")
		)
		(pad "SH" thru_hole circle
			(at -2 -4.385)
			(size 0.65 0.65)
			(drill 0.3)
			(layers "*.Cu" "*.Mask")
			(remove_unused_layers no)
			(net 1 "GND")
			(pinfunction "SH")
			(pintype "passive")
		)
		(pad "SH" thru_hole circle
			(at 2 -4.385)
			(size 0.65 0.65)
			(drill 0.3)
			(layers "*.Cu" "*.Mask")
			(remove_unused_layers no)
			(net 1 "GND")
			(pinfunction "SH")
			(pintype "passive")
		)
		(pad "SH" thru_hole oval
			(at 4.27 -3.235)
			(size 1 1.6)
			(drill oval 0.6 1.2)
			(layers "*.Cu" "*.Mask")
			(remove_unused_layers no)
			(net 1 "GND")
			(pinfunction "SH")
			(pintype "passive")
		)
		(pad "SH" thru_hole oval
			(at 4.27 1.495)
			(size 1 1.6)
			(drill oval 0.6 1.2)
			(layers "*.Cu" "*.Mask")
			(remove_unused_layers no)
			(net 1 "GND")
			(pinfunction "SH")
			(pintype "passive")
		)
	)
	(footprint "antmicro-footprints:C_0402_1005Metric"
		(layer "F.Cu")
		(at 89.3 117.95 90)
		(descr "Capacitor SMD 0402")
		(tags "capacitor SMD 0402")
		(property "Reference" "C164"
			(at -1.03 -0.45 90)
			(layer "F.SilkS")
			(effects
				(font
					(size 0.7 0.7)
					(thickness 0.15)
				)
				(justify left bottom)
			)
		)
		(property "Value" "C_100n_0402"
			(at 0 1.4 90)
			(layer "F.Fab")
			(effects
				(font
					(size 0.7 0.7)
					(thickness 0.15)
				)
				(justify left bottom)
			)
		)
		(property "Footprint" "antmicro-footprints:C_0402_1005Metric"
			(at 0 0 90)
			(layer "F.Fab")
			(hide yes)
			(effects
				(font
					(size 1.27 1.27)
					(thickness 0.15)
				)
			)
		)
		(property "Datasheet" "https://www.murata.com/products/productdetail?partno=GRM155R61H104KE14%23"
			(at 0 0 90)
			(layer "F.Fab")
			(hide yes)
			(effects
				(font
					(size 1.27 1.27)
					(thickness 0.15)
				)
			)
		)
		(property "Author" "Antmicro"
			(at 207.25 28.65 0)
			(layer "F.Fab")
			(hide yes)
			(effects
				(font
					(size 1 1)
					(thickness 0.15)
				)
			)
		)
		(property "Dielectric" "X5R"
			(at 207.25 28.65 0)
			(layer "F.Fab")
			(hide yes)
			(effects
				(font
					(size 1 1)
					(thickness 0.15)
				)
			)
		)
		(property "License" "Apache-2.0"
			(at 207.25 28.65 0)
			(layer "F.Fab")
			(hide yes)
			(effects
				(font
					(size 1 1)
					(thickness 0.15)
				)
			)
		)
		(property "MPN" "GRM155R61H104KE14D"
			(at 207.25 28.65 0)
			(layer "F.Fab")
			(hide yes)
			(effects
				(font
					(size 1 1)
					(thickness 0.15)
				)
			)
		)
		(property "Manufacturer" "Murata"
			(at 207.25 28.65 0)
			(layer "F.Fab")
			(hide yes)
			(effects
				(font
					(size 1 1)
					(thickness 0.15)
				)
			)
		)
		(property "Val" "100n"
			(at 207.25 28.65 0)
			(layer "F.Fab")
			(hide yes)
			(effects
				(font
					(size 1 1)
					(thickness 0.15)
				)
			)
		)
		(property "Voltage" "50V"
			(at 207.25 28.65 0)
			(layer "F.Fab")
			(hide yes)
			(effects
				(font
					(size 1 1)
					(thickness 0.15)
				)
			)
		)
		(sheetname "HDMI")
		(sheetfile "hdmi.kicad_sch")
		(attr smd)
		(fp_rect
			(start -0.925 -0.47)
			(end 0.925 0.47)
			(stroke
				(width 0.05)
				(type default)
			)
			(fill none)
			(layer "F.CrtYd")
		)
		(fp_line
			(start 0.504 -0.25)
			(end 0.504 0.248)
			(stroke
				(width 0.15)
				(type solid)
			)
			(layer "F.Fab")
		)
		(fp_line
			(start -0.494 -0.25)
			(end 0.504 -0.25)
			(stroke
				(width 0.15)
				(type solid)
			)
			(layer "F.Fab")
		)
		(fp_line
			(start 0.504 0.248)
			(end -0.494 0.248)
			(stroke
				(width 0.15)
				(type solid)
			)
			(layer "F.Fab")
		)
		(fp_line
			(start -0.494 0.248)
			(end -0.494 -0.25)
			(stroke
				(width 0.15)
				(type solid)
			)
			(layer "F.Fab")
		)
		(fp_text user "Author: Antmicro"
			(at -0.932 4.17 90)
			(layer "F.Fab")
			(hide yes)
			(effects
				(font
					(size 0.7 0.7)
					(thickness 0.15)
				)
				(justify left bottom)
			)
		)
		(fp_text user "License: Apache-2.0"
			(at -0.932 5.17 90)
			(layer "F.Fab")
			(hide yes)
			(effects
				(font
					(size 0.7 0.7)
					(thickness 0.15)
				)
				(justify left bottom)
			)
		)
		(fp_text user "${REFERENCE}"
			(at -0.932 3.168 90)
			(layer "F.Fab")
			(hide yes)
			(effects
				(font
					(size 0.7 0.7)
					(thickness 0.15)
				)
				(justify left bottom)
			)
		)
		(pad "1" smd roundrect
			(at -0.48 0 90)
			(size 0.59 0.64)
			(layers "F.Cu" "F.Paste" "F.Mask")
			(roundrect_rratio 0.25)
			(net 1 "GND")
			(pintype "passive")
		)
		(pad "2" smd roundrect
			(at 0.48 0 90)
			(size 0.59 0.64)
			(layers "F.Cu" "F.Paste" "F.Mask")
			(roundrect_rratio 0.25)
			(net 498 "/HDMI/5V_HDMI")
			(pintype "passive")
		)
	)
	(footprint "antmicro-footprints:Fiducial_1mm_Mask2mm"
		(layer "F.Cu")
		(at 31.6 70.35)
		(descr "Circular Fiducial, 1mm bare copper, 3mm soldermask opening")
		(tags "fiducial")
		(property "Reference" "FID2"
			(at 0 -1.4 0)
			(layer "F.SilkS")
			(hide yes)
			(effects
				(font
					(size 0.7 0.7)
					(thickness 0.15)
				)
				(justify left bottom)
			)
		)
		(property "Value" "Fiducial_1mm_Mask2mm"
			(at 0 2.2 0)
			(layer "F.Fab")
			(effects
				(font
					(size 0.7 0.7)
					(thickness 0.15)
				)
				(justify left bottom)
			)
		)
		(property "Footprint" "antmicro-footprints:Fiducial_1mm_Mask2mm"
			(at 0 0 0)
			(layer "F.Fab")
			(hide yes)
			(effects
				(font
					(size 1.27 1.27)
					(thickness 0.15)
				)
			)
		)
		(attr board_only exclude_from_pos_files exclude_from_bom)
		(fp_circle
			(center 0 0)
			(end 1.24 0)
			(stroke
				(width 0.05)
				(type solid)
			)
			(fill none)
			(layer "F.CrtYd")
		)
		(fp_circle
			(center 0 0)
			(end 0.999 0)
			(stroke
				(width 0.15)
				(type solid)
			)
			(fill none)
			(layer "F.Fab")
		)
		(fp_text user "License: Apache-2.0"
			(at -1.25 7.003 0)
			(layer "F.Fab")
			(hide yes)
			(effects
				(font
					(size 0.7 0.7)
					(thickness 0.15)
				)
				(justify left bottom)
			)
		)
		(fp_text user "${REFERENCE}"
			(at -1.25 4.603 0)
			(layer "F.Fab")
			(hide yes)
			(effects
				(font
					(size 0.7 0.7)
					(thickness 0.15)
				)
				(justify left bottom)
			)
		)
		(fp_text user "Author: Antmicro"
			(at -1.25 5.803 0)
			(layer "F.Fab")
			(hide yes)
			(effects
				(font
					(size 0.7 0.7)
					(thickness 0.15)
				)
				(justify left bottom)
			)
		)
		(pad "" smd circle
			(at 0 0)
			(size 1 1)
			(layers "F.Cu" "F.Mask")
			(solder_mask_margin 0.5)
			(clearance 0.5)
		)
	)
	(footprint "antmicro-footprints:R_0402_1005Metric"
		(layer "F.Cu")
		(at 103.2 115.8 90)
		(descr "Resistor SMD 0402")
		(tags "resistor SMD 0402")
		(property "Reference" "R137"
			(at 0.9 0.45 90)
			(layer "F.SilkS")
			(effects
				(font
					(size 0.7 0.7)
					(thickness 0.15)
				)
				(justify left bottom)
			)
		)
		(property "Value" "R_10k_0402"
			(at 0 1.4 90)
			(layer "F.Fab")
			(effects
				(font
					(size 0.7 0.7)
					(thickness 0.15)
				)
				(justify left bottom)
			)
		)
		(property "Footprint" "antmicro-footprints:R_0402_1005Metric"
			(at 0 0 90)
			(layer "F.Fab")
			(hide yes)
			(effects
				(font
					(size 1.27 1.27)
					(thickness 0.15)
				)
			)
		)
		(property "Datasheet" "https://www.bourns.com/docs/product-datasheets/cr.pdf"
			(at 0 0 90)
			(layer "F.Fab")
			(hide yes)
			(effects
				(font
					(size 1.27 1.27)
					(thickness 0.15)
				)
			)
		)
		(property "Author" "Antmicro"
			(at 219 12.6 0)
			(layer "F.Fab")
			(hide yes)
			(effects
				(font
					(size 1 1)
					(thickness 0.15)
				)
			)
		)
		(property "License" "Apache-2.0"
			(at 219 12.6 0)
			(layer "F.Fab")
			(hide yes)
			(effects
				(font
					(size 1 1)
					(thickness 0.15)
				)
			)
		)
		(property "MPN" "CR0402-FX-1002GLF"
			(at 219 12.6 0)
			(layer "F.Fab")
			(hide yes)
			(effects
				(font
					(size 1 1)
					(thickness 0.15)
				)
			)
		)
		(property "Manufacturer" "Bourns"
			(at 219 12.6 0)
			(layer "F.Fab")
			(hide yes)
			(effects
				(font
					(size 1 1)
					(thickness 0.15)
				)
			)
		)
		(property "Tolerance" "1%"
			(at 219 12.6 0)
			(layer "F.Fab")
			(hide yes)
			(effects
				(font
					(size 1 1)
					(thickness 0.15)
				)
			)
		)
		(property "Val" "10k"
			(at 219 12.6 0)
			(layer "F.Fab")
			(hide yes)
			(effects
				(font
					(size 1 1)
					(thickness 0.15)
				)
			)
		)
		(sheetname "USB3")
		(sheetfile "usb3.kicad_sch")
		(attr smd)
		(fp_rect
			(start -0.925 -0.47)
			(end 0.925 0.47)
			(stroke
				(width 0.05)
				(type default)
			)
			(fill none)
			(layer "F.CrtYd")
		)
		(fp_rect
			(start -0.5 -0.25)
			(end 0.5 0.25)
			(stroke
				(width 0.15)
				(type solid)
			)
			(fill none)
			(layer "F.Fab")
		)
		(fp_text user "License: Apache-2.0"
			(at -0.95 5.169 90)
			(layer "F.Fab")
			(hide yes)
			(effects
				(font
					(size 0.7 0.7)
					(thickness 0.15)
				)
				(justify left bottom)
			)
		)
		(fp_text user "Author: Antmicro"
			(at -0.95 4.169 90)
			(layer "F.Fab")
			(hide yes)
			(effects
				(font
					(size 0.7 0.7)
					(thickness 0.15)
				)
				(justify left bottom)
			)
		)
		(fp_text user "${REFERENCE}"
			(at -0.95 3.168 90)
			(layer "F.Fab")
			(hide yes)
			(effects
				(font
					(size 0.7 0.7)
					(thickness 0.15)
				)
				(justify left bottom)
			)
		)
		(pad "1" smd roundrect
			(at -0.48 0 90)
			(size 0.59 0.64)
			(layers "F.Cu" "F.Paste" "F.Mask")
			(roundrect_rratio 0.25)
			(net 625 "Net-(Q4-D)")
			(pintype "passive")
		)
		(pad "2" smd roundrect
			(at 0.48 0 90)
			(size 0.59 0.64)
			(layers "F.Cu" "F.Paste" "F.Mask")
			(roundrect_rratio 0.25)
			(net 562 "USBC1_PEN")
			(pintype "passive")
		)
	)
	(footprint "antmicro-footprints:R_0402_1005Metric"
		(layer "F.Cu")
		(at 129.9 107.9 -90)
		(descr "Resistor SMD 0402")
		(tags "resistor SMD 0402")
		(property "Reference" "R39"
			(at 3.85 -0.37 -90)
			(layer "F.SilkS")
			(effects
				(font
					(size 0.7 0.7)
					(thickness 0.15)
				)
				(justify left bottom)
			)
		)
		(property "Value" "R_200R_0402"
			(at 0 1.4 -90)
			(layer "F.Fab")
			(effects
				(font
					(size 0.7 0.7)
					(thickness 0.15)
				)
				(justify left bottom)
			)
		)
		(property "Footprint" "antmicro-footprints:R_0402_1005Metric"
			(at 0 0 -90)
			(layer "F.Fab")
			(hide yes)
			(effects
				(font
					(size 1.27 1.27)
					(thickness 0.15)
				)
			)
		)
		(property "Datasheet" "https://www.bourns.com/docs/product-datasheets/cr.pdf"
			(at 0 0 -90)
			(layer "F.Fab")
			(hide yes)
			(effects
				(font
					(size 1.27 1.27)
					(thickness 0.15)
				)
			)
		)
		(property "Author" "Antmicro"
			(at 22 237.8 0)
			(layer "F.Fab")
			(hide yes)
			(effects
				(font
					(size 1 1)
					(thickness 0.15)
				)
			)
		)
		(property "License" "Apache-2.0"
			(at 22 237.8 0)
			(layer "F.Fab")
			(hide yes)
			(effects
				(font
					(size 1 1)
					(thickness 0.15)
				)
			)
		)
		(property "MPN" "CR0402-FX-2000GLF"
			(at 22 237.8 0)
			(layer "F.Fab")
			(hide yes)
			(effects
				(font
					(size 1 1)
					(thickness 0.15)
				)
			)
		)
		(property "Manufacturer" "Bourns"
			(at 22 237.8 0)
			(layer "F.Fab")
			(hide yes)
			(effects
				(font
					(size 1 1)
					(thickness 0.15)
				)
			)
		)
		(property "Tolerance" "1%"
			(at 22 237.8 0)
			(layer "F.Fab")
			(hide yes)
			(effects
				(font
					(size 1 1)
					(thickness 0.15)
				)
			)
		)
		(property "Val" "200R"
			(at 22 237.8 0)
			(layer "F.Fab")
			(hide yes)
			(effects
				(font
					(size 1 1)
					(thickness 0.15)
				)
			)
		)
		(sheetname "M.2")
		(sheetfile "m-2.kicad_sch")
		(attr smd)
		(fp_rect
			(start -0.925 -0.47)
			(end 0.925 0.47)
			(stroke
				(width 0.05)
				(type default)
			)
			(fill none)
			(layer "F.CrtYd")
		)
		(fp_rect
			(start -0.5 -0.25)
			(end 0.5 0.25)
			(stroke
				(width 0.15)
				(type solid)
			)
			(fill none)
			(layer "F.Fab")
		)
		(fp_text user "${REFERENCE}"
			(at -0.95 3.168 -90)
			(layer "F.Fab")
			(hide yes)
			(effects
				(font
					(size 0.7 0.7)
					(thickness 0.15)
				)
				(justify left bottom)
			)
		)
		(fp_text user "Author: Antmicro"
			(at -0.95 4.169 -90)
			(layer "F.Fab")
			(hide yes)
			(effects
				(font
					(size 0.7 0.7)
					(thickness 0.15)
				)
				(justify left bottom)
			)
		)
		(fp_text user "License: Apache-2.0"
			(at -0.95 5.169 -90)
			(layer "F.Fab")
			(hide yes)
			(effects
				(font
					(size 0.7 0.7)
					(thickness 0.15)
				)
				(justify left bottom)
			)
		)
		(pad "1" smd roundrect
			(at -0.48 0 270)
			(size 0.59 0.64)
			(layers "F.Cu" "F.Paste" "F.Mask")
			(roundrect_rratio 0.25)
			(net 141 "Net-(D1-A)")
			(pintype "passive")
		)
		(pad "2" smd roundrect
			(at 0.48 0 270)
			(size 0.59 0.64)
			(layers "F.Cu" "F.Paste" "F.Mask")
			(roundrect_rratio 0.25)
			(net 87 "+3V3")
			(pintype "passive")
		)
	)
	(footprint "antmicro-footprints:R_0402_1005Metric"
		(layer "F.Cu")
		(at 105.15 104.1 180)
		(descr "Resistor SMD 0402")
		(tags "resistor SMD 0402")
		(property "Reference" "R116"
			(at 3.65 -0.4 180)
			(layer "F.SilkS")
			(effects
				(font
					(size 0.7 0.7)
					(thickness 0.15)
				)
				(justify left bottom)
			)
		)
		(property "Value" "R_10k_0402"
			(at 0 1.4 180)
			(layer "F.Fab")
			(effects
				(font
					(size 0.7 0.7)
					(thickness 0.15)
				)
				(justify left bottom)
			)
		)
		(property "Footprint" "antmicro-footprints:R_0402_1005Metric"
			(at 0 0 180)
			(layer "F.Fab")
			(hide yes)
			(effects
				(font
					(size 1.27 1.27)
					(thickness 0.15)
				)
			)
		)
		(property "Datasheet" "https://www.bourns.com/docs/product-datasheets/cr.pdf"
			(at 0 0 180)
			(layer "F.Fab")
			(hide yes)
			(effects
				(font
					(size 1.27 1.27)
					(thickness 0.15)
				)
			)
		)
		(property "Author" "Antmicro"
			(at 210.3 208.2 0)
			(layer "F.Fab")
			(hide yes)
			(effects
				(font
					(size 1 1)
					(thickness 0.15)
				)
			)
		)
		(property "License" "Apache-2.0"
			(at 210.3 208.2 0)
			(layer "F.Fab")
			(hide yes)
			(effects
				(font
					(size 1 1)
					(thickness 0.15)
				)
			)
		)
		(property "MPN" "CR0402-FX-1002GLF"
			(at 210.3 208.2 0)
			(layer "F.Fab")
			(hide yes)
			(effects
				(font
					(size 1 1)
					(thickness 0.15)
				)
			)
		)
		(property "Manufacturer" "Bourns"
			(at 210.3 208.2 0)
			(layer "F.Fab")
			(hide yes)
			(effects
				(font
					(size 1 1)
					(thickness 0.15)
				)
			)
		)
		(property "Tolerance" "1%"
			(at 210.3 208.2 0)
			(layer "F.Fab")
			(hide yes)
			(effects
				(font
					(size 1 1)
					(thickness 0.15)
				)
			)
		)
		(property "Val" "10k"
			(at 210.3 208.2 0)
			(layer "F.Fab")
			(hide yes)
			(effects
				(font
					(size 1 1)
					(thickness 0.15)
				)
			)
		)
		(sheetname "USB3")
		(sheetfile "usb3.kicad_sch")
		(attr smd)
		(fp_rect
			(start -0.925 -0.47)
			(end 0.925 0.47)
			(stroke
				(width 0.05)
				(type default)
			)
			(fill none)
			(layer "F.CrtYd")
		)
		(fp_rect
			(start -0.5 -0.25)
			(end 0.5 0.25)
			(stroke
				(width 0.15)
				(type solid)
			)
			(fill none)
			(layer "F.Fab")
		)
		(fp_text user "Author: Antmicro"
			(at -0.95 4.169 180)
			(layer "F.Fab")
			(hide yes)
			(effects
				(font
					(size 0.7 0.7)
					(thickness 0.15)
				)
				(justify left bottom)
			)
		)
		(fp_text user "License: Apache-2.0"
			(at -0.95 5.169 180)
			(layer "F.Fab")
			(hide yes)
			(effects
				(font
					(size 0.7 0.7)
					(thickness 0.15)
				)
				(justify left bottom)
			)
		)
		(fp_text user "${REFERENCE}"
			(at -0.95 3.168 180)
			(layer "F.Fab")
			(hide yes)
			(effects
				(font
					(size 0.7 0.7)
					(thickness 0.15)
				)
				(justify left bottom)
			)
		)
		(pad "1" smd roundrect
			(at -0.48 0 180)
			(size 0.59 0.64)
			(layers "F.Cu" "F.Paste" "F.Mask")
			(roundrect_rratio 0.25)
			(net 316 "/USB3/USBC1_I_MODE")
			(pintype "passive")
		)
		(pad "2" smd roundrect
			(at 0.48 0 180)
			(size 0.59 0.64)
			(layers "F.Cu" "F.Paste" "F.Mask")
			(roundrect_rratio 0.25)
			(net 99 "+5V")
			(pintype "passive")
		)
	)
	(footprint "antmicro-footprints:C_0402_1005Metric"
		(layer "F.Cu")
		(at 76.6 111 -90)
		(descr "Capacitor SMD 0402")
		(tags "capacitor SMD 0402")
		(property "Reference" "C61"
			(at 2.95 -0.45 -90)
			(layer "F.SilkS")
			(effects
				(font
					(size 0.7 0.7)
					(thickness 0.15)
				)
				(justify left bottom)
			)
		)
		(property "Value" "C_100n_0402"
			(at 0 1.4 -90)
			(layer "F.Fab")
			(effects
				(font
					(size 0.7 0.7)
					(thickness 0.15)
				)
				(justify left bottom)
			)
		)
		(property "Footprint" "antmicro-footprints:C_0402_1005Metric"
			(at 0 0 -90)
			(layer "F.Fab")
			(hide yes)
			(effects
				(font
					(size 1.27 1.27)
					(thickness 0.15)
				)
			)
		)
		(property "Datasheet" "https://www.murata.com/products/productdetail?partno=GRM155R61H104KE14%23"
			(at 0 0 -90)
			(layer "F.Fab")
			(hide yes)
			(effects
				(font
					(size 1.27 1.27)
					(thickness 0.15)
				)
			)
		)
		(property "Author" "Antmicro"
			(at -34.4 187.6 0)
			(layer "F.Fab")
			(hide yes)
			(effects
				(font
					(size 1 1)
					(thickness 0.15)
				)
			)
		)
		(property "Dielectric" "X5R"
			(at -34.4 187.6 0)
			(layer "F.Fab")
			(hide yes)
			(effects
				(font
					(size 1 1)
					(thickness 0.15)
				)
			)
		)
		(property "License" "Apache-2.0"
			(at -34.4 187.6 0)
			(layer "F.Fab")
			(hide yes)
			(effects
				(font
					(size 1 1)
					(thickness 0.15)
				)
			)
		)
		(property "MPN" "GRM155R61H104KE14D"
			(at -34.4 187.6 0)
			(layer "F.Fab")
			(hide yes)
			(effects
				(font
					(size 1 1)
					(thickness 0.15)
				)
			)
		)
		(property "Manufacturer" "Murata"
			(at -34.4 187.6 0)
			(layer "F.Fab")
			(hide yes)
			(effects
				(font
					(size 1 1)
					(thickness 0.15)
				)
			)
		)
		(property "Val" "100n"
			(at -34.4 187.6 0)
			(layer "F.Fab")
			(hide yes)
			(effects
				(font
					(size 1 1)
					(thickness 0.15)
				)
			)
		)
		(property "Voltage" "50V"
			(at -34.4 187.6 0)
			(layer "F.Fab")
			(hide yes)
			(effects
				(font
					(size 1 1)
					(thickness 0.15)
				)
			)
		)
		(sheetname "USB Debug, DP")
		(sheetfile "usb.kicad_sch")
		(attr smd)
		(fp_rect
			(start -0.925 -0.47)
			(end 0.925 0.47)
			(stroke
				(width 0.05)
				(type default)
			)
			(fill none)
			(layer "F.CrtYd")
		)
		(fp_line
			(start -0.494 0.248)
			(end -0.494 -0.25)
			(stroke
				(width 0.15)
				(type solid)
			)
			(layer "F.Fab")
		)
		(fp_line
			(start 0.504 0.248)
			(end -0.494 0.248)
			(stroke
				(width 0.15)
				(type solid)
			)
			(layer "F.Fab")
		)
		(fp_line
			(start -0.494 -0.25)
			(end 0.504 -0.25)
			(stroke
				(width 0.15)
				(type solid)
			)
			(layer "F.Fab")
		)
		(fp_line
			(start 0.504 -0.25)
			(end 0.504 0.248)
			(stroke
				(width 0.15)
				(type solid)
			)
			(layer "F.Fab")
		)
		(fp_text user "${REFERENCE}"
			(at -0.932 3.168 -90)
			(layer "F.Fab")
			(hide yes)
			(effects
				(font
					(size 0.7 0.7)
					(thickness 0.15)
				)
				(justify left bottom)
			)
		)
		(fp_text user "License: Apache-2.0"
			(at -0.932 5.17 -90)
			(layer "F.Fab")
			(hide yes)
			(effects
				(font
					(size 0.7 0.7)
					(thickness 0.15)
				)
				(justify left bottom)
			)
		)
		(fp_text user "Author: Antmicro"
			(at -0.932 4.17 -90)
			(layer "F.Fab")
			(hide yes)
			(effects
				(font
					(size 0.7 0.7)
					(thickness 0.15)
				)
				(justify left bottom)
			)
		)
		(pad "1" smd roundrect
			(at -0.48 0 270)
			(size 0.59 0.64)
			(layers "F.Cu" "F.Paste" "F.Mask")
			(roundrect_rratio 0.25)
			(net 259 "/USB Debug, DP/USBC0_TX2_P")
			(pintype "passive")
		)
		(pad "2" smd roundrect
			(at 0.48 0 270)
			(size 0.59 0.64)
			(layers "F.Cu" "F.Paste" "F.Mask")
			(roundrect_rratio 0.25)
			(net 260 "/USB Debug, DP/USBC0_CONN_TX2_P")
			(pintype "passive")
		)
	)
	(footprint "antmicro-footprints:C_0603_1608Metric_EIA"
		(layer "F.Cu")
		(at 72.575 91.67 -90)
		(descr "Capacitor SMD 0603, IPC-7351 Density Level A")
		(tags "Capacitor 0603")
		(property "Reference" "C128"
			(at -6.406396 -14.09 -90)
			(layer "F.SilkS")
			(effects
				(font
					(size 0.7 0.7)
					(thickness 0.15)
				)
				(justify left bottom)
			)
		)
		(property "Value" "C_22u_16V_0603"
			(at -1.42757 1.770288 -90)
			(layer "F.Fab")
			(effects
				(font
					(size 0.7 0.7)
					(thickness 0.15)
				)
				(justify left bottom)
			)
		)
		(property "Footprint" "antmicro-footprints:C_0603_1608Metric_EIA"
			(at 0 0 -90)
			(layer "F.Fab")
			(hide yes)
			(effects
				(font
					(size 1.27 1.27)
					(thickness 0.15)
				)
			)
		)
		(property "Datasheet" "https://product.samsungsem.com/mlcc/CL10A226MO7JZN.do"
			(at 0 0 -90)
			(layer "F.Fab")
			(hide yes)
			(effects
				(font
					(size 1.27 1.27)
					(thickness 0.15)
				)
			)
		)
		(property "Description" "SMD Multilayer Ceramic Capacitor"
			(at 0 0 -90)
			(layer "F.Fab")
			(hide yes)
			(effects
				(font
					(size 1.27 1.27)
					(thickness 0.15)
				)
			)
		)
		(property "Manufacturer" "Samsung Electro-Mechanics"
			(at 0 0 -90)
			(unlocked yes)
			(layer "F.Fab")
			(hide yes)
			(effects
				(font
					(size 1 1)
					(thickness 0.15)
				)
			)
		)
		(property "MPN" "CL10A226MO7JZNC"
			(at 0 0 -90)
			(unlocked yes)
			(layer "F.Fab")
			(hide yes)
			(effects
				(font
					(size 1 1)
					(thickness 0.15)
				)
			)
		)
		(property "Val" "22u"
			(at 0 0 -90)
			(unlocked yes)
			(layer "F.Fab")
			(hide yes)
			(effects
				(font
					(size 1 1)
					(thickness 0.15)
				)
			)
		)
		(property "License" "Apache-2.0"
			(at 0 0 -90)
			(unlocked yes)
			(layer "F.Fab")
			(hide yes)
			(effects
				(font
					(size 1 1)
					(thickness 0.15)
				)
			)
		)
		(property "Author" "Antmicro"
			(at 0 0 -90)
			(unlocked yes)
			(layer "F.Fab")
			(hide yes)
			(effects
				(font
					(size 1 1)
					(thickness 0.15)
				)
			)
		)
		(property "Voltage" "16V"
			(at 0 0 -90)
			(unlocked yes)
			(layer "F.Fab")
			(hide yes)
			(effects
				(font
					(size 1 1)
					(thickness 0.15)
				)
			)
		)
		(property "Dielectric" ""
			(at 0 0 -90)
			(unlocked yes)
			(layer "F.Fab")
			(hide yes)
			(effects
				(font
					(size 1 1)
					(thickness 0.15)
				)
			)
		)
		(sheetname "Supply")
		(sheetfile "supply.kicad_sch")
		(attr smd)
		(fp_line
			(start -0.15 0.55)
			(end 0.15 0.55)
			(stroke
				(width 0.15)
				(type solid)
			)
			(layer "F.SilkS")
		)
		(fp_line
			(start -0.15 -0.55)
			(end 0.15 -0.55)
			(stroke
				(width 0.15)
				(type solid)
			)
			(layer "F.SilkS")
		)
		(fp_rect
			(start -1.25 -0.65)
			(end 1.25 0.65)
			(stroke
				(width 0.05)
				(type solid)
			)
			(fill none)
			(layer "F.CrtYd")
		)
		(fp_rect
			(start -0.8 -0.45)
			(end 0.8 0.45)
			(stroke
				(width 0.15)
				(type solid)
			)
			(fill none)
			(layer "F.Fab")
		)
		(fp_text user "License: Apache-2.0"
			(at -1.682 5.895 -90)
			(layer "F.Fab")
			(hide yes)
			(effects
				(font
					(size 0.7 0.7)
					(thickness 0.15)
				)
				(justify left bottom)
			)
		)
		(fp_text user "Author: Antmicro"
			(at -1.682 4.894 -90)
			(layer "F.Fab")
			(hide yes)
			(effects
				(font
					(size 0.7 0.7)
					(thickness 0.15)
				)
				(justify left bottom)
			)
		)
		(fp_text user "${REFERENCE}"
			(at -1.682 3.895 -90)
			(layer "F.Fab")
			(hide yes)
			(effects
				(font
					(size 0.7 0.7)
					(thickness 0.15)
				)
				(justify left bottom)
			)
		)
		(pad "1" smd roundrect
			(at -0.7 0 270)
			(size 0.8 1.1)
			(layers "F.Cu" "F.Paste" "F.Mask")
			(roundrect_rratio 0.2)
			(net 1 "GND")
			(pintype "passive")
		)
		(pad "2" smd roundrect
			(at 0.7 0 270)
			(size 0.8 1.1)
			(layers "F.Cu" "F.Paste" "F.Mask")
			(roundrect_rratio 0.2)
			(net 641 "/Supply/3V3_OUT")
			(pintype "passive")
		)
	)
	(footprint "antmicro-footprints:R_0402_1005Metric"
		(layer "F.Cu")
		(at 89.95 88.7 -90)
		(descr "Resistor SMD 0402")
		(tags "resistor SMD 0402")
		(property "Reference" "R277"
			(at -0.88 -0.53 -90)
			(layer "F.SilkS")
			(effects
				(font
					(size 0.7 0.7)
					(thickness 0.15)
				)
				(justify left bottom)
			)
		)
		(property "Value" "R_0R_0402"
			(at 0 1.4 -90)
			(layer "F.Fab")
			(effects
				(font
					(size 0.7 0.7)
					(thickness 0.15)
				)
				(justify left bottom)
			)
		)
		(property "Footprint" "antmicro-footprints:R_0402_1005Metric"
			(at 0 0 -90)
			(layer "F.Fab")
			(hide yes)
			(effects
				(font
					(size 1.27 1.27)
					(thickness 0.15)
				)
			)
		)
		(property "Datasheet" "https://industrial.panasonic.com/cdbs/www-data/pdf/RDA0000/AOA0000C301.pdf"
			(at 0 0 -90)
			(layer "F.Fab")
			(hide yes)
			(effects
				(font
					(size 1.27 1.27)
					(thickness 0.15)
				)
			)
		)
		(property "Author" "Antmicro"
			(at 1.25 178.65 0)
			(layer "F.Fab")
			(hide yes)
			(effects
				(font
					(size 1 1)
					(thickness 0.15)
				)
			)
		)
		(property "Current" "1A"
			(at 1.25 178.65 0)
			(layer "F.Fab")
			(hide yes)
			(effects
				(font
					(size 1 1)
					(thickness 0.15)
				)
			)
		)
		(property "License" "Apache-2.0"
			(at 1.25 178.65 0)
			(layer "F.Fab")
			(hide yes)
			(effects
				(font
					(size 1 1)
					(thickness 0.15)
				)
			)
		)
		(property "MPN" "ERJ2GE0R00X"
			(at 1.25 178.65 0)
			(layer "F.Fab")
			(hide yes)
			(effects
				(font
					(size 1 1)
					(thickness 0.15)
				)
			)
		)
		(property "Manufacturer" "Panasonic"
			(at 1.25 178.65 0)
			(layer "F.Fab")
			(hide yes)
			(effects
				(font
					(size 1 1)
					(thickness 0.15)
				)
			)
		)
		(property "Tolerance" ""
			(at 1.25 178.65 0)
			(layer "F.Fab")
			(hide yes)
			(effects
				(font
					(size 1 1)
					(thickness 0.15)
				)
			)
		)
		(property "Val" "0R"
			(at 1.25 178.65 0)
			(layer "F.Fab")
			(hide yes)
			(effects
				(font
					(size 1 1)
					(thickness 0.15)
				)
			)
		)
		(sheetname "HDMI")
		(sheetfile "hdmi.kicad_sch")
		(attr smd)
		(fp_rect
			(start -0.925 -0.47)
			(end 0.925 0.47)
			(stroke
				(width 0.05)
				(type default)
			)
			(fill none)
			(layer "F.CrtYd")
		)
		(fp_rect
			(start -0.5 -0.25)
			(end 0.5 0.25)
			(stroke
				(width 0.15)
				(type solid)
			)
			(fill none)
			(layer "F.Fab")
		)
		(fp_text user "${REFERENCE}"
			(at -0.95 3.168 -90)
			(layer "F.Fab")
			(hide yes)
			(effects
				(font
					(size 0.7 0.7)
					(thickness 0.15)
				)
				(justify left bottom)
			)
		)
		(fp_text user "License: Apache-2.0"
			(at -0.95 5.169 -90)
			(layer "F.Fab")
			(hide yes)
			(effects
				(font
					(size 0.7 0.7)
					(thickness 0.15)
				)
				(justify left bottom)
			)
		)
		(fp_text user "Author: Antmicro"
			(at -0.95 4.169 -90)
			(layer "F.Fab")
			(hide yes)
			(effects
				(font
					(size 0.7 0.7)
					(thickness 0.15)
				)
				(justify left bottom)
			)
		)
		(pad "1" smd roundrect
			(at -0.48 0 270)
			(size 0.59 0.64)
			(layers "F.Cu" "F.Paste" "F.Mask")
			(roundrect_rratio 0.25)
			(net 679 "/HDMI/DP_MUX_AUX_A+")
			(pintype "passive")
		)
		(pad "2" smd roundrect
			(at 0.48 0 270)
			(size 0.59 0.64)
			(layers "F.Cu" "F.Paste" "F.Mask")
			(roundrect_rratio 0.25)
			(net 555 "/HDMI/HDMI_SCL_3V3")
			(pintype "passive")
		)
	)
	(footprint "antmicro-footprints:R_0402_1005Metric"
		(layer "F.Cu")
		(at 68.74 82.31 -90)
		(descr "Resistor SMD 0402")
		(tags "resistor SMD 0402")
		(property "Reference" "R2"
			(at 0.84 0.37 90)
			(layer "F.SilkS")
			(effects
				(font
					(size 0.7 0.7)
					(thickness 0.15)
				)
				(justify right top)
			)
		)
		(property "Value" "R_0R_0402"
			(at 0 1.4 90)
			(layer "F.Fab")
			(effects
				(font
					(size 0.7 0.7)
					(thickness 0.15)
				)
				(justify right top)
			)
		)
		(property "Footprint" "antmicro-footprints:R_0402_1005Metric"
			(at 0 0 90)
			(layer "F.Fab")
			(hide yes)
			(effects
				(font
					(size 1.27 1.27)
					(thickness 0.15)
				)
			)
		)
		(property "Datasheet" "https://industrial.panasonic.com/cdbs/www-data/pdf/RDA0000/AOA0000C301.pdf"
			(at 0 0 90)
			(layer "F.Fab")
			(hide yes)
			(effects
				(font
					(size 1.27 1.27)
					(thickness 0.15)
				)
			)
		)
		(property "Author" "Antmicro"
			(at -14.1 151 0)
			(layer "F.Fab")
			(hide yes)
			(effects
				(font
					(size 1 1)
					(thickness 0.15)
				)
			)
		)
		(property "Current" "1A"
			(at -14.1 151 0)
			(layer "F.Fab")
			(hide yes)
			(effects
				(font
					(size 1 1)
					(thickness 0.15)
				)
			)
		)
		(property "License" "Apache-2.0"
			(at -14.1 151 0)
			(layer "F.Fab")
			(hide yes)
			(effects
				(font
					(size 1 1)
					(thickness 0.15)
				)
			)
		)
		(property "MPN" "ERJ2GE0R00X"
			(at -14.1 151 0)
			(layer "F.Fab")
			(hide yes)
			(effects
				(font
					(size 1 1)
					(thickness 0.15)
				)
			)
		)
		(property "Manufacturer" "Panasonic"
			(at -14.1 151 0)
			(layer "F.Fab")
			(hide yes)
			(effects
				(font
					(size 1 1)
					(thickness 0.15)
				)
			)
		)
		(property "Tolerance" ""
			(at -14.1 151 0)
			(layer "F.Fab")
			(hide yes)
			(effects
				(font
					(size 1 1)
					(thickness 0.15)
				)
			)
		)
		(property "Val" "0R"
			(at -14.1 151 0)
			(layer "F.Fab")
			(hide yes)
			(effects
				(font
					(size 1 1)
					(thickness 0.15)
				)
			)
		)
		(sheetname "SoM")
		(sheetfile "som.kicad_sch")
		(attr smd)
		(fp_rect
			(start -0.925 -0.47)
			(end 0.925 0.47)
			(stroke
				(width 0.05)
				(type default)
			)
			(fill none)
			(layer "F.CrtYd")
		)
		(fp_rect
			(start -0.5 -0.25)
			(end 0.5 0.25)
			(stroke
				(width 0.15)
				(type solid)
			)
			(fill none)
			(layer "F.Fab")
		)
		(fp_text user "License: Apache-2.0"
			(at -0.95 5.169 90)
			(layer "F.Fab")
			(hide yes)
			(effects
				(font
					(size 0.7 0.7)
					(thickness 0.15)
				)
				(justify right top)
			)
		)
		(fp_text user "${REFERENCE}"
			(at -0.95 3.168 90)
			(layer "F.Fab")
			(hide yes)
			(effects
				(font
					(size 0.7 0.7)
					(thickness 0.15)
				)
				(justify right top)
			)
		)
		(fp_text user "Author: Antmicro"
			(at -0.95 4.169 90)
			(layer "F.Fab")
			(hide yes)
			(effects
				(font
					(size 0.7 0.7)
					(thickness 0.15)
				)
				(justify right top)
			)
		)
		(pad "1" smd roundrect
			(at -0.48 0 270)
			(size 0.59 0.64)
			(layers "F.Cu" "F.Paste" "F.Mask")
			(roundrect_rratio 0.25)
			(net 752 "Net-(J15H-GPIO12{slash}PWM)")
			(pintype "passive")
		)
		(pad "2" smd roundrect
			(at 0.48 0 270)
			(size 0.59 0.64)
			(layers "F.Cu" "F.Paste" "F.Mask")
			(roundrect_rratio 0.25)
			(net 83 "GPIO12")
			(pintype "passive")
		)
	)
	(footprint "antmicro-footprints:R_0402_1005Metric"
		(layer "F.Cu")
		(at 127.05 99.55 180)
		(descr "Resistor SMD 0402")
		(tags "resistor SMD 0402")
		(property "Reference" "R14"
			(at 1 -1.35 0)
			(layer "F.SilkS")
			(effects
				(font
					(size 0.7 0.7)
					(thickness 0.15)
				)
				(justify left bottom)
			)
		)
		(property "Value" "R_0R_0402"
			(at 0 1.4 180)
			(layer "F.Fab")
			(effects
				(font
					(size 0.7 0.7)
					(thickness 0.15)
				)
				(justify left bottom)
			)
		)
		(property "Footprint" "antmicro-footprints:R_0402_1005Metric"
			(at 0 0 180)
			(layer "F.Fab")
			(hide yes)
			(effects
				(font
					(size 1.27 1.27)
					(thickness 0.15)
				)
			)
		)
		(property "Datasheet" "https://industrial.panasonic.com/cdbs/www-data/pdf/RDA0000/AOA0000C301.pdf"
			(at 0 0 180)
			(layer "F.Fab")
			(hide yes)
			(effects
				(font
					(size 1.27 1.27)
					(thickness 0.15)
				)
			)
		)
		(property "Author" "Antmicro"
			(at 254.1 199.1 0)
			(layer "F.Fab")
			(hide yes)
			(effects
				(font
					(size 1 1)
					(thickness 0.15)
				)
			)
		)
		(property "Current" "1A"
			(at 254.1 199.1 0)
			(layer "F.Fab")
			(hide yes)
			(effects
				(font
					(size 1 1)
					(thickness 0.15)
				)
			)
		)
		(property "License" "Apache-2.0"
			(at 254.1 199.1 0)
			(layer "F.Fab")
			(hide yes)
			(effects
				(font
					(size 1 1)
					(thickness 0.15)
				)
			)
		)
		(property "MPN" "ERJ2GE0R00X"
			(at 254.1 199.1 0)
			(layer "F.Fab")
			(hide yes)
			(effects
				(font
					(size 1 1)
					(thickness 0.15)
				)
			)
		)
		(property "Manufacturer" "Panasonic"
			(at 254.1 199.1 0)
			(layer "F.Fab")
			(hide yes)
			(effects
				(font
					(size 1 1)
					(thickness 0.15)
				)
			)
		)
		(property "Tolerance" ""
			(at 254.1 199.1 0)
			(layer "F.Fab")
			(hide yes)
			(effects
				(font
					(size 1 1)
					(thickness 0.15)
				)
			)
		)
		(property "Val" "0R"
			(at 254.1 199.1 0)
			(layer "F.Fab")
			(hide yes)
			(effects
				(font
					(size 1 1)
					(thickness 0.15)
				)
			)
		)
		(sheetname "M.2")
		(sheetfile "m-2.kicad_sch")
		(attr smd)
		(fp_rect
			(start -0.925 -0.47)
			(end 0.925 0.47)
			(stroke
				(width 0.05)
				(type default)
			)
			(fill none)
			(layer "F.CrtYd")
		)
		(fp_rect
			(start -0.5 -0.25)
			(end 0.5 0.25)
			(stroke
				(width 0.15)
				(type solid)
			)
			(fill none)
			(layer "F.Fab")
		)
		(fp_text user "Author: Antmicro"
			(at -0.95 4.169 180)
			(layer "F.Fab")
			(hide yes)
			(effects
				(font
					(size 0.7 0.7)
					(thickness 0.15)
				)
				(justify left bottom)
			)
		)
		(fp_text user "${REFERENCE}"
			(at -0.95 3.168 180)
			(layer "F.Fab")
			(hide yes)
			(effects
				(font
					(size 0.7 0.7)
					(thickness 0.15)
				)
				(justify left bottom)
			)
		)
		(fp_text user "License: Apache-2.0"
			(at -0.95 5.169 180)
			(layer "F.Fab")
			(hide yes)
			(effects
				(font
					(size 0.7 0.7)
					(thickness 0.15)
				)
				(justify left bottom)
			)
		)
		(pad "1" smd roundrect
			(at -0.48 0 180)
			(size 0.59 0.64)
			(layers "F.Cu" "F.Paste" "F.Mask")
			(roundrect_rratio 0.25)
			(net 453 "PCIE_WAKE*")
			(pintype "passive")
		)
		(pad "2" smd roundrect
			(at 0.48 0 180)
			(size 0.59 0.64)
			(layers "F.Cu" "F.Paste" "F.Mask")
			(roundrect_rratio 0.25)
			(net 171 "/M.2/PCIE_WAKE_SEL1")
			(pintype "passive")
		)
	)
	(footprint "antmicro-footprints:R_0402_1005Metric"
		(layer "F.Cu")
		(at 129.3 92.2 180)
		(descr "Resistor SMD 0402")
		(tags "resistor SMD 0402")
		(property "Reference" "R52"
			(at 2.925 -0.45 180)
			(layer "F.SilkS")
			(effects
				(font
					(size 0.7 0.7)
					(thickness 0.15)
				)
				(justify left bottom)
			)
		)
		(property "Value" "R_0R_0402"
			(at 0 1.4 180)
			(layer "F.Fab")
			(effects
				(font
					(size 0.7 0.7)
					(thickness 0.15)
				)
				(justify left bottom)
			)
		)
		(property "Footprint" "antmicro-footprints:R_0402_1005Metric"
			(at 0 0 180)
			(layer "F.Fab")
			(hide yes)
			(effects
				(font
					(size 1.27 1.27)
					(thickness 0.15)
				)
			)
		)
		(property "Datasheet" "https://industrial.panasonic.com/cdbs/www-data/pdf/RDA0000/AOA0000C301.pdf"
			(at 0 0 180)
			(layer "F.Fab")
			(hide yes)
			(effects
				(font
					(size 1.27 1.27)
					(thickness 0.15)
				)
			)
		)
		(property "Author" "Antmicro"
			(at 258.6 184.4 0)
			(layer "F.Fab")
			(hide yes)
			(effects
				(font
					(size 1 1)
					(thickness 0.15)
				)
			)
		)
		(property "Current" "1A"
			(at 258.6 184.4 0)
			(layer "F.Fab")
			(hide yes)
			(effects
				(font
					(size 1 1)
					(thickness 0.15)
				)
			)
		)
		(property "License" "Apache-2.0"
			(at 258.6 184.4 0)
			(layer "F.Fab")
			(hide yes)
			(effects
				(font
					(size 1 1)
					(thickness 0.15)
				)
			)
		)
		(property "MPN" "ERJ2GE0R00X"
			(at 258.6 184.4 0)
			(layer "F.Fab")
			(hide yes)
			(effects
				(font
					(size 1 1)
					(thickness 0.15)
				)
			)
		)
		(property "Manufacturer" "Panasonic"
			(at 258.6 184.4 0)
			(layer "F.Fab")
			(hide yes)
			(effects
				(font
					(size 1 1)
					(thickness 0.15)
				)
			)
		)
		(property "Tolerance" ""
			(at 258.6 184.4 0)
			(layer "F.Fab")
			(hide yes)
			(effects
				(font
					(size 1 1)
					(thickness 0.15)
				)
			)
		)
		(property "Val" "0R"
			(at 258.6 184.4 0)
			(layer "F.Fab")
			(hide yes)
			(effects
				(font
					(size 1 1)
					(thickness 0.15)
				)
			)
		)
		(sheetname "M.2")
		(sheetfile "m-2.kicad_sch")
		(attr smd)
		(fp_rect
			(start -0.925 -0.47)
			(end 0.925 0.47)
			(stroke
				(width 0.05)
				(type default)
			)
			(fill none)
			(layer "F.CrtYd")
		)
		(fp_rect
			(start -0.5 -0.25)
			(end 0.5 0.25)
			(stroke
				(width 0.15)
				(type solid)
			)
			(fill none)
			(layer "F.Fab")
		)
		(fp_text user "Author: Antmicro"
			(at -0.95 4.169 180)
			(layer "F.Fab")
			(hide yes)
			(effects
				(font
					(size 0.7 0.7)
					(thickness 0.15)
				)
				(justify left bottom)
			)
		)
		(fp_text user "${REFERENCE}"
			(at -0.95 3.168 180)
			(layer "F.Fab")
			(hide yes)
			(effects
				(font
					(size 0.7 0.7)
					(thickness 0.15)
				)
				(justify left bottom)
			)
		)
		(fp_text user "License: Apache-2.0"
			(at -0.95 5.169 180)
			(layer "F.Fab")
			(hide yes)
			(effects
				(font
					(size 0.7 0.7)
					(thickness 0.15)
				)
				(justify left bottom)
			)
		)
		(pad "1" smd roundrect
			(at -0.48 0 180)
			(size 0.59 0.64)
			(layers "F.Cu" "F.Paste" "F.Mask")
			(roundrect_rratio 0.25)
			(net 434 "USB1_D_N")
			(pintype "passive")
		)
		(pad "2" smd roundrect
			(at 0.48 0 180)
			(size 0.59 0.64)
			(layers "F.Cu" "F.Paste" "F.Mask")
			(roundrect_rratio 0.25)
			(net 617 "/M.2/USB_E_N")
			(pintype "passive")
		)
	)
	(footprint "antmicro-footprints:R_0402_1005Metric"
		(layer "F.Cu")
		(at 148 108.5)
		(descr "Resistor SMD 0402")
		(tags "resistor SMD 0402")
		(property "Reference" "R120"
			(at -1.21 6.1 0)
			(layer "F.SilkS")
			(effects
				(font
					(size 0.7 0.7)
					(thickness 0.15)
				)
				(justify left bottom)
			)
		)
		(property "Value" "R_0R_0402"
			(at 0 1.4 0)
			(layer "F.Fab")
			(effects
				(font
					(size 0.7 0.7)
					(thickness 0.15)
				)
				(justify left bottom)
			)
		)
		(property "Footprint" "antmicro-footprints:R_0402_1005Metric"
			(at 0 0 0)
			(layer "F.Fab")
			(hide yes)
			(effects
				(font
					(size 1.27 1.27)
					(thickness 0.15)
				)
			)
		)
		(property "Datasheet" "https://industrial.panasonic.com/cdbs/www-data/pdf/RDA0000/AOA0000C301.pdf"
			(at 0 0 0)
			(layer "F.Fab")
			(hide yes)
			(effects
				(font
					(size 1.27 1.27)
					(thickness 0.15)
				)
			)
		)
		(property "Author" "Antmicro"
			(at 0 0 0)
			(layer "F.Fab")
			(hide yes)
			(effects
				(font
					(size 1 1)
					(thickness 0.15)
				)
			)
		)
		(property "Current" "1A"
			(at 0 0 0)
			(layer "F.Fab")
			(hide yes)
			(effects
				(font
					(size 1 1)
					(thickness 0.15)
				)
			)
		)
		(property "License" "Apache-2.0"
			(at 0 0 0)
			(layer "F.Fab")
			(hide yes)
			(effects
				(font
					(size 1 1)
					(thickness 0.15)
				)
			)
		)
		(property "MPN" "ERJ2GE0R00X"
			(at 0 0 0)
			(layer "F.Fab")
			(hide yes)
			(effects
				(font
					(size 1 1)
					(thickness 0.15)
				)
			)
		)
		(property "Manufacturer" "Panasonic"
			(at 0 0 0)
			(layer "F.Fab")
			(hide yes)
			(effects
				(font
					(size 1 1)
					(thickness 0.15)
				)
			)
		)
		(property "Tolerance" ""
			(at 0 0 0)
			(layer "F.Fab")
			(hide yes)
			(effects
				(font
					(size 1 1)
					(thickness 0.15)
				)
			)
		)
		(property "Val" "0R"
			(at 0 0 0)
			(layer "F.Fab")
			(hide yes)
			(effects
				(font
					(size 1 1)
					(thickness 0.15)
				)
			)
		)
		(sheetname "Peripherals")
		(sheetfile "peripherals.kicad_sch")
		(attr smd exclude_from_pos_files exclude_from_bom dnp)
		(fp_rect
			(start -0.925 -0.47)
			(end 0.925 0.47)
			(stroke
				(width 0.05)
				(type default)
			)
			(fill none)
			(layer "F.CrtYd")
		)
		(fp_rect
			(start -0.5 -0.25)
			(end 0.5 0.25)
			(stroke
				(width 0.15)
				(type solid)
			)
			(fill none)
			(layer "F.Fab")
		)
		(fp_text user "Author: Antmicro"
			(at -0.95 4.169 0)
			(layer "F.Fab")
			(hide yes)
			(effects
				(font
					(size 0.7 0.7)
					(thickness 0.15)
				)
				(justify left bottom)
			)
		)
		(fp_text user "License: Apache-2.0"
			(at -0.95 5.169 0)
			(layer "F.Fab")
			(hide yes)
			(effects
				(font
					(size 0.7 0.7)
					(thickness 0.15)
				)
				(justify left bottom)
			)
		)
		(fp_text user "${REFERENCE}"
			(at -0.95 3.168 0)
			(layer "F.Fab")
			(hide yes)
			(effects
				(font
					(size 0.7 0.7)
					(thickness 0.15)
				)
				(justify left bottom)
			)
		)
		(pad "1" smd roundrect
			(at -0.48 0)
			(size 0.59 0.64)
			(layers "F.Cu" "F.Paste" "F.Mask")
			(roundrect_rratio 0.25)
			(net 597 "Net-(J11-Pad64)")
			(pintype "passive")
		)
		(pad "2" smd roundrect
			(at 0.48 0)
			(size 0.59 0.64)
			(layers "F.Cu" "F.Paste" "F.Mask")
			(roundrect_rratio 0.25)
			(net 130 "I2C2_SDA")
			(pintype "passive")
		)
	)
	(footprint "antmicro-footprints:R_0402_1005Metric"
		(layer "F.Cu")
		(at 129.3 91.25 180)
		(descr "Resistor SMD 0402")
		(tags "resistor SMD 0402")
		(property "Reference" "R20"
			(at 2.925 -0.4 180)
			(layer "F.SilkS")
			(effects
				(font
					(size 0.7 0.7)
					(thickness 0.15)
				)
				(justify left bottom)
			)
		)
		(property "Value" "R_0R_0402"
			(at 0 1.4 180)
			(layer "F.Fab")
			(effects
				(font
					(size 0.7 0.7)
					(thickness 0.15)
				)
				(justify left bottom)
			)
		)
		(property "Footprint" "antmicro-footprints:R_0402_1005Metric"
			(at 0 0 180)
			(layer "F.Fab")
			(hide yes)
			(effects
				(font
					(size 1.27 1.27)
					(thickness 0.15)
				)
			)
		)
		(property "Datasheet" "https://industrial.panasonic.com/cdbs/www-data/pdf/RDA0000/AOA0000C301.pdf"
			(at 0 0 180)
			(layer "F.Fab")
			(hide yes)
			(effects
				(font
					(size 1.27 1.27)
					(thickness 0.15)
				)
			)
		)
		(property "Author" "Antmicro"
			(at 258.6 182.5 0)
			(layer "F.Fab")
			(hide yes)
			(effects
				(font
					(size 1 1)
					(thickness 0.15)
				)
			)
		)
		(property "Current" "1A"
			(at 258.6 182.5 0)
			(layer "F.Fab")
			(hide yes)
			(effects
				(font
					(size 1 1)
					(thickness 0.15)
				)
			)
		)
		(property "License" "Apache-2.0"
			(at 258.6 182.5 0)
			(layer "F.Fab")
			(hide yes)
			(effects
				(font
					(size 1 1)
					(thickness 0.15)
				)
			)
		)
		(property "MPN" "ERJ2GE0R00X"
			(at 258.6 182.5 0)
			(layer "F.Fab")
			(hide yes)
			(effects
				(font
					(size 1 1)
					(thickness 0.15)
				)
			)
		)
		(property "Manufacturer" "Panasonic"
			(at 258.6 182.5 0)
			(layer "F.Fab")
			(hide yes)
			(effects
				(font
					(size 1 1)
					(thickness 0.15)
				)
			)
		)
		(property "Tolerance" ""
			(at 258.6 182.5 0)
			(layer "F.Fab")
			(hide yes)
			(effects
				(font
					(size 1 1)
					(thickness 0.15)
				)
			)
		)
		(property "Val" "0R"
			(at 258.6 182.5 0)
			(layer "F.Fab")
			(hide yes)
			(effects
				(font
					(size 1 1)
					(thickness 0.15)
				)
			)
		)
		(sheetname "M.2")
		(sheetfile "m-2.kicad_sch")
		(attr smd)
		(fp_rect
			(start -0.925 -0.47)
			(end 0.925 0.47)
			(stroke
				(width 0.05)
				(type default)
			)
			(fill none)
			(layer "F.CrtYd")
		)
		(fp_rect
			(start -0.5 -0.25)
			(end 0.5 0.25)
			(stroke
				(width 0.15)
				(type solid)
			)
			(fill none)
			(layer "F.Fab")
		)
		(fp_text user "${REFERENCE}"
			(at -0.95 3.168 180)
			(layer "F.Fab")
			(hide yes)
			(effects
				(font
					(size 0.7 0.7)
					(thickness 0.15)
				)
				(justify left bottom)
			)
		)
		(fp_text user "Author: Antmicro"
			(at -0.95 4.169 180)
			(layer "F.Fab")
			(hide yes)
			(effects
				(font
					(size 0.7 0.7)
					(thickness 0.15)
				)
				(justify left bottom)
			)
		)
		(fp_text user "License: Apache-2.0"
			(at -0.95 5.169 180)
			(layer "F.Fab")
			(hide yes)
			(effects
				(font
					(size 0.7 0.7)
					(thickness 0.15)
				)
				(justify left bottom)
			)
		)
		(pad "1" smd roundrect
			(at -0.48 0 180)
			(size 0.59 0.64)
			(layers "F.Cu" "F.Paste" "F.Mask")
			(roundrect_rratio 0.25)
			(net 436 "USB1_D_P")
			(pintype "passive")
		)
		(pad "2" smd roundrect
			(at 0.48 0 180)
			(size 0.59 0.64)
			(layers "F.Cu" "F.Paste" "F.Mask")
			(roundrect_rratio 0.25)
			(net 616 "/M.2/USB_E_P")
			(pintype "passive")
		)
	)
	(footprint "antmicro-footprints:C_0402_1005Metric"
		(layer "F.Cu")
		(at 134.71 91.31 180)
		(descr "Capacitor SMD 0402")
		(tags "capacitor SMD 0402")
		(property "Reference" "C113"
			(at 3.785 -0.39 180)
			(layer "F.SilkS")
			(effects
				(font
					(size 0.7 0.7)
					(thickness 0.15)
				)
				(justify left bottom)
			)
		)
		(property "Value" "C_100n_0402"
			(at 0 1.4 180)
			(layer "F.Fab")
			(effects
				(font
					(size 0.7 0.7)
					(thickness 0.15)
				)
				(justify left bottom)
			)
		)
		(property "Footprint" "antmicro-footprints:C_0402_1005Metric"
			(at 0 0 180)
			(layer "F.Fab")
			(hide yes)
			(effects
				(font
					(size 1.27 1.27)
					(thickness 0.15)
				)
			)
		)
		(property "Datasheet" "https://www.murata.com/products/productdetail?partno=GRM155R61H104KE14%23"
			(at 0 0 180)
			(layer "F.Fab")
			(hide yes)
			(effects
				(font
					(size 1.27 1.27)
					(thickness 0.15)
				)
			)
		)
		(property "Author" "Antmicro"
			(at 269.42 182.62 0)
			(layer "F.Fab")
			(hide yes)
			(effects
				(font
					(size 1 1)
					(thickness 0.15)
				)
			)
		)
		(property "Dielectric" "X5R"
			(at 269.42 182.62 0)
			(layer "F.Fab")
			(hide yes)
			(effects
				(font
					(size 1 1)
					(thickness 0.15)
				)
			)
		)
		(property "License" "Apache-2.0"
			(at 269.42 182.62 0)
			(layer "F.Fab")
			(hide yes)
			(effects
				(font
					(size 1 1)
					(thickness 0.15)
				)
			)
		)
		(property "MPN" "GRM155R61H104KE14D"
			(at 269.42 182.62 0)
			(layer "F.Fab")
			(hide yes)
			(effects
				(font
					(size 1 1)
					(thickness 0.15)
				)
			)
		)
		(property "Manufacturer" "Murata"
			(at 269.42 182.62 0)
			(layer "F.Fab")
			(hide yes)
			(effects
				(font
					(size 1 1)
					(thickness 0.15)
				)
			)
		)
		(property "Val" "100n"
			(at 269.42 182.62 0)
			(layer "F.Fab")
			(hide yes)
			(effects
				(font
					(size 1 1)
					(thickness 0.15)
				)
			)
		)
		(property "Voltage" "50V"
			(at 269.42 182.62 0)
			(layer "F.Fab")
			(hide yes)
			(effects
				(font
					(size 1 1)
					(thickness 0.15)
				)
			)
		)
		(sheetname "Peripherals")
		(sheetfile "peripherals.kicad_sch")
		(attr smd)
		(fp_rect
			(start -0.925 -0.47)
			(end 0.925 0.47)
			(stroke
				(width 0.05)
				(type default)
			)
			(fill none)
			(layer "F.CrtYd")
		)
		(fp_line
			(start 0.504 0.248)
			(end -0.494 0.248)
			(stroke
				(width 0.15)
				(type solid)
			)
			(layer "F.Fab")
		)
		(fp_line
			(start 0.504 -0.25)
			(end 0.504 0.248)
			(stroke
				(width 0.15)
				(type solid)
			)
			(layer "F.Fab")
		)
		(fp_line
			(start -0.494 0.248)
			(end -0.494 -0.25)
			(stroke
				(width 0.15)
				(type solid)
			)
			(layer "F.Fab")
		)
		(fp_line
			(start -0.494 -0.25)
			(end 0.504 -0.25)
			(stroke
				(width 0.15)
				(type solid)
			)
			(layer "F.Fab")
		)
		(fp_text user "${REFERENCE}"
			(at -0.932 3.168 180)
			(layer "F.Fab")
			(hide yes)
			(effects
				(font
					(size 0.7 0.7)
					(thickness 0.15)
				)
				(justify left bottom)
			)
		)
		(fp_text user "Author: Antmicro"
			(at -0.932 4.17 180)
			(layer "F.Fab")
			(hide yes)
			(effects
				(font
					(size 0.7 0.7)
					(thickness 0.15)
				)
				(justify left bottom)
			)
		)
		(fp_text user "License: Apache-2.0"
			(at -0.932 5.17 180)
			(layer "F.Fab")
			(hide yes)
			(effects
				(font
					(size 0.7 0.7)
					(thickness 0.15)
				)
				(justify left bottom)
			)
		)
		(pad "1" smd roundrect
			(at -0.48 0 180)
			(size 0.59 0.64)
			(layers "F.Cu" "F.Paste" "F.Mask")
			(roundrect_rratio 0.25)
			(net 416 "/Peripherals/USBSS2_TX_CONN_N")
			(pintype "passive")
		)
		(pad "2" smd roundrect
			(at 0.48 0 180)
			(size 0.59 0.64)
			(layers "F.Cu" "F.Paste" "F.Mask")
			(roundrect_rratio 0.25)
			(net 132 "USBSS1_TX_N")
			(pintype "passive")
		)
	)
	(footprint "antmicro-footprints:R_0402_1005Metric"
		(layer "F.Cu")
		(at 114.4 98)
		(descr "Resistor SMD 0402")
		(tags "resistor SMD 0402")
		(property "Reference" "R27"
			(at -3.95 -1.125 0)
			(layer "F.SilkS")
			(effects
				(font
					(size 0.7 0.7)
					(thickness 0.15)
				)
				(justify left bottom)
			)
		)
		(property "Value" "R_47k_0402"
			(at 0 1.4 0)
			(layer "F.Fab")
			(effects
				(font
					(size 0.7 0.7)
					(thickness 0.15)
				)
				(justify left bottom)
			)
		)
		(property "Footprint" "antmicro-footprints:R_0402_1005Metric"
			(at 0 0 0)
			(layer "F.Fab")
			(hide yes)
			(effects
				(font
					(size 1.27 1.27)
					(thickness 0.15)
				)
			)
		)
		(property "Datasheet" "https://www.bourns.com/docs/product-datasheets/cr.pdf"
			(at 0 0 0)
			(layer "F.Fab")
			(hide yes)
			(effects
				(font
					(size 1.27 1.27)
					(thickness 0.15)
				)
			)
		)
		(property "Author" "Antmicro"
			(at 0 0 0)
			(layer "F.Fab")
			(hide yes)
			(effects
				(font
					(size 1 1)
					(thickness 0.15)
				)
			)
		)
		(property "License" "Apache-2.0"
			(at 0 0 0)
			(layer "F.Fab")
			(hide yes)
			(effects
				(font
					(size 1 1)
					(thickness 0.15)
				)
			)
		)
		(property "MPN" "CR0402-FX-4702GLF"
			(at 0 0 0)
			(layer "F.Fab")
			(hide yes)
			(effects
				(font
					(size 1 1)
					(thickness 0.15)
				)
			)
		)
		(property "Manufacturer" "Bourns"
			(at 0 0 0)
			(layer "F.Fab")
			(hide yes)
			(effects
				(font
					(size 1 1)
					(thickness 0.15)
				)
			)
		)
		(property "Tolerance" "1%"
			(at 0 0 0)
			(layer "F.Fab")
			(hide yes)
			(effects
				(font
					(size 1 1)
					(thickness 0.15)
				)
			)
		)
		(property "Val" "47k"
			(at 0 0 0)
			(layer "F.Fab")
			(hide yes)
			(effects
				(font
					(size 1 1)
					(thickness 0.15)
				)
			)
		)
		(sheetname "M.2")
		(sheetfile "m-2.kicad_sch")
		(attr smd exclude_from_pos_files exclude_from_bom dnp)
		(fp_rect
			(start -0.925 -0.47)
			(end 0.925 0.47)
			(stroke
				(width 0.05)
				(type default)
			)
			(fill none)
			(layer "F.CrtYd")
		)
		(fp_rect
			(start -0.5 -0.25)
			(end 0.5 0.25)
			(stroke
				(width 0.15)
				(type solid)
			)
			(fill none)
			(layer "F.Fab")
		)
		(fp_text user "Author: Antmicro"
			(at -0.95 4.169 0)
			(layer "F.Fab")
			(hide yes)
			(effects
				(font
					(size 0.7 0.7)
					(thickness 0.15)
				)
				(justify left bottom)
			)
		)
		(fp_text user "License: Apache-2.0"
			(at -0.95 5.169 0)
			(layer "F.Fab")
			(hide yes)
			(effects
				(font
					(size 0.7 0.7)
					(thickness 0.15)
				)
				(justify left bottom)
			)
		)
		(fp_text user "${REFERENCE}"
			(at -0.95 3.168 0)
			(layer "F.Fab")
			(hide yes)
			(effects
				(font
					(size 0.7 0.7)
					(thickness 0.15)
				)
				(justify left bottom)
			)
		)
		(pad "1" smd roundrect
			(at -0.48 0)
			(size 0.59 0.64)
			(layers "F.Cu" "F.Paste" "F.Mask")
			(roundrect_rratio 0.25)
			(net 87 "+3V3")
			(pintype "passive")
		)
		(pad "2" smd roundrect
			(at 0.48 0)
			(size 0.59 0.64)
			(layers "F.Cu" "F.Paste" "F.Mask")
			(roundrect_rratio 0.25)
			(net 65 "PCIE1_RST*")
			(pintype "passive")
		)
	)
	(footprint "antmicro-footprints:R_0402_1005Metric"
		(layer "F.Cu")
		(at 139.1 108.6)
		(descr "Resistor SMD 0402")
		(tags "resistor SMD 0402")
		(property "Reference" "R62"
			(at -3.075 0 0)
			(layer "F.SilkS")
			(effects
				(font
					(size 0.7 0.7)
					(thickness 0.15)
				)
				(justify left bottom)
			)
		)
		(property "Value" "R_0R_0402"
			(at 0 1.4 0)
			(layer "F.Fab")
			(effects
				(font
					(size 0.7 0.7)
					(thickness 0.15)
				)
				(justify left bottom)
			)
		)
		(property "Footprint" "antmicro-footprints:R_0402_1005Metric"
			(at 0 0 0)
			(layer "F.Fab")
			(hide yes)
			(effects
				(font
					(size 1.27 1.27)
					(thickness 0.15)
				)
			)
		)
		(property "Datasheet" "https://industrial.panasonic.com/cdbs/www-data/pdf/RDA0000/AOA0000C301.pdf"
			(at 0 0 0)
			(layer "F.Fab")
			(hide yes)
			(effects
				(font
					(size 1.27 1.27)
					(thickness 0.15)
				)
			)
		)
		(property "Author" "Antmicro"
			(at 0 0 0)
			(layer "F.Fab")
			(hide yes)
			(effects
				(font
					(size 1 1)
					(thickness 0.15)
				)
			)
		)
		(property "Current" "1A"
			(at 0 0 0)
			(layer "F.Fab")
			(hide yes)
			(effects
				(font
					(size 1 1)
					(thickness 0.15)
				)
			)
		)
		(property "License" "Apache-2.0"
			(at 0 0 0)
			(layer "F.Fab")
			(hide yes)
			(effects
				(font
					(size 1 1)
					(thickness 0.15)
				)
			)
		)
		(property "MPN" "ERJ2GE0R00X"
			(at 0 0 0)
			(layer "F.Fab")
			(hide yes)
			(effects
				(font
					(size 1 1)
					(thickness 0.15)
				)
			)
		)
		(property "Manufacturer" "Panasonic"
			(at 0 0 0)
			(layer "F.Fab")
			(hide yes)
			(effects
				(font
					(size 1 1)
					(thickness 0.15)
				)
			)
		)
		(property "Tolerance" ""
			(at 0 0 0)
			(layer "F.Fab")
			(hide yes)
			(effects
				(font
					(size 1 1)
					(thickness 0.15)
				)
			)
		)
		(property "Val" "0R"
			(at 0 0 0)
			(layer "F.Fab")
			(hide yes)
			(effects
				(font
					(size 1 1)
					(thickness 0.15)
				)
			)
		)
		(sheetname "Peripherals")
		(sheetfile "peripherals.kicad_sch")
		(attr smd)
		(fp_rect
			(start -0.925 -0.47)
			(end 0.925 0.47)
			(stroke
				(width 0.05)
				(type default)
			)
			(fill none)
			(layer "F.CrtYd")
		)
		(fp_rect
			(start -0.5 -0.25)
			(end 0.5 0.25)
			(stroke
				(width 0.15)
				(type solid)
			)
			(fill none)
			(layer "F.Fab")
		)
		(fp_text user "Author: Antmicro"
			(at -0.95 4.169 0)
			(layer "F.Fab")
			(hide yes)
			(effects
				(font
					(size 0.7 0.7)
					(thickness 0.15)
				)
				(justify left bottom)
			)
		)
		(fp_text user "License: Apache-2.0"
			(at -0.95 5.169 0)
			(layer "F.Fab")
			(hide yes)
			(effects
				(font
					(size 0.7 0.7)
					(thickness 0.15)
				)
				(justify left bottom)
			)
		)
		(fp_text user "${REFERENCE}"
			(at -0.95 3.168 0)
			(layer "F.Fab")
			(hide yes)
			(effects
				(font
					(size 0.7 0.7)
					(thickness 0.15)
				)
				(justify left bottom)
			)
		)
		(pad "1" smd roundrect
			(at -0.48 0)
			(size 0.59 0.64)
			(layers "F.Cu" "F.Paste" "F.Mask")
			(roundrect_rratio 0.25)
			(net 252 "SYS_SCL")
			(pintype "passive")
		)
		(pad "2" smd roundrect
			(at 0.48 0)
			(size 0.59 0.64)
			(layers "F.Cu" "F.Paste" "F.Mask")
			(roundrect_rratio 0.25)
			(net 598 "Net-(J11-Pad65)")
			(pintype "passive")
		)
	)
	(footprint "antmicro-footprints:C_0402_1005Metric"
		(layer "F.Cu")
		(at 81.9 105.6 180)
		(descr "Capacitor SMD 0402")
		(tags "capacitor SMD 0402")
		(property "Reference" "C141"
			(at -0.8 -0.45 180)
			(layer "F.SilkS")
			(effects
				(font
					(size 0.7 0.7)
					(thickness 0.15)
				)
				(justify left bottom)
			)
		)
		(property "Value" "C_100n_0402"
			(at 0 1.4 180)
			(layer "F.Fab")
			(effects
				(font
					(size 0.7 0.7)
					(thickness 0.15)
				)
				(justify left bottom)
			)
		)
		(property "Footprint" "antmicro-footprints:C_0402_1005Metric"
			(at 0 0 180)
			(layer "F.Fab")
			(hide yes)
			(effects
				(font
					(size 1.27 1.27)
					(thickness 0.15)
				)
			)
		)
		(property "Datasheet" "https://www.murata.com/products/productdetail?partno=GRM155R61H104KE14%23"
			(at 0 0 180)
			(layer "F.Fab")
			(hide yes)
			(effects
				(font
					(size 1.27 1.27)
					(thickness 0.15)
				)
			)
		)
		(property "Author" "Antmicro"
			(at 163.8 211.2 0)
			(layer "F.Fab")
			(hide yes)
			(effects
				(font
					(size 1 1)
					(thickness 0.15)
				)
			)
		)
		(property "Dielectric" "X5R"
			(at 163.8 211.2 0)
			(layer "F.Fab")
			(hide yes)
			(effects
				(font
					(size 1 1)
					(thickness 0.15)
				)
			)
		)
		(property "License" "Apache-2.0"
			(at 163.8 211.2 0)
			(layer "F.Fab")
			(hide yes)
			(effects
				(font
					(size 1 1)
					(thickness 0.15)
				)
			)
		)
		(property "MPN" "GRM155R61H104KE14D"
			(at 163.8 211.2 0)
			(layer "F.Fab")
			(hide yes)
			(effects
				(font
					(size 1 1)
					(thickness 0.15)
				)
			)
		)
		(property "Manufacturer" "Murata"
			(at 163.8 211.2 0)
			(layer "F.Fab")
			(hide yes)
			(effects
				(font
					(size 1 1)
					(thickness 0.15)
				)
			)
		)
		(property "Val" "100n"
			(at 163.8 211.2 0)
			(layer "F.Fab")
			(hide yes)
			(effects
				(font
					(size 1 1)
					(thickness 0.15)
				)
			)
		)
		(property "Voltage" "50V"
			(at 163.8 211.2 0)
			(layer "F.Fab")
			(hide yes)
			(effects
				(font
					(size 1 1)
					(thickness 0.15)
				)
			)
		)
		(sheetname "USB Debug, DP")
		(sheetfile "usb.kicad_sch")
		(attr smd)
		(fp_rect
			(start -0.925 -0.47)
			(end 0.925 0.47)
			(stroke
				(width 0.05)
				(type default)
			)
			(fill none)
			(layer "F.CrtYd")
		)
		(fp_line
			(start 0.504 0.248)
			(end -0.494 0.248)
			(stroke
				(width 0.15)
				(type solid)
			)
			(layer "F.Fab")
		)
		(fp_line
			(start 0.504 -0.25)
			(end 0.504 0.248)
			(stroke
				(width 0.15)
				(type solid)
			)
			(layer "F.Fab")
		)
		(fp_line
			(start -0.494 0.248)
			(end -0.494 -0.25)
			(stroke
				(width 0.15)
				(type solid)
			)
			(layer "F.Fab")
		)
		(fp_line
			(start -0.494 -0.25)
			(end 0.504 -0.25)
			(stroke
				(width 0.15)
				(type solid)
			)
			(layer "F.Fab")
		)
		(fp_text user "Author: Antmicro"
			(at -0.932 4.17 180)
			(layer "F.Fab")
			(hide yes)
			(effects
				(font
					(size 0.7 0.7)
					(thickness 0.15)
				)
				(justify left bottom)
			)
		)
		(fp_text user "${REFERENCE}"
			(at -0.932 3.168 180)
			(layer "F.Fab")
			(hide yes)
			(effects
				(font
					(size 0.7 0.7)
					(thickness 0.15)
				)
				(justify left bottom)
			)
		)
		(fp_text user "License: Apache-2.0"
			(at -0.932 5.17 180)
			(layer "F.Fab")
			(hide yes)
			(effects
				(font
					(size 0.7 0.7)
					(thickness 0.15)
				)
				(justify left bottom)
			)
		)
		(pad "1" smd roundrect
			(at -0.48 0 180)
			(size 0.59 0.64)
			(layers "F.Cu" "F.Paste" "F.Mask")
			(roundrect_rratio 0.25)
			(net 449 "USBSS0_TX_P")
			(pintype "passive")
		)
		(pad "2" smd roundrect
			(at 0.48 0 180)
			(size 0.59 0.64)
			(layers "F.Cu" "F.Paste" "F.Mask")
			(roundrect_rratio 0.25)
			(net 187 "/USB Debug, DP/USBSS0_TX_C_N")
			(pintype "passive")
		)
	)
	(footprint "antmicro-footprints:XDFN-2_1x0.60mm"
		(layer "F.Cu")
		(at 137.8 87.45 -90)
		(property "Reference" "D42"
			(at 0.298 -0.402 180)
			(layer "F.SilkS")
			(effects
				(font
					(size 0.7 0.7)
					(thickness 0.15)
				)
				(justify left bottom)
			)
		)
		(property "Value" "TPD1E0B04_XDFN-2"
			(at 0 1.5 -90)
			(layer "F.Fab")
			(effects
				(font
					(size 0.7 0.7)
					(thickness 0.15)
				)
				(justify left bottom)
			)
		)
		(property "Footprint" "antmicro-footprints:XDFN-2_1x0.60mm"
			(at 0 0 -90)
			(layer "F.Fab")
			(hide yes)
			(effects
				(font
					(size 1.27 1.27)
					(thickness 0.15)
				)
			)
		)
		(property "Datasheet" "https://www.ti.com/general/docs/suppproductinfo.tsp?distId=26&gotoUrl=https://www.ti.com/lit/gpn/tpd1e0b04"
			(at 0 0 -90)
			(layer "F.Fab")
			(hide yes)
			(effects
				(font
					(size 1.27 1.27)
					(thickness 0.15)
				)
			)
		)
		(property "MPN" "TPD1E0B04DPYR"
			(at 50.35 225.25 0)
			(layer "F.Fab")
			(hide yes)
			(effects
				(font
					(size 1 1)
					(thickness 0.15)
				)
			)
		)
		(property "Manufacturer" "Texas Instruments"
			(at 50.35 225.25 0)
			(layer "F.Fab")
			(hide yes)
			(effects
				(font
					(size 1 1)
					(thickness 0.15)
				)
			)
		)
		(property "Author" "Antmicro"
			(at 50.35 225.25 0)
			(layer "F.Fab")
			(hide yes)
			(effects
				(font
					(size 1 1)
					(thickness 0.15)
				)
			)
		)
		(property "License" "Apache-2.0"
			(at 50.35 225.25 0)
			(layer "F.Fab")
			(hide yes)
			(effects
				(font
					(size 1 1)
					(thickness 0.15)
				)
			)
		)
		(sheetname "Peripherals")
		(sheetfile "peripherals.kicad_sch")
		(attr smd)
		(fp_rect
			(start -0.725 -0.475)
			(end 0.725 0.475)
			(stroke
				(width 0.05)
				(type solid)
			)
			(fill none)
			(layer "F.CrtYd")
		)
		(fp_rect
			(start -0.55 -0.35)
			(end 0.55 0.35)
			(stroke
				(width 0.15)
				(type solid)
			)
			(fill none)
			(layer "F.Fab")
		)
		(fp_text user "Author: Antmicro"
			(at -0.8 4.4 -90)
			(layer "F.Fab")
			(hide yes)
			(effects
				(font
					(size 0.7 0.7)
					(thickness 0.15)
				)
				(justify left bottom)
			)
		)
		(fp_text user "License: Apache-2.0"
			(at -0.8 5.6 -90)
			(layer "F.Fab")
			(hide yes)
			(effects
				(font
					(size 0.7 0.7)
					(thickness 0.15)
				)
				(justify left bottom)
			)
		)
		(fp_text user "${REFERENCE}"
			(at -0.8 3.2 -90)
			(layer "F.Fab")
			(hide yes)
			(effects
				(font
					(size 0.7 0.7)
					(thickness 0.15)
				)
				(justify left bottom)
			)
		)
		(pad "1" smd roundrect
			(at -0.351 0 270)
			(size 0.3 0.5)
			(layers "F.Cu" "F.Paste" "F.Mask")
			(roundrect_rratio 0.25)
			(net 412 "/Peripherals/PCIE2_TX0_CONN_P")
			(pinfunction "C")
			(pintype "passive")
		)
		(pad "2" smd roundrect
			(at 0.349 0 270)
			(size 0.3 0.5)
			(layers "F.Cu" "F.Paste" "F.Mask")
			(roundrect_rratio 0.25)
			(net 1 "GND")
			(pinfunction "A")
			(pintype "passive")
		)
	)
	(footprint "antmicro-footprints:R_0402_1005Metric"
		(layer "F.Cu")
		(at 114.4 100.8 180)
		(descr "Resistor SMD 0402")
		(tags "resistor SMD 0402")
		(property "Reference" "R31"
			(at 3.05 -0.475 180)
			(layer "F.SilkS")
			(effects
				(font
					(size 0.7 0.7)
					(thickness 0.15)
				)
				(justify left bottom)
			)
		)
		(property "Value" "R_0R_0402"
			(at 0 1.4 180)
			(layer "F.Fab")
			(effects
				(font
					(size 0.7 0.7)
					(thickness 0.15)
				)
				(justify left bottom)
			)
		)
		(property "Footprint" "antmicro-footprints:R_0402_1005Metric"
			(at 0 0 180)
			(layer "F.Fab")
			(hide yes)
			(effects
				(font
					(size 1.27 1.27)
					(thickness 0.15)
				)
			)
		)
		(property "Datasheet" "https://industrial.panasonic.com/cdbs/www-data/pdf/RDA0000/AOA0000C301.pdf"
			(at 0 0 180)
			(layer "F.Fab")
			(hide yes)
			(effects
				(font
					(size 1.27 1.27)
					(thickness 0.15)
				)
			)
		)
		(property "Author" "Antmicro"
			(at 228.8 201.6 0)
			(layer "F.Fab")
			(hide yes)
			(effects
				(font
					(size 1 1)
					(thickness 0.15)
				)
			)
		)
		(property "Current" "1A"
			(at 228.8 201.6 0)
			(layer "F.Fab")
			(hide yes)
			(effects
				(font
					(size 1 1)
					(thickness 0.15)
				)
			)
		)
		(property "License" "Apache-2.0"
			(at 228.8 201.6 0)
			(layer "F.Fab")
			(hide yes)
			(effects
				(font
					(size 1 1)
					(thickness 0.15)
				)
			)
		)
		(property "MPN" "ERJ2GE0R00X"
			(at 228.8 201.6 0)
			(layer "F.Fab")
			(hide yes)
			(effects
				(font
					(size 1 1)
					(thickness 0.15)
				)
			)
		)
		(property "Manufacturer" "Panasonic"
			(at 228.8 201.6 0)
			(layer "F.Fab")
			(hide yes)
			(effects
				(font
					(size 1 1)
					(thickness 0.15)
				)
			)
		)
		(property "Tolerance" ""
			(at 228.8 201.6 0)
			(layer "F.Fab")
			(hide yes)
			(effects
				(font
					(size 1 1)
					(thickness 0.15)
				)
			)
		)
		(property "Val" "0R"
			(at 228.8 201.6 0)
			(layer "F.Fab")
			(hide yes)
			(effects
				(font
					(size 1 1)
					(thickness 0.15)
				)
			)
		)
		(sheetname "M.2")
		(sheetfile "m-2.kicad_sch")
		(attr smd exclude_from_pos_files exclude_from_bom dnp)
		(fp_rect
			(start -0.925 -0.47)
			(end 0.925 0.47)
			(stroke
				(width 0.05)
				(type default)
			)
			(fill none)
			(layer "F.CrtYd")
		)
		(fp_rect
			(start -0.5 -0.25)
			(end 0.5 0.25)
			(stroke
				(width 0.15)
				(type solid)
			)
			(fill none)
			(layer "F.Fab")
		)
		(fp_text user "License: Apache-2.0"
			(at -0.95 5.169 180)
			(layer "F.Fab")
			(hide yes)
			(effects
				(font
					(size 0.7 0.7)
					(thickness 0.15)
				)
				(justify left bottom)
			)
		)
		(fp_text user "${REFERENCE}"
			(at -0.95 3.168 180)
			(layer "F.Fab")
			(hide yes)
			(effects
				(font
					(size 0.7 0.7)
					(thickness 0.15)
				)
				(justify left bottom)
			)
		)
		(fp_text user "Author: Antmicro"
			(at -0.95 4.169 180)
			(layer "F.Fab")
			(hide yes)
			(effects
				(font
					(size 0.7 0.7)
					(thickness 0.15)
				)
				(justify left bottom)
			)
		)
		(pad "1" smd roundrect
			(at -0.48 0 180)
			(size 0.59 0.64)
			(layers "F.Cu" "F.Paste" "F.Mask")
			(roundrect_rratio 0.25)
			(net 223 "/M.2/M2_E_I2C_CLK")
			(pintype "passive")
		)
		(pad "2" smd roundrect
			(at 0.48 0 180)
			(size 0.59 0.64)
			(layers "F.Cu" "F.Paste" "F.Mask")
			(roundrect_rratio 0.25)
			(net 252 "SYS_SCL")
			(pintype "passive")
		)
	)
	(footprint "antmicro-footprints:USON-10_2.5x1mm_P0.5mm"
		(layer "F.Cu")
		(at 131.7 108.65)
		(descr "USON-10 2.5x1mm_ Pitch 0.5mm")
		(tags "USON-10 2.5x1mm Pitch 0.5mm")
		(property "Reference" "U30"
			(at 1.82 0.98 90)
			(layer "F.SilkS")
			(effects
				(font
					(size 0.7 0.7)
					(thickness 0.15)
				)
				(justify left bottom)
			)
		)
		(property "Value" "TPD4E05U06QDQARQ1"
			(at 0.018 2.499 0)
			(layer "F.Fab")
			(effects
				(font
					(size 0.7 0.7)
					(thickness 0.15)
				)
				(justify left bottom)
			)
		)
		(property "Footprint" "antmicro-footprints:USON-10_2.5x1mm_P0.5mm"
			(at 0 0 0)
			(layer "F.Fab")
			(hide yes)
			(effects
				(font
					(size 1.27 1.27)
					(thickness 0.15)
				)
			)
		)
		(property "Datasheet" "https://www.ti.com/lit/ds/symlink/tpd4e05u06-q1.pdf?HQS=dis-mous-null-mousermode-dsf-pf-null-wwe&ts=1663591265741&ref_url=https%253A%252F%252Fwww.mouser.com%252F"
			(at 0 0 0)
			(layer "F.Fab")
			(hide yes)
			(effects
				(font
					(size 1.27 1.27)
					(thickness 0.15)
				)
			)
		)
		(property "Author" "Antmicro"
			(at 0 0 0)
			(layer "F.Fab")
			(hide yes)
			(effects
				(font
					(size 1 1)
					(thickness 0.15)
				)
			)
		)
		(property "License" "Apache-2.0"
			(at 0 0 0)
			(layer "F.Fab")
			(hide yes)
			(effects
				(font
					(size 1 1)
					(thickness 0.15)
				)
			)
		)
		(property "MPN" "TPD4E05U06QDQARQ1"
			(at 0 0 0)
			(layer "F.Fab")
			(hide yes)
			(effects
				(font
					(size 1 1)
					(thickness 0.15)
				)
			)
		)
		(property "Manufacturer" "Texas Instruments"
			(at 0 0 0)
			(layer "F.Fab")
			(hide yes)
			(effects
				(font
					(size 1 1)
					(thickness 0.15)
				)
			)
		)
		(sheetname "Peripherals")
		(sheetfile "peripherals.kicad_sch")
		(attr smd)
		(fp_line
			(start 0.498 -1.401)
			(end -0.5 -1.401)
			(stroke
				(width 0.15)
				(type solid)
			)
			(layer "F.SilkS")
		)
		(fp_line
			(start 0.498 1.398)
			(end -0.5 1.398)
			(stroke
				(width 0.15)
				(type solid)
			)
			(layer "F.SilkS")
		)
		(fp_circle
			(center -0.68 -1.27)
			(end -0.63 -1.27)
			(stroke
				(width 0.15)
				(type solid)
			)
			(fill solid)
			(layer "F.SilkS")
		)
		(fp_rect
			(start -0.8 -1.5)
			(end 0.8 1.499)
			(stroke
				(width 0.05)
				(type solid)
			)
			(fill none)
			(layer "F.CrtYd")
		)
		(fp_line
			(start -0.5 -1)
			(end -0.5 1.249)
			(stroke
				(width 0.15)
				(type solid)
			)
			(layer "F.Fab")
		)
		(fp_line
			(start -0.5 1.249)
			(end 0.498 1.249)
			(stroke
				(width 0.15)
				(type solid)
			)
			(layer "F.Fab")
		)
		(fp_line
			(start -0.25 -1.25)
			(end -0.5 -1)
			(stroke
				(width 0.15)
				(type solid)
			)
			(layer "F.Fab")
		)
		(fp_line
			(start 0.498 -1.25)
			(end -0.25 -1.25)
			(stroke
				(width 0.15)
				(type solid)
			)
			(layer "F.Fab")
		)
		(fp_line
			(start 0.498 -1.25)
			(end 0.498 1.249)
			(stroke
				(width 0.15)
				(type solid)
			)
			(layer "F.Fab")
		)
		(fp_text user "Author: Antmicro"
			(at -0.802 5.7 0)
			(layer "F.Fab")
			(hide yes)
			(effects
				(font
					(size 0.7 0.7)
					(thickness 0.15)
				)
				(justify left bottom)
			)
		)
		(fp_text user "License: Apache-2.0"
			(at -0.802 6.9 0)
			(layer "F.Fab")
			(hide yes)
			(effects
				(font
					(size 0.7 0.7)
					(thickness 0.15)
				)
				(justify left bottom)
			)
		)
		(fp_text user "${REFERENCE}"
			(at -0.802 4.498 0)
			(layer "F.Fab")
			(hide yes)
			(effects
				(font
					(size 0.7 0.7)
					(thickness 0.15)
				)
				(justify left bottom)
			)
		)
		(pad "1" smd roundrect
			(at -0.387 -1 270)
			(size 0.25 0.55)
			(layers "F.Cu" "F.Paste" "F.Mask")
			(roundrect_rratio 0.25)
			(net 251 "SYS_SDA")
			(pintype "passive")
		)
		(pad "2" smd roundrect
			(at -0.387 -0.5 270)
			(size 0.25 0.55)
			(layers "F.Cu" "F.Paste" "F.Mask")
			(roundrect_rratio 0.25)
			(net 252 "SYS_SCL")
			(pintype "passive")
		)
		(pad "3" smd roundrect
			(at -0.387 0 270)
			(size 0.4 0.55)
			(layers "F.Cu" "F.Paste" "F.Mask")
			(roundrect_rratio 0.25)
			(net 1 "GND")
			(pintype "power_in")
		)
		(pad "4" smd roundrect
			(at -0.387 0.498 270)
			(size 0.25 0.55)
			(layers "F.Cu" "F.Paste" "F.Mask")
			(roundrect_rratio 0.25)
			(net 130 "I2C2_SDA")
			(pintype "passive")
		)
		(pad "5" smd roundrect
			(at -0.387 0.998 270)
			(size 0.25 0.55)
			(layers "F.Cu" "F.Paste" "F.Mask")
			(roundrect_rratio 0.25)
			(net 129 "I2C2_SCL")
			(pintype "passive")
		)
		(pad "6" smd roundrect
			(at 0.385 0.998 270)
			(size 0.25 0.55)
			(layers "F.Cu" "F.Paste" "F.Mask")
			(roundrect_rratio 0.25)
			(net 129 "I2C2_SCL")
			(pintype "passive")
		)
		(pad "7" smd roundrect
			(at 0.385 0.498 270)
			(size 0.25 0.55)
			(layers "F.Cu" "F.Paste" "F.Mask")
			(roundrect_rratio 0.25)
			(net 130 "I2C2_SDA")
			(pintype "passive")
		)
		(pad "8" smd roundrect
			(at 0.385 0 270)
			(size 0.4 0.55)
			(layers "F.Cu" "F.Paste" "F.Mask")
			(roundrect_rratio 0.25)
			(net 1 "GND")
			(pintype "passive")
		)
		(pad "9" smd roundrect
			(at 0.385 -0.5 270)
			(size 0.25 0.55)
			(layers "F.Cu" "F.Paste" "F.Mask")
			(roundrect_rratio 0.25)
			(net 252 "SYS_SCL")
			(pintype "passive")
		)
		(pad "10" smd roundrect
			(at 0.385 -1 270)
			(size 0.25 0.55)
			(layers "F.Cu" "F.Paste" "F.Mask")
			(roundrect_rratio 0.25)
			(net 251 "SYS_SDA")
			(pintype "passive")
		)
	)
	(footprint "antmicro-footprints:SOT-363"
		(layer "F.Cu")
		(at 58.1 109.2)
		(property "Reference" "Q13"
			(at -3.45 -1.025 0)
			(layer "F.SilkS")
			(effects
				(font
					(size 0.7 0.7)
					(thickness 0.15)
				)
				(justify left bottom)
			)
		)
		(property "Value" "BCM857BS-7-F"
			(at 0 2.2 0)
			(layer "F.Fab")
			(effects
				(font
					(size 0.7 0.7)
					(thickness 0.15)
				)
				(justify left bottom)
			)
		)
		(property "Footprint" "antmicro-footprints:SOT-363"
			(at 0 0 0)
			(layer "F.Fab")
			(hide yes)
			(effects
				(font
					(size 1.27 1.27)
					(thickness 0.15)
				)
			)
		)
		(property "Datasheet" "https://www.diodes.com/assets/Datasheets/BCM857BS.pdf"
			(at 0 0 0)
			(layer "F.Fab")
			(hide yes)
			(effects
				(font
					(size 1.27 1.27)
					(thickness 0.15)
				)
			)
		)
		(property "Author" "Antmicro"
			(at 0 0 0)
			(layer "F.Fab")
			(hide yes)
			(effects
				(font
					(size 1 1)
					(thickness 0.15)
				)
			)
		)
		(property "License" "Apache-2.0"
			(at 0 0 0)
			(layer "F.Fab")
			(hide yes)
			(effects
				(font
					(size 1 1)
					(thickness 0.15)
				)
			)
		)
		(property "MPN" "BCM857BS-7-F"
			(at 0 0 0)
			(layer "F.Fab")
			(hide yes)
			(effects
				(font
					(size 1 1)
					(thickness 0.15)
				)
			)
		)
		(property "Manufacturer" "Diodes Incorporated"
			(at 0 0 0)
			(layer "F.Fab")
			(hide yes)
			(effects
				(font
					(size 1 1)
					(thickness 0.15)
				)
			)
		)
		(sheetname "Supply")
		(sheetfile "supply.kicad_sch")
		(attr smd)
		(fp_line
			(start -0.8 1.146)
			(end -0.8 1.223)
			(stroke
				(width 0.15)
				(type solid)
			)
			(layer "F.SilkS")
		)
		(fp_line
			(start -0.8 1.223)
			(end 0.803 1.223)
			(stroke
				(width 0.15)
				(type solid)
			)
			(layer "F.SilkS")
		)
		(fp_line
			(start -0.72 -1.153)
			(end -0.72 -1.228)
			(stroke
				(width 0.15)
				(type solid)
			)
			(layer "F.SilkS")
		)
		(fp_line
			(start 0.803 -1.228)
			(end -0.72 -1.228)
			(stroke
				(width 0.15)
				(type solid)
			)
			(layer "F.SilkS")
		)
		(fp_line
			(start 0.803 -1.153)
			(end 0.803 -1.228)
			(stroke
				(width 0.15)
				(type solid)
			)
			(layer "F.SilkS")
		)
		(fp_line
			(start 0.803 1.146)
			(end 0.803 1.223)
			(stroke
				(width 0.15)
				(type solid)
			)
			(layer "F.SilkS")
		)
		(fp_circle
			(center -0.978102 -1.2)
			(end -0.928102 -1.2)
			(stroke
				(width 0.15)
				(type solid)
			)
			(fill solid)
			(layer "F.SilkS")
		)
		(fp_rect
			(start 1.3 -1.3)
			(end -1.3 1.3)
			(stroke
				(width 0.05)
				(type solid)
			)
			(fill none)
			(layer "F.CrtYd")
		)
		(fp_line
			(start -0.1 -1.1)
			(end -0.68 -0.52)
			(stroke
				(width 0.15)
				(type solid)
			)
			(layer "F.Fab")
		)
		(fp_rect
			(start 0.68 1.1)
			(end -0.68 -1.1)
			(stroke
				(width 0.15)
				(type solid)
			)
			(fill none)
			(layer "F.Fab")
		)
		(fp_text user "Author: Antmicro"
			(at -1.3 6.4 0)
			(layer "F.Fab")
			(hide yes)
			(effects
				(font
					(size 0.7 0.7)
					(thickness 0.15)
				)
				(justify left bottom)
			)
		)
		(fp_text user "${REFERENCE}"
			(at -1.3 4 0)
			(layer "F.Fab")
			(hide yes)
			(effects
				(font
					(size 0.7 0.7)
					(thickness 0.15)
				)
				(justify left bottom)
			)
		)
		(fp_text user "License: Apache-2.0"
			(at -1.3 5.2 0)
			(layer "F.Fab")
			(hide yes)
			(effects
				(font
					(size 0.7 0.7)
					(thickness 0.15)
				)
				(justify left bottom)
			)
		)
		(pad "1" smd custom
			(at -0.948 -0.752 270)
			(size 0.6 0.6)
			(layers "F.Cu" "F.Paste" "F.Mask")
			(net 328 "/Supply/VCC_IN")
			(pintype "passive")
			(options
				(clearance outline)
				(anchor rect)
			)
			(primitives)
		)
		(pad "2" smd rect
			(at -0.948 -0.002 270)
			(size 0.4 0.6)
			(layers "F.Cu" "F.Paste" "F.Mask")
			(net 717 "Net-(Q13-Pad2)")
			(pintype "passive")
		)
		(pad "3" smd custom
			(at -0.948 0.745 270)
			(size 0.6 0.6)
			(layers "F.Cu" "F.Paste" "F.Mask")
			(net 717 "Net-(Q13-Pad2)")
			(pintype "passive")
			(options
				(clearance outline)
				(anchor rect)
			)
			(primitives)
		)
		(pad "4" smd custom
			(at 0.951 0.745 270)
			(size 0.6 0.6)
			(layers "F.Cu" "F.Paste" "F.Mask")
			(net 189 "Net-(D28-C)")
			(pintype "passive")
			(options
				(clearance outline)
				(anchor rect)
			)
			(primitives)
		)
		(pad "5" smd rect
			(at 0.951 -0.002 270)
			(size 0.4 0.6)
			(layers "F.Cu" "F.Paste" "F.Mask")
			(net 717 "Net-(Q13-Pad2)")
			(pintype "passive")
		)
		(pad "6" smd custom
			(at 0.951 -0.752 270)
			(size 0.6 0.6)
			(layers "F.Cu" "F.Paste" "F.Mask")
			(net 630 "Net-(Q15-G)")
			(pintype "passive")
			(options
				(clearance outline)
				(anchor rect)
			)
			(primitives)
		)
	)
	(footprint "antmicro-footprints:C_0402_1005Metric"
		(layer "F.Cu")
		(at 80.23 91.04 -90)
		(descr "Capacitor SMD 0402")
		(tags "capacitor SMD 0402")
		(property "Reference" "C155"
			(at -1.11 -1.52 90)
			(layer "F.SilkS")
			(effects
				(font
					(size 0.7 0.7)
					(thickness 0.15)
				)
				(justify right bottom)
			)
		)
		(property "Value" "C_4u7_25V_0402"
			(at -1.022927 2.155213 90)
			(layer "F.Fab")
			(effects
				(font
					(size 0.7 0.7)
					(thickness 0.15)
				)
				(justify right bottom)
			)
		)
		(property "Footprint" "antmicro-footprints:C_0402_1005Metric"
			(at 0 0 -90)
			(layer "F.Fab")
			(hide yes)
			(effects
				(font
					(size 1.27 1.27)
					(thickness 0.15)
				)
			)
		)
		(property "Datasheet" "https://www.murata.com/products/productdetail?partno=GRM155C61E475ME15%23"
			(at 0 0 -90)
			(layer "F.Fab")
			(hide yes)
			(effects
				(font
					(size 1.27 1.27)
					(thickness 0.15)
				)
			)
		)
		(property "Author" "Antmicro"
			(at -10.81 171.27 0)
			(layer "F.Fab")
			(hide yes)
			(effects
				(font
					(size 1 1)
					(thickness 0.15)
				)
			)
		)
		(property "Dielectric" "X5S"
			(at -10.81 171.27 0)
			(layer "F.Fab")
			(hide yes)
			(effects
				(font
					(size 1 1)
					(thickness 0.15)
				)
			)
		)
		(property "License" "Apache-2.0"
			(at -10.81 171.27 0)
			(layer "F.Fab")
			(hide yes)
			(effects
				(font
					(size 1 1)
					(thickness 0.15)
				)
			)
		)
		(property "MPN" "GRM155C61E475ME15J"
			(at -10.81 171.27 0)
			(layer "F.Fab")
			(hide yes)
			(effects
				(font
					(size 1 1)
					(thickness 0.15)
				)
			)
		)
		(property "Manufacturer" "Murata"
			(at -10.81 171.27 0)
			(layer "F.Fab")
			(hide yes)
			(effects
				(font
					(size 1 1)
					(thickness 0.15)
				)
			)
		)
		(property "Val" "4u7"
			(at -10.81 171.27 0)
			(layer "F.Fab")
			(hide yes)
			(effects
				(font
					(size 1 1)
					(thickness 0.15)
				)
			)
		)
		(property "Voltage" "25V"
			(at -10.81 171.27 0)
			(layer "F.Fab")
			(hide yes)
			(effects
				(font
					(size 1 1)
					(thickness 0.15)
				)
			)
		)
		(sheetname "Supply")
		(sheetfile "supply.kicad_sch")
		(attr smd)
		(fp_rect
			(start -0.925 -0.47)
			(end 0.925 0.47)
			(stroke
				(width 0.05)
				(type default)
			)
			(fill none)
			(layer "F.CrtYd")
		)
		(fp_line
			(start -0.494 0.248)
			(end -0.494 -0.25)
			(stroke
				(width 0.15)
				(type solid)
			)
			(layer "F.Fab")
		)
		(fp_line
			(start 0.504 0.248)
			(end -0.494 0.248)
			(stroke
				(width 0.15)
				(type solid)
			)
			(layer "F.Fab")
		)
		(fp_line
			(start -0.494 -0.25)
			(end 0.504 -0.25)
			(stroke
				(width 0.15)
				(type solid)
			)
			(layer "F.Fab")
		)
		(fp_line
			(start 0.504 -0.25)
			(end 0.504 0.248)
			(stroke
				(width 0.15)
				(type solid)
			)
			(layer "F.Fab")
		)
		(fp_text user "License: Apache-2.0"
			(at -0.939 5.799 90)
			(layer "F.Fab")
			(hide yes)
			(effects
				(font
					(size 0.7 0.7)
					(thickness 0.15)
				)
				(justify right bottom)
			)
		)
		(fp_text user "Author: Antmicro"
			(at -0.939 3.399 90)
			(layer "F.Fab")
			(hide yes)
			(effects
				(font
					(size 0.7 0.7)
					(thickness 0.15)
				)
				(justify right bottom)
			)
		)
		(fp_text user "${REFERENCE}"
			(at -0.939 4.599 90)
			(layer "F.Fab")
			(hide yes)
			(effects
				(font
					(size 0.7 0.7)
					(thickness 0.15)
				)
				(justify right bottom)
			)
		)
		(pad "1" smd roundrect
			(at -0.48 0 270)
			(size 0.59 0.64)
			(layers "F.Cu" "F.Paste" "F.Mask")
			(roundrect_rratio 0.25)
			(net 1 "GND")
			(pintype "passive")
		)
		(pad "2" smd roundrect
			(at 0.48 0 270)
			(size 0.59 0.64)
			(layers "F.Cu" "F.Paste" "F.Mask")
			(roundrect_rratio 0.25)
			(net 642 "/Supply/3V3_VDRV")
			(pintype "passive")
		)
	)
	(footprint "antmicro-footprints:C_0402_1005Metric"
		(layer "F.Cu")
		(at 68.67 99.42 -90)
		(descr "Capacitor SMD 0402")
		(tags "capacitor SMD 0402")
		(property "Reference" "C157"
			(at 0.73 -0.48 90)
			(layer "F.SilkS")
			(effects
				(font
					(size 0.7 0.7)
					(thickness 0.15)
				)
				(justify right bottom)
			)
		)
		(property "Value" "C_100n_0402"
			(at -1.022927 2.155213 90)
			(layer "F.Fab")
			(effects
				(font
					(size 0.7 0.7)
					(thickness 0.15)
				)
				(justify right bottom)
			)
		)
		(property "Footprint" "antmicro-footprints:C_0402_1005Metric"
			(at 0 0 -90)
			(layer "F.Fab")
			(hide yes)
			(effects
				(font
					(size 1.27 1.27)
					(thickness 0.15)
				)
			)
		)
		(property "Datasheet" "https://www.murata.com/products/productdetail?partno=GRM155R61H104KE14%23"
			(at 0 0 -90)
			(layer "F.Fab")
			(hide yes)
			(effects
				(font
					(size 1.27 1.27)
					(thickness 0.15)
				)
			)
		)
		(property "Author" "Antmicro"
			(at -30.75 168.09 0)
			(layer "F.Fab")
			(hide yes)
			(effects
				(font
					(size 1 1)
					(thickness 0.15)
				)
			)
		)
		(property "Dielectric" "X5R"
			(at -30.75 168.09 0)
			(layer "F.Fab")
			(hide yes)
			(effects
				(font
					(size 1 1)
					(thickness 0.15)
				)
			)
		)
		(property "License" "Apache-2.0"
			(at -30.75 168.09 0)
			(layer "F.Fab")
			(hide yes)
			(effects
				(font
					(size 1 1)
					(thickness 0.15)
				)
			)
		)
		(property "MPN" "GRM155R61H104KE14D"
			(at -30.75 168.09 0)
			(layer "F.Fab")
			(hide yes)
			(effects
				(font
					(size 1 1)
					(thickness 0.15)
				)
			)
		)
		(property "Manufacturer" "Murata"
			(at -30.75 168.09 0)
			(layer "F.Fab")
			(hide yes)
			(effects
				(font
					(size 1 1)
					(thickness 0.15)
				)
			)
		)
		(property "Val" "100n"
			(at -30.75 168.09 0)
			(layer "F.Fab")
			(hide yes)
			(effects
				(font
					(size 1 1)
					(thickness 0.15)
				)
			)
		)
		(property "Voltage" "50V"
			(at -30.75 168.09 0)
			(layer "F.Fab")
			(hide yes)
			(effects
				(font
					(size 1 1)
					(thickness 0.15)
				)
			)
		)
		(sheetname "Supply")
		(sheetfile "supply.kicad_sch")
		(attr smd)
		(fp_rect
			(start -0.925 -0.47)
			(end 0.925 0.47)
			(stroke
				(width 0.05)
				(type default)
			)
			(fill none)
			(layer "F.CrtYd")
		)
		(fp_line
			(start -0.494 0.248)
			(end -0.494 -0.25)
			(stroke
				(width 0.15)
				(type solid)
			)
			(layer "F.Fab")
		)
		(fp_line
			(start 0.504 0.248)
			(end -0.494 0.248)
			(stroke
				(width 0.15)
				(type solid)
			)
			(layer "F.Fab")
		)
		(fp_line
			(start -0.494 -0.25)
			(end 0.504 -0.25)
			(stroke
				(width 0.15)
				(type solid)
			)
			(layer "F.Fab")
		)
		(fp_line
			(start 0.504 -0.25)
			(end 0.504 0.248)
			(stroke
				(width 0.15)
				(type solid)
			)
			(layer "F.Fab")
		)
		(fp_text user "Author: Antmicro"
			(at -0.939 3.399 90)
			(layer "F.Fab")
			(hide yes)
			(effects
				(font
					(size 0.7 0.7)
					(thickness 0.15)
				)
				(justify right bottom)
			)
		)
		(fp_text user "${REFERENCE}"
			(at -0.939 4.599 90)
			(layer "F.Fab")
			(hide yes)
			(effects
				(font
					(size 0.7 0.7)
					(thickness 0.15)
				)
				(justify right bottom)
			)
		)
		(fp_text user "License: Apache-2.0"
			(at -0.939 5.799 90)
			(layer "F.Fab")
			(hide yes)
			(effects
				(font
					(size 0.7 0.7)
					(thickness 0.15)
				)
				(justify right bottom)
			)
		)
		(pad "1" smd roundrect
			(at -0.48 0 270)
			(size 0.59 0.64)
			(layers "F.Cu" "F.Paste" "F.Mask")
			(roundrect_rratio 0.25)
			(net 712 "/Supply/5V_EN")
			(pintype "passive")
		)
		(pad "2" smd roundrect
			(at 0.48 0 270)
			(size 0.59 0.64)
			(layers "F.Cu" "F.Paste" "F.Mask")
			(roundrect_rratio 0.25)
			(net 1 "GND")
			(pintype "passive")
		)
	)
	(footprint "antmicro-footprints:C_0603_1608Metric"
		(layer "F.Cu")
		(at 113.95 86.65 180)
		(descr "Capacitor SMD 0603")
		(tags "capacitor 0603")
		(property "Reference" "C11"
			(at -1.075 0.6 0)
			(layer "F.SilkS")
			(effects
				(font
					(size 0.7 0.7)
					(thickness 0.15)
				)
				(justify right bottom)
			)
		)
		(property "Value" "C_10u_0603"
			(at 0 1.6 0)
			(layer "F.Fab")
			(effects
				(font
					(size 0.7 0.7)
					(thickness 0.15)
				)
				(justify right bottom)
			)
		)
		(property "Footprint" "antmicro-footprints:C_0603_1608Metric"
			(at 0 0 180)
			(layer "F.Fab")
			(hide yes)
			(effects
				(font
					(size 1.27 1.27)
					(thickness 0.15)
				)
			)
		)
		(property "Datasheet" "https://www.murata.com/products/productdetail?partno=GRM188R61A106KE69%23"
			(at 0 0 180)
			(layer "F.Fab")
			(hide yes)
			(effects
				(font
					(size 1.27 1.27)
					(thickness 0.15)
				)
			)
		)
		(property "Author" "Antmicro"
			(at 227.9 173.3 0)
			(layer "F.Fab")
			(hide yes)
			(effects
				(font
					(size 1 1)
					(thickness 0.15)
				)
			)
		)
		(property "Dielectric" "template_dielectric"
			(at 227.9 173.3 0)
			(layer "F.Fab")
			(hide yes)
			(effects
				(font
					(size 1 1)
					(thickness 0.15)
				)
			)
		)
		(property "License" "Apache-2.0"
			(at 227.9 173.3 0)
			(layer "F.Fab")
			(hide yes)
			(effects
				(font
					(size 1 1)
					(thickness 0.15)
				)
			)
		)
		(property "MPN" "GRM188R61A106KE69D"
			(at 227.9 173.3 0)
			(layer "F.Fab")
			(hide yes)
			(effects
				(font
					(size 1 1)
					(thickness 0.15)
				)
			)
		)
		(property "Manufacturer" "Murata"
			(at 227.9 173.3 0)
			(layer "F.Fab")
			(hide yes)
			(effects
				(font
					(size 1 1)
					(thickness 0.15)
				)
			)
		)
		(property "Val" "10u"
			(at 227.9 173.3 0)
			(layer "F.Fab")
			(hide yes)
			(effects
				(font
					(size 1 1)
					(thickness 0.15)
				)
			)
		)
		(property "Voltage" ""
			(at 227.9 173.3 0)
			(layer "F.Fab")
			(hide yes)
			(effects
				(font
					(size 1 1)
					(thickness 0.15)
				)
			)
		)
		(sheetname "M.2")
		(sheetfile "m-2.kicad_sch")
		(attr smd)
		(fp_line
			(start -0.15 0.4)
			(end 0.15 0.4)
			(stroke
				(width 0.15)
				(type solid)
			)
			(layer "F.SilkS")
		)
		(fp_line
			(start -0.15 -0.4)
			(end 0.15 -0.4)
			(stroke
				(width 0.15)
				(type solid)
			)
			(layer "F.SilkS")
		)
		(fp_rect
			(start -1.25 -0.65)
			(end 1.25 0.65)
			(stroke
				(width 0.05)
				(type solid)
			)
			(fill none)
			(layer "F.CrtYd")
		)
		(fp_rect
			(start -0.8 -0.4)
			(end 0.8 0.4)
			(stroke
				(width 0.15)
				(type solid)
			)
			(fill none)
			(layer "F.Fab")
		)
		(fp_text user "Author: Antmicro"
			(at -1.682 4.894 0)
			(layer "F.Fab")
			(hide yes)
			(effects
				(font
					(size 0.7 0.7)
					(thickness 0.15)
				)
				(justify right bottom)
			)
		)
		(fp_text user "License: Apache-2.0"
			(at -1.682 5.895 0)
			(layer "F.Fab")
			(hide yes)
			(effects
				(font
					(size 0.7 0.7)
					(thickness 0.15)
				)
				(justify right bottom)
			)
		)
		(fp_text user "${REFERENCE}"
			(at -1.682 3.895 0)
			(layer "F.Fab")
			(hide yes)
			(effects
				(font
					(size 0.7 0.7)
					(thickness 0.15)
				)
				(justify right bottom)
			)
		)
		(pad "1" smd roundrect
			(at -0.7 0 180)
			(size 0.8 1)
			(layers "F.Cu" "F.Paste" "F.Mask")
			(roundrect_rratio 0.2)
			(net 87 "+3V3")
			(pintype "passive")
		)
		(pad "2" smd roundrect
			(at 0.7 0 180)
			(size 0.8 1)
			(layers "F.Cu" "F.Paste" "F.Mask")
			(roundrect_rratio 0.2)
			(net 1 "GND")
			(pintype "passive")
		)
	)
	(footprint "antmicro-footprints:C_0402_1005Metric"
		(layer "F.Cu")
		(at 106.3 102.65 90)
		(descr "Capacitor SMD 0402")
		(tags "capacitor SMD 0402")
		(property "Reference" "C67"
			(at 0.75 0.45 90)
			(layer "F.SilkS")
			(effects
				(font
					(size 0.7 0.7)
					(thickness 0.15)
				)
				(justify left bottom)
			)
		)
		(property "Value" "C_100n_0402"
			(at 0 1.4 90)
			(layer "F.Fab")
			(effects
				(font
					(size 0.7 0.7)
					(thickness 0.15)
				)
				(justify left bottom)
			)
		)
		(property "Footprint" "antmicro-footprints:C_0402_1005Metric"
			(at 0 0 90)
			(layer "F.Fab")
			(hide yes)
			(effects
				(font
					(size 1.27 1.27)
					(thickness 0.15)
				)
			)
		)
		(property "Datasheet" "https://www.murata.com/products/productdetail?partno=GRM155R61H104KE14%23"
			(at 0 0 90)
			(layer "F.Fab")
			(hide yes)
			(effects
				(font
					(size 1.27 1.27)
					(thickness 0.15)
				)
			)
		)
		(property "Author" "Antmicro"
			(at 208.95 -3.65 0)
			(layer "F.Fab")
			(hide yes)
			(effects
				(font
					(size 1 1)
					(thickness 0.15)
				)
			)
		)
		(property "Dielectric" "X5R"
			(at 208.95 -3.65 0)
			(layer "F.Fab")
			(hide yes)
			(effects
				(font
					(size 1 1)
					(thickness 0.15)
				)
			)
		)
		(property "License" "Apache-2.0"
			(at 208.95 -3.65 0)
			(layer "F.Fab")
			(hide yes)
			(effects
				(font
					(size 1 1)
					(thickness 0.15)
				)
			)
		)
		(property "MPN" "GRM155R61H104KE14D"
			(at 208.95 -3.65 0)
			(layer "F.Fab")
			(hide yes)
			(effects
				(font
					(size 1 1)
					(thickness 0.15)
				)
			)
		)
		(property "Manufacturer" "Murata"
			(at 208.95 -3.65 0)
			(layer "F.Fab")
			(hide yes)
			(effects
				(font
					(size 1 1)
					(thickness 0.15)
				)
			)
		)
		(property "Val" "100n"
			(at 208.95 -3.65 0)
			(layer "F.Fab")
			(hide yes)
			(effects
				(font
					(size 1 1)
					(thickness 0.15)
				)
			)
		)
		(property "Voltage" "50V"
			(at 208.95 -3.65 0)
			(layer "F.Fab")
			(hide yes)
			(effects
				(font
					(size 1 1)
					(thickness 0.15)
				)
			)
		)
		(sheetname "USB3")
		(sheetfile "usb3.kicad_sch")
		(attr smd)
		(fp_rect
			(start -0.925 -0.47)
			(end 0.925 0.47)
			(stroke
				(width 0.05)
				(type default)
			)
			(fill none)
			(layer "F.CrtYd")
		)
		(fp_line
			(start 0.504 -0.25)
			(end 0.504 0.248)
			(stroke
				(width 0.15)
				(type solid)
			)
			(layer "F.Fab")
		)
		(fp_line
			(start -0.494 -0.25)
			(end 0.504 -0.25)
			(stroke
				(width 0.15)
				(type solid)
			)
			(layer "F.Fab")
		)
		(fp_line
			(start 0.504 0.248)
			(end -0.494 0.248)
			(stroke
				(width 0.15)
				(type solid)
			)
			(layer "F.Fab")
		)
		(fp_line
			(start -0.494 0.248)
			(end -0.494 -0.25)
			(stroke
				(width 0.15)
				(type solid)
			)
			(layer "F.Fab")
		)
		(fp_text user "License: Apache-2.0"
			(at -0.932 5.17 90)
			(layer "F.Fab")
			(hide yes)
			(effects
				(font
					(size 0.7 0.7)
					(thickness 0.15)
				)
				(justify left bottom)
			)
		)
		(fp_text user "${REFERENCE}"
			(at -0.932 3.168 90)
			(layer "F.Fab")
			(hide yes)
			(effects
				(font
					(size 0.7 0.7)
					(thickness 0.15)
				)
				(justify left bottom)
			)
		)
		(fp_text user "Author: Antmicro"
			(at -0.932 4.17 90)
			(layer "F.Fab")
			(hide yes)
			(effects
				(font
					(size 0.7 0.7)
					(thickness 0.15)
				)
				(justify left bottom)
			)
		)
		(pad "1" smd roundrect
			(at -0.48 0 90)
			(size 0.59 0.64)
			(layers "F.Cu" "F.Paste" "F.Mask")
			(roundrect_rratio 0.25)
			(net 99 "+5V")
			(pintype "passive")
		)
		(pad "2" smd roundrect
			(at 0.48 0 90)
			(size 0.59 0.64)
			(layers "F.Cu" "F.Paste" "F.Mask")
			(roundrect_rratio 0.25)
			(net 1 "GND")
			(pintype "passive")
		)
	)
	(footprint "antmicro-footprints:C_0402_1005Metric"
		(layer "F.Cu")
		(at 136.35 83.95 180)
		(descr "Capacitor SMD 0402")
		(tags "capacitor SMD 0402")
		(property "Reference" "C110"
			(at 3.6 -0.4 180)
			(layer "F.SilkS")
			(effects
				(font
					(size 0.7 0.7)
					(thickness 0.15)
				)
				(justify left bottom)
			)
		)
		(property "Value" "C_220n_0402"
			(at 0 1.4 180)
			(layer "F.Fab")
			(effects
				(font
					(size 0.7 0.7)
					(thickness 0.15)
				)
				(justify left bottom)
			)
		)
		(property "Footprint" "antmicro-footprints:C_0402_1005Metric"
			(at 0 0 180)
			(layer "F.Fab")
			(hide yes)
			(effects
				(font
					(size 1.27 1.27)
					(thickness 0.15)
				)
			)
		)
		(property "Datasheet" "https://www.yageo.com/en/Chart/Download/pdf/CC0402KRX5R6BB224"
			(at 0 0 180)
			(layer "F.Fab")
			(hide yes)
			(effects
				(font
					(size 1.27 1.27)
					(thickness 0.15)
				)
			)
		)
		(property "Author" "Antmicro"
			(at 272.7 167.9 0)
			(layer "F.Fab")
			(hide yes)
			(effects
				(font
					(size 1 1)
					(thickness 0.15)
				)
			)
		)
		(property "Dielectric" ""
			(at 272.7 167.9 0)
			(layer "F.Fab")
			(hide yes)
			(effects
				(font
					(size 1 1)
					(thickness 0.15)
				)
			)
		)
		(property "License" "Apache-2.0"
			(at 272.7 167.9 0)
			(layer "F.Fab")
			(hide yes)
			(effects
				(font
					(size 1 1)
					(thickness 0.15)
				)
			)
		)
		(property "MPN" "CC0402KRX5R6BB224"
			(at 272.7 167.9 0)
			(layer "F.Fab")
			(hide yes)
			(effects
				(font
					(size 1 1)
					(thickness 0.15)
				)
			)
		)
		(property "Manufacturer" "YAGEO"
			(at 272.7 167.9 0)
			(layer "F.Fab")
			(hide yes)
			(effects
				(font
					(size 1 1)
					(thickness 0.15)
				)
			)
		)
		(property "Val" "220n"
			(at 272.7 167.9 0)
			(layer "F.Fab")
			(hide yes)
			(effects
				(font
					(size 1 1)
					(thickness 0.15)
				)
			)
		)
		(property "Voltage" ""
			(at 272.7 167.9 0)
			(layer "F.Fab")
			(hide yes)
			(effects
				(font
					(size 1 1)
					(thickness 0.15)
				)
			)
		)
		(sheetname "Peripherals")
		(sheetfile "peripherals.kicad_sch")
		(attr smd)
		(fp_rect
			(start -0.925 -0.47)
			(end 0.925 0.47)
			(stroke
				(width 0.05)
				(type default)
			)
			(fill none)
			(layer "F.CrtYd")
		)
		(fp_line
			(start 0.504 0.248)
			(end -0.494 0.248)
			(stroke
				(width 0.15)
				(type solid)
			)
			(layer "F.Fab")
		)
		(fp_line
			(start 0.504 -0.25)
			(end 0.504 0.248)
			(stroke
				(width 0.15)
				(type solid)
			)
			(layer "F.Fab")
		)
		(fp_line
			(start -0.494 0.248)
			(end -0.494 -0.25)
			(stroke
				(width 0.15)
				(type solid)
			)
			(layer "F.Fab")
		)
		(fp_line
			(start -0.494 -0.25)
			(end 0.504 -0.25)
			(stroke
				(width 0.15)
				(type solid)
			)
			(layer "F.Fab")
		)
		(fp_text user "License: Apache-2.0"
			(at -0.932 5.17 180)
			(layer "F.Fab")
			(hide yes)
			(effects
				(font
					(size 0.7 0.7)
					(thickness 0.15)
				)
				(justify left bottom)
			)
		)
		(fp_text user "Author: Antmicro"
			(at -0.932 4.17 180)
			(layer "F.Fab")
			(hide yes)
			(effects
				(font
					(size 0.7 0.7)
					(thickness 0.15)
				)
				(justify left bottom)
			)
		)
		(fp_text user "${REFERENCE}"
			(at -0.932 3.168 180)
			(layer "F.Fab")
			(hide yes)
			(effects
				(font
					(size 0.7 0.7)
					(thickness 0.15)
				)
				(justify left bottom)
			)
		)
		(pad "1" smd roundrect
			(at -0.48 0 180)
			(size 0.59 0.64)
			(layers "F.Cu" "F.Paste" "F.Mask")
			(roundrect_rratio 0.25)
			(net 413 "/Peripherals/PCIE2_TX1_CONN_P")
			(pintype "passive")
		)
		(pad "2" smd roundrect
			(at 0.48 0 180)
			(size 0.59 0.64)
			(layers "F.Cu" "F.Paste" "F.Mask")
			(roundrect_rratio 0.25)
			(net 370 "PCIE2_TX1_P")
			(pintype "passive")
		)
	)
	(footprint "antmicro-footprints:R_0402_1005Metric"
		(layer "F.Cu")
		(at 92.8 92.2)
		(descr "Resistor SMD 0402")
		(tags "resistor SMD 0402")
		(property "Reference" "R228"
			(at 0 -0.7 0)
			(layer "F.SilkS")
			(effects
				(font
					(size 0.7 0.7)
					(thickness 0.15)
				)
				(justify left bottom)
			)
		)
		(property "Value" "R_10k_0402"
			(at 0 1.4 0)
			(layer "F.Fab")
			(effects
				(font
					(size 0.7 0.7)
					(thickness 0.15)
				)
				(justify left bottom)
			)
		)
		(property "Footprint" "antmicro-footprints:R_0402_1005Metric"
			(at 0 0 0)
			(layer "F.Fab")
			(hide yes)
			(effects
				(font
					(size 1.27 1.27)
					(thickness 0.15)
				)
			)
		)
		(property "Datasheet" "https://www.bourns.com/docs/product-datasheets/cr.pdf"
			(at 0 0 0)
			(layer "F.Fab")
			(hide yes)
			(effects
				(font
					(size 1.27 1.27)
					(thickness 0.15)
				)
			)
		)
		(property "Author" "Antmicro"
			(at 0 0 0)
			(layer "F.Fab")
			(hide yes)
			(effects
				(font
					(size 1 1)
					(thickness 0.15)
				)
			)
		)
		(property "License" "Apache-2.0"
			(at 0 0 0)
			(layer "F.Fab")
			(hide yes)
			(effects
				(font
					(size 1 1)
					(thickness 0.15)
				)
			)
		)
		(property "MPN" "CR0402-FX-1002GLF"
			(at 0 0 0)
			(layer "F.Fab")
			(hide yes)
			(effects
				(font
					(size 1 1)
					(thickness 0.15)
				)
			)
		)
		(property "Manufacturer" "Bourns"
			(at 0 0 0)
			(layer "F.Fab")
			(hide yes)
			(effects
				(font
					(size 1 1)
					(thickness 0.15)
				)
			)
		)
		(property "Tolerance" "1%"
			(at 0 0 0)
			(layer "F.Fab")
			(hide yes)
			(effects
				(font
					(size 1 1)
					(thickness 0.15)
				)
			)
		)
		(property "Val" "10k"
			(at 0 0 0)
			(layer "F.Fab")
			(hide yes)
			(effects
				(font
					(size 1 1)
					(thickness 0.15)
				)
			)
		)
		(sheetname "HDMI")
		(sheetfile "hdmi.kicad_sch")
		(attr smd exclude_from_pos_files exclude_from_bom dnp)
		(fp_rect
			(start -0.925 -0.47)
			(end 0.925 0.47)
			(stroke
				(width 0.05)
				(type default)
			)
			(fill none)
			(layer "F.CrtYd")
		)
		(fp_rect
			(start -0.5 -0.25)
			(end 0.5 0.25)
			(stroke
				(width 0.15)
				(type solid)
			)
			(fill none)
			(layer "F.Fab")
		)
		(fp_text user "${REFERENCE}"
			(at -0.95 3.168 0)
			(layer "F.Fab")
			(hide yes)
			(effects
				(font
					(size 0.7 0.7)
					(thickness 0.15)
				)
				(justify left bottom)
			)
		)
		(fp_text user "License: Apache-2.0"
			(at -0.95 5.169 0)
			(layer "F.Fab")
			(hide yes)
			(effects
				(font
					(size 0.7 0.7)
					(thickness 0.15)
				)
				(justify left bottom)
			)
		)
		(fp_text user "Author: Antmicro"
			(at -0.95 4.169 0)
			(layer "F.Fab")
			(hide yes)
			(effects
				(font
					(size 0.7 0.7)
					(thickness 0.15)
				)
				(justify left bottom)
			)
		)
		(pad "1" smd roundrect
			(at -0.48 0)
			(size 0.59 0.64)
			(layers "F.Cu" "F.Paste" "F.Mask")
			(roundrect_rratio 0.25)
			(net 624 "Net-(Q3-D)")
			(pintype "passive")
		)
		(pad "2" smd roundrect
			(at 0.48 0)
			(size 0.59 0.64)
			(layers "F.Cu" "F.Paste" "F.Mask")
			(roundrect_rratio 0.25)
			(net 87 "+3V3")
			(pintype "passive")
		)
	)
	(footprint "antmicro-footprints:SW_KMR211NGLFS_SMD"
		(layer "F.Cu")
		(at 128.9 125.9 180)
		(property "Reference" "S3"
			(at 2.41 1.97 180)
			(layer "F.SilkS")
			(effects
				(font
					(size 0.7 0.7)
					(thickness 0.15)
				)
				(justify left bottom)
			)
		)
		(property "Value" "SW_KMR211NGLFS_SMD"
			(at -3 3 180)
			(layer "F.Fab")
			(effects
				(font
					(size 0.7 0.7)
					(thickness 0.15)
				)
				(justify left bottom)
			)
		)
		(property "Footprint" "antmicro-footprints:SW_KMR211NGLFS_SMD"
			(at 0 0 180)
			(layer "F.Fab")
			(hide yes)
			(effects
				(font
					(size 1.27 1.27)
					(thickness 0.15)
				)
			)
		)
		(property "Datasheet" "http://www.farnell.com/datasheets/2631211.pdf"
			(at 0 0 180)
			(layer "F.Fab")
			(hide yes)
			(effects
				(font
					(size 1.27 1.27)
					(thickness 0.15)
				)
			)
		)
		(property "Author" "Antmicro"
			(at 257.8 251.8 0)
			(layer "F.Fab")
			(hide yes)
			(effects
				(font
					(size 1 1)
					(thickness 0.15)
				)
			)
		)
		(property "License" "Apache-2.0"
			(at 257.8 251.8 0)
			(layer "F.Fab")
			(hide yes)
			(effects
				(font
					(size 1 1)
					(thickness 0.15)
				)
			)
		)
		(property "MPN" "KMR211NGLFS"
			(at 257.8 251.8 0)
			(layer "F.Fab")
			(hide yes)
			(effects
				(font
					(size 1 1)
					(thickness 0.15)
				)
			)
		)
		(property "Manufacturer" "C&K"
			(at 257.8 251.8 0)
			(layer "F.Fab")
			(hide yes)
			(effects
				(font
					(size 1 1)
					(thickness 0.15)
				)
			)
		)
		(sheetname "Peripherals")
		(sheetfile "peripherals.kicad_sch")
		(attr smd)
		(fp_line
			(start 2.101 1.601)
			(end 2.101 1.48)
			(stroke
				(width 0.15)
				(type solid)
			)
			(layer "F.SilkS")
		)
		(fp_line
			(start 2.101 1.601)
			(end -2.1 1.601)
			(stroke
				(width 0.15)
				(type solid)
			)
			(layer "F.SilkS")
		)
		(fp_line
			(start 2.101 -1.58)
			(end 2.101 -1.459)
			(stroke
				(width 0.15)
				(type solid)
			)
			(layer "F.SilkS")
		)
		(fp_line
			(start 2.101 -1.6)
			(end -2.1 -1.6)
			(stroke
				(width 0.15)
				(type solid)
			)
			(layer "F.SilkS")
		)
		(fp_line
			(start -2.1 1.601)
			(end -2.1 1.48)
			(stroke
				(width 0.15)
				(type solid)
			)
			(layer "F.SilkS")
		)
		(fp_line
			(start -2.1 -1.6)
			(end -2.1 -1.499)
			(stroke
				(width 0.15)
				(type solid)
			)
			(layer "F.SilkS")
		)
		(fp_rect
			(start 2.751 1.75)
			(end -2.748 -1.749)
			(stroke
				(width 0.05)
				(type solid)
			)
			(fill none)
			(layer "F.CrtYd")
		)
		(fp_line
			(start 2.101 1.601)
			(end 2.101 -1.6)
			(stroke
				(width 0.15)
				(type solid)
			)
			(layer "F.Fab")
		)
		(fp_line
			(start 2.101 -1.6)
			(end -2.1 -1.6)
			(stroke
				(width 0.15)
				(type solid)
			)
			(layer "F.Fab")
		)
		(fp_line
			(start 0.25 0.802)
			(end -0.248 0.802)
			(stroke
				(width 0.15)
				(type solid)
			)
			(layer "F.Fab")
		)
		(fp_line
			(start -0.248 -0.8)
			(end 0.25 -0.8)
			(stroke
				(width 0.15)
				(type solid)
			)
			(layer "F.Fab")
		)
		(fp_line
			(start -2.1 1.601)
			(end 2.101 1.601)
			(stroke
				(width 0.15)
				(type solid)
			)
			(layer "F.Fab")
		)
		(fp_line
			(start -2.1 -1.6)
			(end -2.1 1.601)
			(stroke
				(width 0.15)
				(type solid)
			)
			(layer "F.Fab")
		)
		(fp_arc
			(start 0.25 -0.8)
			(mid 1.051001 0.001)
			(end 0.25 0.802)
			(stroke
				(width 0.15)
				(type solid)
			)
			(layer "F.Fab")
		)
		(fp_arc
			(start -0.248 0.802)
			(mid -1.050001 0.001)
			(end -0.248 -0.8)
			(stroke
				(width 0.15)
				(type solid)
			)
			(layer "F.Fab")
		)
		(fp_text user "License: Apache-2.0"
			(at -3 6.75 180)
			(layer "F.Fab")
			(hide yes)
			(effects
				(font
					(size 0.7 0.7)
					(thickness 0.15)
				)
				(justify left bottom)
			)
		)
		(fp_text user "${REFERENCE}"
			(at -3 4.25 180)
			(layer "F.Fab")
			(hide yes)
			(effects
				(font
					(size 0.7 0.7)
					(thickness 0.15)
				)
				(justify left bottom)
			)
		)
		(fp_text user "Author: Antmicro"
			(at -3 5.5 180)
			(layer "F.Fab")
			(hide yes)
			(effects
				(font
					(size 0.7 0.7)
					(thickness 0.15)
				)
				(justify left bottom)
			)
		)
		(pad "1" smd rect
			(at -2.048 -0.8)
			(size 0.9 1)
			(layers "F.Cu" "F.Paste" "F.Mask")
			(net 46 "USER_BTN1")
			(pinfunction "1")
			(pintype "passive")
		)
		(pad "2" smd rect
			(at 2.05 -0.8)
			(size 0.9 1)
			(layers "F.Cu" "F.Paste" "F.Mask")
			(net 46 "USER_BTN1")
			(pinfunction "2")
			(pintype "passive")
		)
		(pad "3" smd rect
			(at -2.048 0.802)
			(size 0.9 1)
			(layers "F.Cu" "F.Paste" "F.Mask")
			(net 1 "GND")
			(pinfunction "3")
			(pintype "passive")
		)
		(pad "4" smd rect
			(at 2.05 0.802)
			(size 0.9 1)
			(layers "F.Cu" "F.Paste" "F.Mask")
			(net 1 "GND")
			(pinfunction "4")
			(pintype "passive")
		)
	)
	(footprint "antmicro-footprints:TP_SMD_0.75mm"
		(layer "F.Cu")
		(at 127.905 113.22 180)
		(property "Reference" "TP8"
			(at -0.42 -0.425 180)
			(layer "F.SilkS")
			(effects
				(font
					(size 0.7 0.7)
					(thickness 0.15)
				)
				(justify left bottom)
			)
		)
		(property "Value" "TP_0.75mm_SMD"
			(at 0 1.2 180)
			(layer "F.Fab")
			(effects
				(font
					(size 0.7 0.7)
					(thickness 0.15)
				)
				(justify left bottom)
			)
		)
		(property "Footprint" "antmicro-footprints:TP_SMD_0.75mm"
			(at 0 0 180)
			(layer "F.Fab")
			(hide yes)
			(effects
				(font
					(size 1.27 1.27)
					(thickness 0.15)
				)
			)
		)
		(property "Author" "Antmicro"
			(at 255.81 226.44 0)
			(layer "F.Fab")
			(hide yes)
			(effects
				(font
					(size 1 1)
					(thickness 0.15)
				)
			)
		)
		(property "License" "Apache-2.0"
			(at 255.81 226.44 0)
			(layer "F.Fab")
			(hide yes)
			(effects
				(font
					(size 1 1)
					(thickness 0.15)
				)
			)
		)
		(property "MPN" ""
			(at 255.81 226.44 0)
			(layer "F.Fab")
			(hide yes)
			(effects
				(font
					(size 1 1)
					(thickness 0.15)
				)
			)
		)
		(property "Manufacturer" ""
			(at 255.81 226.44 0)
			(layer "F.Fab")
			(hide yes)
			(effects
				(font
					(size 1 1)
					(thickness 0.15)
				)
			)
		)
		(sheetname "M.2")
		(sheetfile "m-2.kicad_sch")
		(attr exclude_from_pos_files exclude_from_bom)
		(fp_circle
			(center 0 0)
			(end 0.475 0)
			(stroke
				(width 0.05)
				(type default)
			)
			(fill none)
			(layer "F.CrtYd")
		)
		(fp_text user "Author: Antmicro"
			(at -0.4 3.901 180)
			(layer "F.Fab")
			(hide yes)
			(effects
				(font
					(size 0.7 0.7)
					(thickness 0.15)
				)
				(justify left bottom)
			)
		)
		(fp_text user "${REFERENCE}"
			(at -0.4 2.7 180)
			(layer "F.Fab")
			(hide yes)
			(effects
				(font
					(size 0.7 0.7)
					(thickness 0.15)
				)
				(justify left bottom)
			)
		)
		(fp_text user "License: Apache-2.0"
			(at -0.4 5.101 180)
			(layer "F.Fab")
			(hide yes)
			(effects
				(font
					(size 0.7 0.7)
					(thickness 0.15)
				)
				(justify left bottom)
			)
		)
		(pad "1" smd circle
			(at 0 0 180)
			(size 0.75 0.75)
			(layers "F.Cu" "F.Mask")
			(net 218 "/M.2/M2_E_W_DIS_2")
			(pinfunction "1")
			(pintype "passive")
		)
	)
	(footprint "antmicro-footprints:R_0402_1005Metric"
		(layer "F.Cu")
		(at 78.17 85.88 -90)
		(descr "Resistor SMD 0402")
		(tags "resistor SMD 0402")
		(property "Reference" "R264"
			(at -3.56 -0.46 90)
			(layer "F.SilkS")
			(effects
				(font
					(size 0.7 0.7)
					(thickness 0.15)
				)
				(justify right bottom)
			)
		)
		(property "Value" "R_0R_0402"
			(at -1.011843 1.772047 90)
			(layer "F.Fab")
			(effects
				(font
					(size 0.7 0.7)
					(thickness 0.15)
				)
				(justify right bottom)
			)
		)
		(property "Footprint" "antmicro-footprints:R_0402_1005Metric"
			(at 0 0 -90)
			(layer "F.Fab")
			(hide yes)
			(effects
				(font
					(size 1.27 1.27)
					(thickness 0.15)
				)
			)
		)
		(property "Datasheet" "https://industrial.panasonic.com/cdbs/www-data/pdf/RDA0000/AOA0000C301.pdf"
			(at 0 0 -90)
			(layer "F.Fab")
			(hide yes)
			(effects
				(font
					(size 1.27 1.27)
					(thickness 0.15)
				)
			)
		)
		(property "Author" "Antmicro"
			(at -7.71 164.05 0)
			(layer "F.Fab")
			(hide yes)
			(effects
				(font
					(size 1 1)
					(thickness 0.15)
				)
			)
		)
		(property "Current" "1A"
			(at -7.71 164.05 0)
			(layer "F.Fab")
			(hide yes)
			(effects
				(font
					(size 1 1)
					(thickness 0.15)
				)
			)
		)
		(property "License" "Apache-2.0"
			(at -7.71 164.05 0)
			(layer "F.Fab")
			(hide yes)
			(effects
				(font
					(size 1 1)
					(thickness 0.15)
				)
			)
		)
		(property "MPN" "ERJ2GE0R00X"
			(at -7.71 164.05 0)
			(layer "F.Fab")
			(hide yes)
			(effects
				(font
					(size 1 1)
					(thickness 0.15)
				)
			)
		)
		(property "Manufacturer" "Panasonic"
			(at -7.71 164.05 0)
			(layer "F.Fab")
			(hide yes)
			(effects
				(font
					(size 1 1)
					(thickness 0.15)
				)
			)
		)
		(property "Tolerance" ""
			(at -7.71 164.05 0)
			(layer "F.Fab")
			(hide yes)
			(effects
				(font
					(size 1 1)
					(thickness 0.15)
				)
			)
		)
		(property "Val" "0R"
			(at -7.71 164.05 0)
			(layer "F.Fab")
			(hide yes)
			(effects
				(font
					(size 1 1)
					(thickness 0.15)
				)
			)
		)
		(sheetname "Supply")
		(sheetfile "supply.kicad_sch")
		(attr smd)
		(fp_rect
			(start -0.925 -0.47)
			(end 0.925 0.47)
			(stroke
				(width 0.05)
				(type default)
			)
			(fill none)
			(layer "F.CrtYd")
		)
		(fp_rect
			(start -0.5 -0.25)
			(end 0.5 0.25)
			(stroke
				(width 0.15)
				(type solid)
			)
			(fill none)
			(layer "F.Fab")
		)
		(fp_text user "License: Apache-2.0"
			(at -0.95 5.169 90)
			(layer "F.Fab")
			(hide yes)
			(effects
				(font
					(size 0.7 0.7)
					(thickness 0.15)
				)
				(justify right bottom)
			)
		)
		(fp_text user "${REFERENCE}"
			(at -0.95 3.168 90)
			(layer "F.Fab")
			(hide yes)
			(effects
				(font
					(size 0.7 0.7)
					(thickness 0.15)
				)
				(justify right bottom)
			)
		)
		(fp_text user "Author: Antmicro"
			(at -0.95 4.169 90)
			(layer "F.Fab")
			(hide yes)
			(effects
				(font
					(size 0.7 0.7)
					(thickness 0.15)
				)
				(justify right bottom)
			)
		)
		(pad "1" smd roundrect
			(at -0.48 0 270)
			(size 0.59 0.64)
			(layers "F.Cu" "F.Paste" "F.Mask")
			(roundrect_rratio 0.25)
			(net 86 "~{RESET}")
			(pintype "passive")
		)
		(pad "2" smd roundrect
			(at 0.48 0 270)
			(size 0.59 0.64)
			(layers "F.Cu" "F.Paste" "F.Mask")
			(roundrect_rratio 0.25)
			(net 771 "/Supply/3V3_EN")
			(pintype "passive")
		)
	)
	(footprint "antmicro-footprints:R_0402_1005Metric"
		(layer "F.Cu")
		(at 60.15 106.55 -90)
		(descr "Resistor SMD 0402")
		(tags "resistor SMD 0402")
		(property "Reference" "R144"
			(at -0.75 -0.4 -90)
			(layer "F.SilkS")
			(effects
				(font
					(size 0.7 0.7)
					(thickness 0.15)
				)
				(justify left bottom)
			)
		)
		(property "Value" "R_0R_0402"
			(at 0 1.4 -90)
			(layer "F.Fab")
			(effects
				(font
					(size 0.7 0.7)
					(thickness 0.15)
				)
				(justify left bottom)
			)
		)
		(property "Footprint" "antmicro-footprints:R_0402_1005Metric"
			(at 0 0 -90)
			(layer "F.Fab")
			(hide yes)
			(effects
				(font
					(size 1.27 1.27)
					(thickness 0.15)
				)
			)
		)
		(property "Datasheet" "https://industrial.panasonic.com/cdbs/www-data/pdf/RDA0000/AOA0000C301.pdf"
			(at 0 0 -90)
			(layer "F.Fab")
			(hide yes)
			(effects
				(font
					(size 1.27 1.27)
					(thickness 0.15)
				)
			)
		)
		(property "Author" "Antmicro"
			(at -46.4 166.7 0)
			(layer "F.Fab")
			(hide yes)
			(effects
				(font
					(size 1 1)
					(thickness 0.15)
				)
			)
		)
		(property "Current" "1A"
			(at -46.4 166.7 0)
			(layer "F.Fab")
			(hide yes)
			(effects
				(font
					(size 1 1)
					(thickness 0.15)
				)
			)
		)
		(property "License" "Apache-2.0"
			(at -46.4 166.7 0)
			(layer "F.Fab")
			(hide yes)
			(effects
				(font
					(size 1 1)
					(thickness 0.15)
				)
			)
		)
		(property "MPN" "ERJ2GE0R00X"
			(at -46.4 166.7 0)
			(layer "F.Fab")
			(hide yes)
			(effects
				(font
					(size 1 1)
					(thickness 0.15)
				)
			)
		)
		(property "Manufacturer" "Panasonic"
			(at -46.4 166.7 0)
			(layer "F.Fab")
			(hide yes)
			(effects
				(font
					(size 1 1)
					(thickness 0.15)
				)
			)
		)
		(property "Tolerance" ""
			(at -46.4 166.7 0)
			(layer "F.Fab")
			(hide yes)
			(effects
				(font
					(size 1 1)
					(thickness 0.15)
				)
			)
		)
		(property "Val" "0R"
			(at -46.4 166.7 0)
			(layer "F.Fab")
			(hide yes)
			(effects
				(font
					(size 1 1)
					(thickness 0.15)
				)
			)
		)
		(sheetname "USB Debug, DP")
		(sheetfile "usb.kicad_sch")
		(attr smd exclude_from_pos_files exclude_from_bom dnp)
		(fp_rect
			(start -0.925 -0.47)
			(end 0.925 0.47)
			(stroke
				(width 0.05)
				(type default)
			)
			(fill none)
			(layer "F.CrtYd")
		)
		(fp_rect
			(start -0.5 -0.25)
			(end 0.5 0.25)
			(stroke
				(width 0.15)
				(type solid)
			)
			(fill none)
			(layer "F.Fab")
		)
		(fp_text user "${REFERENCE}"
			(at -0.95 3.168 -90)
			(layer "F.Fab")
			(hide yes)
			(effects
				(font
					(size 0.7 0.7)
					(thickness 0.15)
				)
				(justify left bottom)
			)
		)
		(fp_text user "License: Apache-2.0"
			(at -0.95 5.169 -90)
			(layer "F.Fab")
			(hide yes)
			(effects
				(font
					(size 0.7 0.7)
					(thickness 0.15)
				)
				(justify left bottom)
			)
		)
		(fp_text user "Author: Antmicro"
			(at -0.95 4.169 -90)
			(layer "F.Fab")
			(hide yes)
			(effects
				(font
					(size 0.7 0.7)
					(thickness 0.15)
				)
				(justify left bottom)
			)
		)
		(pad "1" smd roundrect
			(at -0.48 0 270)
			(size 0.59 0.64)
			(layers "F.Cu" "F.Paste" "F.Mask")
			(roundrect_rratio 0.25)
			(net 549 "/USB Debug, DP/USBC3_5V_PEN")
			(pintype "passive")
		)
		(pad "2" smd roundrect
			(at 0.48 0 270)
			(size 0.59 0.64)
			(layers "F.Cu" "F.Paste" "F.Mask")
			(roundrect_rratio 0.25)
			(net 99 "+5V")
			(pintype "passive")
		)
	)
	(footprint "antmicro-footprints:XDFN-2_1x0.60mm"
		(layer "F.Cu")
		(at 147.45 84.3 90)
		(property "Reference" "D45"
			(at 5.47 -0.15 0)
			(layer "F.SilkS")
			(effects
				(font
					(size 0.7 0.7)
					(thickness 0.15)
				)
				(justify left bottom)
			)
		)
		(property "Value" "TPD1E0B04_XDFN-2"
			(at 0 1.5 90)
			(layer "F.Fab")
			(effects
				(font
					(size 0.7 0.7)
					(thickness 0.15)
				)
				(justify left bottom)
			)
		)
		(property "Footprint" "antmicro-footprints:XDFN-2_1x0.60mm"
			(at 0 0 90)
			(layer "F.Fab")
			(hide yes)
			(effects
				(font
					(size 1.27 1.27)
					(thickness 0.15)
				)
			)
		)
		(property "Datasheet" "https://www.ti.com/general/docs/suppproductinfo.tsp?distId=26&gotoUrl=https://www.ti.com/lit/gpn/tpd1e0b04"
			(at 0 0 90)
			(layer "F.Fab")
			(hide yes)
			(effects
				(font
					(size 1.27 1.27)
					(thickness 0.15)
				)
			)
		)
		(property "MPN" "TPD1E0B04DPYR"
			(at 231.75 -63.15 0)
			(layer "F.Fab")
			(hide yes)
			(effects
				(font
					(size 1 1)
					(thickness 0.15)
				)
			)
		)
		(property "Manufacturer" "Texas Instruments"
			(at 231.75 -63.15 0)
			(layer "F.Fab")
			(hide yes)
			(effects
				(font
					(size 1 1)
					(thickness 0.15)
				)
			)
		)
		(property "Author" "Antmicro"
			(at 231.75 -63.15 0)
			(layer "F.Fab")
			(hide yes)
			(effects
				(font
					(size 1 1)
					(thickness 0.15)
				)
			)
		)
		(property "License" "Apache-2.0"
			(at 231.75 -63.15 0)
			(layer "F.Fab")
			(hide yes)
			(effects
				(font
					(size 1 1)
					(thickness 0.15)
				)
			)
		)
		(sheetname "Peripherals")
		(sheetfile "peripherals.kicad_sch")
		(attr smd)
		(fp_rect
			(start -0.725 -0.475)
			(end 0.725 0.475)
			(stroke
				(width 0.05)
				(type solid)
			)
			(fill none)
			(layer "F.CrtYd")
		)
		(fp_rect
			(start -0.55 -0.35)
			(end 0.55 0.35)
			(stroke
				(width 0.15)
				(type solid)
			)
			(fill none)
			(layer "F.Fab")
		)
		(fp_text user "License: Apache-2.0"
			(at -0.8 5.6 90)
			(layer "F.Fab")
			(hide yes)
			(effects
				(font
					(size 0.7 0.7)
					(thickness 0.15)
				)
				(justify left bottom)
			)
		)
		(fp_text user "${REFERENCE}"
			(at -0.8 3.2 90)
			(layer "F.Fab")
			(hide yes)
			(effects
				(font
					(size 0.7 0.7)
					(thickness 0.15)
				)
				(justify left bottom)
			)
		)
		(fp_text user "Author: Antmicro"
			(at -0.8 4.4 90)
			(layer "F.Fab")
			(hide yes)
			(effects
				(font
					(size 0.7 0.7)
					(thickness 0.15)
				)
				(justify left bottom)
			)
		)
		(pad "1" smd roundrect
			(at -0.351 0 90)
			(size 0.3 0.5)
			(layers "F.Cu" "F.Paste" "F.Mask")
			(roundrect_rratio 0.25)
			(net 172 "PCIE2_RX1_N")
			(pinfunction "C")
			(pintype "passive")
		)
		(pad "2" smd roundrect
			(at 0.349 0 90)
			(size 0.3 0.5)
			(layers "F.Cu" "F.Paste" "F.Mask")
			(roundrect_rratio 0.25)
			(net 1 "GND")
			(pinfunction "A")
			(pintype "passive")
		)
	)
	(footprint "antmicro-footprints:C_0402_1005Metric"
		(layer "F.Cu")
		(at 81.9 107 180)
		(descr "Capacitor SMD 0402")
		(tags "capacitor SMD 0402")
		(property "Reference" "C143"
			(at -0.8 -0.4 180)
			(layer "F.SilkS")
			(effects
				(font
					(size 0.7 0.7)
					(thickness 0.15)
				)
				(justify left bottom)
			)
		)
		(property "Value" "C_100n_0402"
			(at 0 1.4 180)
			(layer "F.Fab")
			(effects
				(font
					(size 0.7 0.7)
					(thickness 0.15)
				)
				(justify left bottom)
			)
		)
		(property "Footprint" "antmicro-footprints:C_0402_1005Metric"
			(at 0 0 180)
			(layer "F.Fab")
			(hide yes)
			(effects
				(font
					(size 1.27 1.27)
					(thickness 0.15)
				)
			)
		)
		(property "Datasheet" "https://www.murata.com/products/productdetail?partno=GRM155R61H104KE14%23"
			(at 0 0 180)
			(layer "F.Fab")
			(hide yes)
			(effects
				(font
					(size 1.27 1.27)
					(thickness 0.15)
				)
			)
		)
		(property "Author" "Antmicro"
			(at 163.8 214 0)
			(layer "F.Fab")
			(hide yes)
			(effects
				(font
					(size 1 1)
					(thickness 0.15)
				)
			)
		)
		(property "Dielectric" "X5R"
			(at 163.8 214 0)
			(layer "F.Fab")
			(hide yes)
			(effects
				(font
					(size 1 1)
					(thickness 0.15)
				)
			)
		)
		(property "License" "Apache-2.0"
			(at 163.8 214 0)
			(layer "F.Fab")
			(hide yes)
			(effects
				(font
					(size 1 1)
					(thickness 0.15)
				)
			)
		)
		(property "MPN" "GRM155R61H104KE14D"
			(at 163.8 214 0)
			(layer "F.Fab")
			(hide yes)
			(effects
				(font
					(size 1 1)
					(thickness 0.15)
				)
			)
		)
		(property "Manufacturer" "Murata"
			(at 163.8 214 0)
			(layer "F.Fab")
			(hide yes)
			(effects
				(font
					(size 1 1)
					(thickness 0.15)
				)
			)
		)
		(property "Val" "100n"
			(at 163.8 214 0)
			(layer "F.Fab")
			(hide yes)
			(effects
				(font
					(size 1 1)
					(thickness 0.15)
				)
			)
		)
		(property "Voltage" "50V"
			(at 163.8 214 0)
			(layer "F.Fab")
			(hide yes)
			(effects
				(font
					(size 1 1)
					(thickness 0.15)
				)
			)
		)
		(sheetname "USB Debug, DP")
		(sheetfile "usb.kicad_sch")
		(attr smd)
		(fp_rect
			(start -0.925 -0.47)
			(end 0.925 0.47)
			(stroke
				(width 0.05)
				(type default)
			)
			(fill none)
			(layer "F.CrtYd")
		)
		(fp_line
			(start 0.504 0.248)
			(end -0.494 0.248)
			(stroke
				(width 0.15)
				(type solid)
			)
			(layer "F.Fab")
		)
		(fp_line
			(start 0.504 -0.25)
			(end 0.504 0.248)
			(stroke
				(width 0.15)
				(type solid)
			)
			(layer "F.Fab")
		)
		(fp_line
			(start -0.494 0.248)
			(end -0.494 -0.25)
			(stroke
				(width 0.15)
				(type solid)
			)
			(layer "F.Fab")
		)
		(fp_line
			(start -0.494 -0.25)
			(end 0.504 -0.25)
			(stroke
				(width 0.15)
				(type solid)
			)
			(layer "F.Fab")
		)
		(fp_text user "License: Apache-2.0"
			(at -0.932 5.17 180)
			(layer "F.Fab")
			(hide yes)
			(effects
				(font
					(size 0.7 0.7)
					(thickness 0.15)
				)
				(justify left bottom)
			)
		)
		(fp_text user "${REFERENCE}"
			(at -0.932 3.168 180)
			(layer "F.Fab")
			(hide yes)
			(effects
				(font
					(size 0.7 0.7)
					(thickness 0.15)
				)
				(justify left bottom)
			)
		)
		(fp_text user "Author: Antmicro"
			(at -0.932 4.17 180)
			(layer "F.Fab")
			(hide yes)
			(effects
				(font
					(size 0.7 0.7)
					(thickness 0.15)
				)
				(justify left bottom)
			)
		)
		(pad "1" smd roundrect
			(at -0.48 0 180)
			(size 0.59 0.64)
			(layers "F.Cu" "F.Paste" "F.Mask")
			(roundrect_rratio 0.25)
			(net 56 "USBSS0_RX_N")
			(pintype "passive")
		)
		(pad "2" smd roundrect
			(at 0.48 0 180)
			(size 0.59 0.64)
			(layers "F.Cu" "F.Paste" "F.Mask")
			(roundrect_rratio 0.25)
			(net 193 "/USB Debug, DP/USBSS0_RX_C_P")
			(pintype "passive")
		)
	)
	(footprint "antmicro-footprints:R_0402_1005Metric"
		(layer "F.Cu")
		(at 96.65 98.05 180)
		(descr "Resistor SMD 0402")
		(tags "resistor SMD 0402")
		(property "Reference" "R163"
			(at 1.4 0.45 180)
			(layer "F.SilkS")
			(effects
				(font
					(size 0.7 0.7)
					(thickness 0.15)
				)
				(justify left bottom)
			)
		)
		(property "Value" "R_10k_0402"
			(at 0 1.4 180)
			(layer "F.Fab")
			(effects
				(font
					(size 0.7 0.7)
					(thickness 0.15)
				)
				(justify left bottom)
			)
		)
		(property "Footprint" "antmicro-footprints:R_0402_1005Metric"
			(at 0 0 180)
			(layer "F.Fab")
			(hide yes)
			(effects
				(font
					(size 1.27 1.27)
					(thickness 0.15)
				)
			)
		)
		(property "Datasheet" "https://www.bourns.com/docs/product-datasheets/cr.pdf"
			(at 0 0 180)
			(layer "F.Fab")
			(hide yes)
			(effects
				(font
					(size 1.27 1.27)
					(thickness 0.15)
				)
			)
		)
		(property "Author" "Antmicro"
			(at 193.3 196.1 0)
			(layer "F.Fab")
			(hide yes)
			(effects
				(font
					(size 1 1)
					(thickness 0.15)
				)
			)
		)
		(property "License" "Apache-2.0"
			(at 193.3 196.1 0)
			(layer "F.Fab")
			(hide yes)
			(effects
				(font
					(size 1 1)
					(thickness 0.15)
				)
			)
		)
		(property "MPN" "CR0402-FX-1002GLF"
			(at 193.3 196.1 0)
			(layer "F.Fab")
			(hide yes)
			(effects
				(font
					(size 1 1)
					(thickness 0.15)
				)
			)
		)
		(property "Manufacturer" "Bourns"
			(at 193.3 196.1 0)
			(layer "F.Fab")
			(hide yes)
			(effects
				(font
					(size 1 1)
					(thickness 0.15)
				)
			)
		)
		(property "Tolerance" "1%"
			(at 193.3 196.1 0)
			(layer "F.Fab")
			(hide yes)
			(effects
				(font
					(size 1 1)
					(thickness 0.15)
				)
			)
		)
		(property "Val" "10k"
			(at 193.3 196.1 0)
			(layer "F.Fab")
			(hide yes)
			(effects
				(font
					(size 1 1)
					(thickness 0.15)
				)
			)
		)
		(sheetname "CSI")
		(sheetfile "csi.kicad_sch")
		(attr smd)
		(fp_rect
			(start -0.925 -0.47)
			(end 0.925 0.47)
			(stroke
				(width 0.05)
				(type default)
			)
			(fill none)
			(layer "F.CrtYd")
		)
		(fp_rect
			(start -0.5 -0.25)
			(end 0.5 0.25)
			(stroke
				(width 0.15)
				(type solid)
			)
			(fill none)
			(layer "F.Fab")
		)
		(fp_text user "${REFERENCE}"
			(at -0.95 3.168 180)
			(layer "F.Fab")
			(hide yes)
			(effects
				(font
					(size 0.7 0.7)
					(thickness 0.15)
				)
				(justify left bottom)
			)
		)
		(fp_text user "Author: Antmicro"
			(at -0.95 4.169 180)
			(layer "F.Fab")
			(hide yes)
			(effects
				(font
					(size 0.7 0.7)
					(thickness 0.15)
				)
				(justify left bottom)
			)
		)
		(fp_text user "License: Apache-2.0"
			(at -0.95 5.169 180)
			(layer "F.Fab")
			(hide yes)
			(effects
				(font
					(size 0.7 0.7)
					(thickness 0.15)
				)
				(justify left bottom)
			)
		)
		(pad "1" smd roundrect
			(at -0.48 0 180)
			(size 0.59 0.64)
			(layers "F.Cu" "F.Paste" "F.Mask")
			(roundrect_rratio 0.25)
			(net 112 "+1V8")
			(pintype "passive")
		)
		(pad "2" smd roundrect
			(at 0.48 0 180)
			(size 0.59 0.64)
			(layers "F.Cu" "F.Paste" "F.Mask")
			(roundrect_rratio 0.25)
			(net 324 "/CSI/I2C_MUX_RESET")
			(pintype "passive")
		)
	)
	(footprint "antmicro-footprints:XDFN-2_1x0.60mm"
		(layer "F.Cu")
		(at 136.27 92.63 -90)
		(property "Reference" "D21"
			(at 0.298 -0.402 180)
			(layer "F.SilkS")
			(effects
				(font
					(size 0.7 0.7)
					(thickness 0.15)
				)
				(justify left bottom)
			)
		)
		(property "Value" "TPD1E0B04_XDFN-2"
			(at 0 1.5 -90)
			(layer "F.Fab")
			(effects
				(font
					(size 0.7 0.7)
					(thickness 0.15)
				)
				(justify left bottom)
			)
		)
		(property "Footprint" "antmicro-footprints:XDFN-2_1x0.60mm"
			(at 0 0 -90)
			(layer "F.Fab")
			(hide yes)
			(effects
				(font
					(size 1.27 1.27)
					(thickness 0.15)
				)
			)
		)
		(property "Datasheet" "https://www.ti.com/general/docs/suppproductinfo.tsp?distId=26&gotoUrl=https://www.ti.com/lit/gpn/tpd1e0b04"
			(at 0 0 -90)
			(layer "F.Fab")
			(hide yes)
			(effects
				(font
					(size 1.27 1.27)
					(thickness 0.15)
				)
			)
		)
		(property "MPN" "TPD1E0B04DPYR"
			(at 43.64 228.9 0)
			(layer "F.Fab")
			(hide yes)
			(effects
				(font
					(size 1 1)
					(thickness 0.15)
				)
			)
		)
		(property "Manufacturer" "Texas Instruments"
			(at 43.64 228.9 0)
			(layer "F.Fab")
			(hide yes)
			(effects
				(font
					(size 1 1)
					(thickness 0.15)
				)
			)
		)
		(property "Author" "Antmicro"
			(at 43.64 228.9 0)
			(layer "F.Fab")
			(hide yes)
			(effects
				(font
					(size 1 1)
					(thickness 0.15)
				)
			)
		)
		(property "License" "Apache-2.0"
			(at 43.64 228.9 0)
			(layer "F.Fab")
			(hide yes)
			(effects
				(font
					(size 1 1)
					(thickness 0.15)
				)
			)
		)
		(sheetname "Peripherals")
		(sheetfile "peripherals.kicad_sch")
		(attr smd)
		(fp_rect
			(start -0.725 -0.475)
			(end 0.725 0.475)
			(stroke
				(width 0.05)
				(type solid)
			)
			(fill none)
			(layer "F.CrtYd")
		)
		(fp_rect
			(start -0.55 -0.35)
			(end 0.55 0.35)
			(stroke
				(width 0.15)
				(type solid)
			)
			(fill none)
			(layer "F.Fab")
		)
		(fp_text user "Author: Antmicro"
			(at -0.8 4.4 -90)
			(layer "F.Fab")
			(hide yes)
			(effects
				(font
					(size 0.7 0.7)
					(thickness 0.15)
				)
				(justify left bottom)
			)
		)
		(fp_text user "${REFERENCE}"
			(at -0.8 3.2 -90)
			(layer "F.Fab")
			(hide yes)
			(effects
				(font
					(size 0.7 0.7)
					(thickness 0.15)
				)
				(justify left bottom)
			)
		)
		(fp_text user "License: Apache-2.0"
			(at -0.8 5.6 -90)
			(layer "F.Fab")
			(hide yes)
			(effects
				(font
					(size 0.7 0.7)
					(thickness 0.15)
				)
				(justify left bottom)
			)
		)
		(pad "1" smd roundrect
			(at -0.351 0 270)
			(size 0.3 0.5)
			(layers "F.Cu" "F.Paste" "F.Mask")
			(roundrect_rratio 0.25)
			(net 414 "/Peripherals/USBSS2_TX_CONN_P")
			(pinfunction "C")
			(pintype "passive")
		)
		(pad "2" smd roundrect
			(at 0.349 0 270)
			(size 0.3 0.5)
			(layers "F.Cu" "F.Paste" "F.Mask")
			(roundrect_rratio 0.25)
			(net 1 "GND")
			(pinfunction "A")
			(pintype "passive")
		)
	)
	(footprint "antmicro-footprints:R_Array_4x0201_Panasonic_EXB18V"
		(layer "F.Cu")
		(at 120.3468 112.2)
		(property "Reference" "R21"
			(at -1.0968 -0.65 180)
			(layer "F.SilkS")
			(effects
				(font
					(size 0.7 0.7)
					(thickness 0.15)
				)
				(justify left bottom)
			)
		)
		(property "Value" "R_4x0R_0201_array"
			(at -1.1 1.8 0)
			(layer "F.Fab")
			(effects
				(font
					(size 0.7 0.7)
					(thickness 0.15)
				)
				(justify left bottom)
			)
		)
		(property "Footprint" "antmicro-footprints:R_Array_4x0201_Panasonic_EXB18V"
			(at 0 0 0)
			(layer "F.Fab")
			(hide yes)
			(effects
				(font
					(size 1.27 1.27)
					(thickness 0.15)
				)
			)
		)
		(property "Datasheet" "http://industrial.panasonic.com/cdbs/www-data/pdf/AOC0000/AOC0000C14.pdf"
			(at 0 0 0)
			(layer "F.Fab")
			(hide yes)
			(effects
				(font
					(size 1.27 1.27)
					(thickness 0.15)
				)
			)
		)
		(property "Author" "Antmicro"
			(at 0 0 0)
			(layer "F.Fab")
			(hide yes)
			(effects
				(font
					(size 1 1)
					(thickness 0.15)
				)
			)
		)
		(property "License" "Apache-2.0"
			(at 0 0 0)
			(layer "F.Fab")
			(hide yes)
			(effects
				(font
					(size 1 1)
					(thickness 0.15)
				)
			)
		)
		(property "MPN" "EXB-18VR000X"
			(at 0 0 0)
			(layer "F.Fab")
			(hide yes)
			(effects
				(font
					(size 1 1)
					(thickness 0.15)
				)
			)
		)
		(property "Manufacturer" "Panasonic"
			(at 0 0 0)
			(layer "F.Fab")
			(hide yes)
			(effects
				(font
					(size 1 1)
					(thickness 0.15)
				)
			)
		)
		(property "Val" "4x0R_0201"
			(at 0 0 0)
			(layer "F.Fab")
			(hide yes)
			(effects
				(font
					(size 1 1)
					(thickness 0.15)
				)
			)
		)
		(sheetname "M.2")
		(sheetfile "m-2.kicad_sch")
		(attr smd)
		(fp_line
			(start -0.8 -0.45)
			(end -0.8 0.45)
			(stroke
				(width 0.12)
				(type solid)
			)
			(layer "F.SilkS")
		)
		(fp_line
			(start 0.8 -0.45)
			(end 0.8 0.45)
			(stroke
				(width 0.12)
				(type solid)
			)
			(layer "F.SilkS")
		)
		(fp_rect
			(start -0.898 -0.66)
			(end 0.898 0.65)
			(stroke
				(width 0.05)
				(type solid)
			)
			(fill none)
			(layer "F.CrtYd")
		)
		(fp_text user "License: Apache-2.0"
			(at -1.051 6 0)
			(layer "F.Fab")
			(hide yes)
			(effects
				(font
					(size 0.7 0.7)
					(thickness 0.15)
				)
				(justify left bottom)
			)
		)
		(fp_text user "Author: Antmicro"
			(at -1.051 4.599 0)
			(layer "F.Fab")
			(hide yes)
			(effects
				(font
					(size 0.7 0.7)
					(thickness 0.15)
				)
				(justify left bottom)
			)
		)
		(fp_text user "${REFERENCE}"
			(at -1.051 3.2 0)
			(layer "F.Fab")
			(hide yes)
			(effects
				(font
					(size 0.7 0.7)
					(thickness 0.15)
				)
				(justify left bottom)
			)
		)
		(pad "1" smd roundrect
			(at -0.6 0.298)
			(size 0.2 0.4)
			(layers "F.Cu" "F.Paste" "F.Mask")
			(roundrect_rratio 0.25)
			(net 470 "I2S1_SCLK")
			(pinfunction "R1.1")
			(pintype "passive")
		)
		(pad "2" smd roundrect
			(at -0.202 0.298)
			(size 0.2 0.4)
			(layers "F.Cu" "F.Paste" "F.Mask")
			(roundrect_rratio 0.25)
			(net 469 "I2S1_LRCK")
			(pinfunction "R2.1")
			(pintype "passive")
		)
		(pad "3" smd roundrect
			(at 0.2 0.298)
			(size 0.2 0.4)
			(layers "F.Cu" "F.Paste" "F.Mask")
			(roundrect_rratio 0.25)
			(net 468 "I2S1_SDIN")
			(pinfunction "R3.1")
			(pintype "passive")
		)
		(pad "4" smd roundrect
			(at 0.598 0.298)
			(size 0.2 0.4)
			(layers "F.Cu" "F.Paste" "F.Mask")
			(roundrect_rratio 0.25)
			(net 467 "I2S1_SDOUT")
			(pinfunction "R4.1")
			(pintype "passive")
		)
		(pad "5" smd roundrect
			(at 0.598 -0.3)
			(size 0.2 0.4)
			(layers "F.Cu" "F.Paste" "F.Mask")
			(roundrect_rratio 0.25)
			(net 178 "/M.2/M2_E_PCM_OUT")
			(pinfunction "R4.2")
			(pintype "passive")
		)
		(pad "6" smd roundrect
			(at 0.2 -0.3)
			(size 0.2 0.4)
			(layers "F.Cu" "F.Paste" "F.Mask")
			(roundrect_rratio 0.25)
			(net 651 "/M.2/M2_E_PCM_IN")
			(pinfunction "R3.2")
			(pintype "passive")
		)
		(pad "7" smd roundrect
			(at -0.202 -0.3)
			(size 0.2 0.4)
			(layers "F.Cu" "F.Paste" "F.Mask")
			(roundrect_rratio 0.25)
			(net 176 "/M.2/M2_E_PCM_SYNC")
			(pinfunction "R2.2")
			(pintype "passive")
		)
		(pad "8" smd roundrect
			(at -0.6 -0.3)
			(size 0.2 0.4)
			(layers "F.Cu" "F.Paste" "F.Mask")
			(roundrect_rratio 0.25)
			(net 170 "/M.2/M2_E_PCM_CLK")
			(pinfunction "R1.2")
			(pintype "passive")
		)
	)
	(footprint "antmicro-footprints:C_0402_1005Metric"
		(layer "F.Cu")
		(at 58.18 105.21 90)
		(descr "Capacitor SMD 0402")
		(tags "capacitor SMD 0402")
		(property "Reference" "C44"
			(at -1.01 1.27 90)
			(layer "F.SilkS")
			(effects
				(font
					(size 0.7 0.7)
					(thickness 0.15)
				)
				(justify left bottom)
			)
		)
		(property "Value" "C_100n_0402"
			(at 0 1.4 90)
			(layer "F.Fab")
			(effects
				(font
					(size 0.7 0.7)
					(thickness 0.15)
				)
				(justify left bottom)
			)
		)
		(property "Footprint" "antmicro-footprints:C_0402_1005Metric"
			(at 0 0 90)
			(layer "F.Fab")
			(hide yes)
			(effects
				(font
					(size 1.27 1.27)
					(thickness 0.15)
				)
			)
		)
		(property "Datasheet" "https://www.murata.com/products/productdetail?partno=GRM155R61H104KE14%23"
			(at 0 0 90)
			(layer "F.Fab")
			(hide yes)
			(effects
				(font
					(size 1.27 1.27)
					(thickness 0.15)
				)
			)
		)
		(property "Author" "Antmicro"
			(at 163.39 47.03 0)
			(layer "F.Fab")
			(hide yes)
			(effects
				(font
					(size 1 1)
					(thickness 0.15)
				)
			)
		)
		(property "Dielectric" "X5R"
			(at 163.39 47.03 0)
			(layer "F.Fab")
			(hide yes)
			(effects
				(font
					(size 1 1)
					(thickness 0.15)
				)
			)
		)
		(property "License" "Apache-2.0"
			(at 163.39 47.03 0)
			(layer "F.Fab")
			(hide yes)
			(effects
				(font
					(size 1 1)
					(thickness 0.15)
				)
			)
		)
		(property "MPN" "GRM155R61H104KE14D"
			(at 163.39 47.03 0)
			(layer "F.Fab")
			(hide yes)
			(effects
				(font
					(size 1 1)
					(thickness 0.15)
				)
			)
		)
		(property "Manufacturer" "Murata"
			(at 163.39 47.03 0)
			(layer "F.Fab")
			(hide yes)
			(effects
				(font
					(size 1 1)
					(thickness 0.15)
				)
			)
		)
		(property "Val" "100n"
			(at 163.39 47.03 0)
			(layer "F.Fab")
			(hide yes)
			(effects
				(font
					(size 1 1)
					(thickness 0.15)
				)
			)
		)
		(property "Voltage" "50V"
			(at 163.39 47.03 0)
			(layer "F.Fab")
			(hide yes)
			(effects
				(font
					(size 1 1)
					(thickness 0.15)
				)
			)
		)
		(sheetname "Peripherals")
		(sheetfile "peripherals.kicad_sch")
		(attr smd)
		(fp_rect
			(start -0.925 -0.47)
			(end 0.925 0.47)
			(stroke
				(width 0.05)
				(type default)
			)
			(fill none)
			(layer "F.CrtYd")
		)
		(fp_line
			(start 0.504 -0.25)
			(end 0.504 0.248)
			(stroke
				(width 0.15)
				(type solid)
			)
			(layer "F.Fab")
		)
		(fp_line
			(start -0.494 -0.25)
			(end 0.504 -0.25)
			(stroke
				(width 0.15)
				(type solid)
			)
			(layer "F.Fab")
		)
		(fp_line
			(start 0.504 0.248)
			(end -0.494 0.248)
			(stroke
				(width 0.15)
				(type solid)
			)
			(layer "F.Fab")
		)
		(fp_line
			(start -0.494 0.248)
			(end -0.494 -0.25)
			(stroke
				(width 0.15)
				(type solid)
			)
			(layer "F.Fab")
		)
		(fp_text user "Author: Antmicro"
			(at -0.932 4.17 90)
			(layer "F.Fab")
			(hide yes)
			(effects
				(font
					(size 0.7 0.7)
					(thickness 0.15)
				)
				(justify left bottom)
			)
		)
		(fp_text user "License: Apache-2.0"
			(at -0.932 5.17 90)
			(layer "F.Fab")
			(hide yes)
			(effects
				(font
					(size 0.7 0.7)
					(thickness 0.15)
				)
				(justify left bottom)
			)
		)
		(fp_text user "${REFERENCE}"
			(at -0.932 3.168 90)
			(layer "F.Fab")
			(hide yes)
			(effects
				(font
					(size 0.7 0.7)
					(thickness 0.15)
				)
				(justify left bottom)
			)
		)
		(pad "1" smd roundrect
			(at -0.48 0 90)
			(size 0.59 0.64)
			(layers "F.Cu" "F.Paste" "F.Mask")
			(roundrect_rratio 0.25)
			(net 1 "GND")
			(pintype "passive")
		)
		(pad "2" smd roundrect
			(at 0.48 0 90)
			(size 0.59 0.64)
			(layers "F.Cu" "F.Paste" "F.Mask")
			(roundrect_rratio 0.25)
			(net 112 "+1V8")
			(pintype "passive")
		)
	)
	(footprint "antmicro-footprints:R_0402_1005Metric"
		(layer "F.Cu")
		(at 66.21 99.99)
		(descr "Resistor SMD 0402")
		(tags "resistor SMD 0402")
		(property "Reference" "R269"
			(at -1.7 2.2 0)
			(layer "F.SilkS")
			(effects
				(font
					(size 0.7 0.7)
					(thickness 0.15)
				)
				(justify left bottom)
			)
		)
		(property "Value" "R_10k_0402"
			(at -1.011843 1.772047 0)
			(layer "F.Fab")
			(effects
				(font
					(size 0.7 0.7)
					(thickness 0.15)
				)
				(justify left bottom)
			)
		)
		(property "Footprint" "antmicro-footprints:R_0402_1005Metric"
			(at 0 0 0)
			(layer "F.Fab")
			(hide yes)
			(effects
				(font
					(size 1.27 1.27)
					(thickness 0.15)
				)
			)
		)
		(property "Datasheet" "https://www.bourns.com/docs/product-datasheets/cr.pdf"
			(at 0 0 0)
			(layer "F.Fab")
			(hide yes)
			(effects
				(font
					(size 1.27 1.27)
					(thickness 0.15)
				)
			)
		)
		(property "Author" "Antmicro"
			(at 0 0 0)
			(layer "F.Fab")
			(hide yes)
			(effects
				(font
					(size 1 1)
					(thickness 0.15)
				)
			)
		)
		(property "License" "Apache-2.0"
			(at 0 0 0)
			(layer "F.Fab")
			(hide yes)
			(effects
				(font
					(size 1 1)
					(thickness 0.15)
				)
			)
		)
		(property "MPN" "CR0402-FX-1002GLF"
			(at 0 0 0)
			(layer "F.Fab")
			(hide yes)
			(effects
				(font
					(size 1 1)
					(thickness 0.15)
				)
			)
		)
		(property "Manufacturer" "Bourns"
			(at 0 0 0)
			(layer "F.Fab")
			(hide yes)
			(effects
				(font
					(size 1 1)
					(thickness 0.15)
				)
			)
		)
		(property "Tolerance" "1%"
			(at 0 0 0)
			(layer "F.Fab")
			(hide yes)
			(effects
				(font
					(size 1 1)
					(thickness 0.15)
				)
			)
		)
		(property "Val" "10k"
			(at 0 0 0)
			(layer "F.Fab")
			(hide yes)
			(effects
				(font
					(size 1 1)
					(thickness 0.15)
				)
			)
		)
		(sheetname "Supply")
		(sheetfile "supply.kicad_sch")
		(attr smd)
		(fp_rect
			(start -0.925 -0.47)
			(end 0.925 0.47)
			(stroke
				(width 0.05)
				(type default)
			)
			(fill none)
			(layer "F.CrtYd")
		)
		(fp_rect
			(start -0.5 -0.25)
			(end 0.5 0.25)
			(stroke
				(width 0.15)
				(type solid)
			)
			(fill none)
			(layer "F.Fab")
		)
		(fp_text user "Author: Antmicro"
			(at -0.95 4.169 0)
			(layer "F.Fab")
			(hide yes)
			(effects
				(font
					(size 0.7 0.7)
					(thickness 0.15)
				)
				(justify left bottom)
			)
		)
		(fp_text user "${REFERENCE}"
			(at -0.95 3.168 0)
			(layer "F.Fab")
			(hide yes)
			(effects
				(font
					(size 0.7 0.7)
					(thickness 0.15)
				)
				(justify left bottom)
			)
		)
		(fp_text user "License: Apache-2.0"
			(at -0.95 5.169 0)
			(layer "F.Fab")
			(hide yes)
			(effects
				(font
					(size 0.7 0.7)
					(thickness 0.15)
				)
				(justify left bottom)
			)
		)
		(pad "1" smd roundrect
			(at -0.48 0)
			(size 0.59 0.64)
			(layers "F.Cu" "F.Paste" "F.Mask")
			(roundrect_rratio 0.25)
			(net 1 "GND")
			(pintype "passive")
		)
		(pad "2" smd roundrect
			(at 0.48 0)
			(size 0.59 0.64)
			(layers "F.Cu" "F.Paste" "F.Mask")
			(roundrect_rratio 0.25)
			(net 766 "/Supply/5V_FB")
			(pintype "passive")
		)
	)
	(footprint "antmicro-footprints:R_0402_1005Metric"
		(layer "F.Cu")
		(at 114.4 90.4 180)
		(descr "Resistor SMD 0402")
		(tags "resistor SMD 0402")
		(property "Reference" "R32"
			(at -0.95 0.45 0)
			(layer "F.SilkS")
			(effects
				(font
					(size 0.7 0.7)
					(thickness 0.15)
				)
				(justify right bottom)
			)
		)
		(property "Value" "R_47k_0402"
			(at 0 1.4 0)
			(layer "F.Fab")
			(effects
				(font
					(size 0.7 0.7)
					(thickness 0.15)
				)
				(justify right bottom)
			)
		)
		(property "Footprint" "antmicro-footprints:R_0402_1005Metric"
			(at 0 0 180)
			(layer "F.Fab")
			(hide yes)
			(effects
				(font
					(size 1.27 1.27)
					(thickness 0.15)
				)
			)
		)
		(property "Datasheet" "https://www.bourns.com/docs/product-datasheets/cr.pdf"
			(at 0 0 180)
			(layer "F.Fab")
			(hide yes)
			(effects
				(font
					(size 1.27 1.27)
					(thickness 0.15)
				)
			)
		)
		(property "Author" "Antmicro"
			(at 228.8 180.8 0)
			(layer "F.Fab")
			(hide yes)
			(effects
				(font
					(size 1 1)
					(thickness 0.15)
				)
			)
		)
		(property "License" "Apache-2.0"
			(at 228.8 180.8 0)
			(layer "F.Fab")
			(hide yes)
			(effects
				(font
					(size 1 1)
					(thickness 0.15)
				)
			)
		)
		(property "MPN" "CR0402-FX-4702GLF"
			(at 228.8 180.8 0)
			(layer "F.Fab")
			(hide yes)
			(effects
				(font
					(size 1 1)
					(thickness 0.15)
				)
			)
		)
		(property "Manufacturer" "Bourns"
			(at 228.8 180.8 0)
			(layer "F.Fab")
			(hide yes)
			(effects
				(font
					(size 1 1)
					(thickness 0.15)
				)
			)
		)
		(property "Tolerance" "1%"
			(at 228.8 180.8 0)
			(layer "F.Fab")
			(hide yes)
			(effects
				(font
					(size 1 1)
					(thickness 0.15)
				)
			)
		)
		(property "Val" "47k"
			(at 228.8 180.8 0)
			(layer "F.Fab")
			(hide yes)
			(effects
				(font
					(size 1 1)
					(thickness 0.15)
				)
			)
		)
		(sheetname "M.2")
		(sheetfile "m-2.kicad_sch")
		(attr smd exclude_from_pos_files exclude_from_bom dnp)
		(fp_rect
			(start -0.925 -0.47)
			(end 0.925 0.47)
			(stroke
				(width 0.05)
				(type default)
			)
			(fill none)
			(layer "F.CrtYd")
		)
		(fp_rect
			(start -0.5 -0.25)
			(end 0.5 0.25)
			(stroke
				(width 0.15)
				(type solid)
			)
			(fill none)
			(layer "F.Fab")
		)
		(fp_text user "License: Apache-2.0"
			(at -0.95 5.169 0)
			(layer "F.Fab")
			(hide yes)
			(effects
				(font
					(size 0.7 0.7)
					(thickness 0.15)
				)
				(justify right bottom)
			)
		)
		(fp_text user "${REFERENCE}"
			(at -0.95 3.168 0)
			(layer "F.Fab")
			(hide yes)
			(effects
				(font
					(size 0.7 0.7)
					(thickness 0.15)
				)
				(justify right bottom)
			)
		)
		(fp_text user "Author: Antmicro"
			(at -0.95 4.169 0)
			(layer "F.Fab")
			(hide yes)
			(effects
				(font
					(size 0.7 0.7)
					(thickness 0.15)
				)
				(justify right bottom)
			)
		)
		(pad "1" smd roundrect
			(at -0.48 0 180)
			(size 0.59 0.64)
			(layers "F.Cu" "F.Paste" "F.Mask")
			(roundrect_rratio 0.25)
			(net 183 "/M.2/~{M2_E_UART_WAKE}")
			(pintype "passive")
		)
		(pad "2" smd roundrect
			(at 0.48 0 180)
			(size 0.59 0.64)
			(layers "F.Cu" "F.Paste" "F.Mask")
			(roundrect_rratio 0.25)
			(net 87 "+3V3")
			(pintype "passive")
		)
	)
	(footprint "antmicro-footprints:TSOT23-6"
		(layer "F.Cu")
		(at 67.77 115.5 -90)
		(property "Reference" "U12"
			(at 0.01 -2.54 90)
			(layer "F.SilkS")
			(effects
				(font
					(size 0.7 0.7)
					(thickness 0.15)
				)
				(justify right bottom)
			)
		)
		(property "Value" "AP22615A_TSOT26"
			(at 0 2.6 90)
			(layer "F.Fab")
			(effects
				(font
					(size 0.7 0.7)
					(thickness 0.15)
				)
				(justify right bottom)
			)
		)
		(property "Footprint" "antmicro-footprints:TSOT23-6"
			(at 0 0 -90)
			(layer "F.Fab")
			(hide yes)
			(effects
				(font
					(size 1.27 1.27)
					(thickness 0.15)
				)
			)
		)
		(property "Datasheet" "https://www.mouser.com/datasheet/2/115/DIOD_S_A0008958405_1-2543193.pdf"
			(at 0 0 -90)
			(layer "F.Fab")
			(hide yes)
			(effects
				(font
					(size 1.27 1.27)
					(thickness 0.15)
				)
			)
		)
		(property "Author" "Antmicro"
			(at -47.73 183.27 0)
			(layer "F.Fab")
			(hide yes)
			(effects
				(font
					(size 1 1)
					(thickness 0.15)
				)
			)
		)
		(property "License" "Apache-2.0"
			(at -47.73 183.27 0)
			(layer "F.Fab")
			(hide yes)
			(effects
				(font
					(size 1 1)
					(thickness 0.15)
				)
			)
		)
		(property "MPN" "AP22615AWU-7"
			(at -47.73 183.27 0)
			(layer "F.Fab")
			(hide yes)
			(effects
				(font
					(size 1 1)
					(thickness 0.15)
				)
			)
		)
		(property "Manufacturer" "Diodes Incorporated"
			(at -47.73 183.27 0)
			(layer "F.Fab")
			(hide yes)
			(effects
				(font
					(size 1 1)
					(thickness 0.15)
				)
			)
		)
		(sheetname "USB Debug, DP")
		(sheetfile "usb.kicad_sch")
		(attr smd)
		(fp_line
			(start -1 1.55)
			(end -1 1.4)
			(stroke
				(width 0.15)
				(type solid)
			)
			(layer "F.SilkS")
		)
		(fp_line
			(start 1 1.55)
			(end -1 1.55)
			(stroke
				(width 0.15)
				(type solid)
			)
			(layer "F.SilkS")
		)
		(fp_line
			(start 1 1.55)
			(end 1 1.4)
			(stroke
				(width 0.15)
				(type solid)
			)
			(layer "F.SilkS")
		)
		(fp_line
			(start 1 -1.497)
			(end 1 -1.375)
			(stroke
				(width 0.15)
				(type solid)
			)
			(layer "F.SilkS")
		)
		(fp_line
			(start 1 -1.497)
			(end -1 -1.5)
			(stroke
				(width 0.15)
				(type solid)
			)
			(layer "F.SilkS")
		)
		(fp_line
			(start -1 -1.5)
			(end -1 -1.375)
			(stroke
				(width 0.15)
				(type solid)
			)
			(layer "F.SilkS")
		)
		(fp_circle
			(center -1.44 -1.5)
			(end -1.39 -1.5)
			(stroke
				(width 0.15)
				(type solid)
			)
			(fill solid)
			(layer "F.SilkS")
		)
		(fp_rect
			(start 1.93 -1.7)
			(end -1.93 1.7)
			(stroke
				(width 0.05)
				(type solid)
			)
			(fill none)
			(layer "F.CrtYd")
		)
		(fp_line
			(start -0.45 -1.521)
			(end -0.876 -1.096)
			(stroke
				(width 0.15)
				(type solid)
			)
			(layer "F.Fab")
		)
		(fp_rect
			(start 0.875 1.528)
			(end -0.875 -1.525)
			(stroke
				(width 0.15)
				(type solid)
			)
			(fill none)
			(layer "F.Fab")
		)
		(fp_text user "Author: Antmicro"
			(at -1.93 5 90)
			(layer "F.Fab")
			(hide yes)
			(effects
				(font
					(size 0.7 0.7)
					(thickness 0.15)
				)
				(justify right bottom)
			)
		)
		(fp_text user "License: Apache-2.0"
			(at -1.93 6.199 90)
			(layer "F.Fab")
			(hide yes)
			(effects
				(font
					(size 0.7 0.7)
					(thickness 0.15)
				)
				(justify right bottom)
			)
		)
		(fp_text user "${REFERENCE}"
			(at -1.93 3.8 90)
			(layer "F.Fab")
			(hide yes)
			(effects
				(font
					(size 0.7 0.7)
					(thickness 0.15)
				)
				(justify right bottom)
			)
		)
		(pad "1" smd rect
			(at -1.301 -0.947 180)
			(size 0.7 1.2)
			(layers "F.Cu" "F.Paste" "F.Mask")
			(net 261 "/USB Debug, DP/USBC0_VBUS")
			(pinfunction "OUT")
			(pintype "power_out")
		)
		(pad "2" smd rect
			(at -1.301 0.004 180)
			(size 0.7 1.2)
			(layers "F.Cu" "F.Paste" "F.Mask")
			(net 1 "GND")
			(pinfunction "GND")
			(pintype "power_in")
		)
		(pad "3" smd rect
			(at -1.301 0.954 180)
			(size 0.7 1.2)
			(layers "F.Cu" "F.Paste" "F.Mask")
			(net 505 "USBC0_FLG")
			(pinfunction "FLG")
			(pintype "output")
		)
		(pad "4" smd rect
			(at 1.299 0.954 180)
			(size 0.7 1.2)
			(layers "F.Cu" "F.Paste" "F.Mask")
			(net 673 "Net-(U12-EN)")
			(pinfunction "EN")
			(pintype "input")
		)
		(pad "5" smd rect
			(at 1.299 0.004 180)
			(size 0.7 1.2)
			(layers "F.Cu" "F.Paste" "F.Mask")
			(net 682 "Net-(U12-ISET)")
			(pinfunction "ISET")
			(pintype "passive")
		)
		(pad "6" smd rect
			(at 1.299 -0.947 180)
			(size 0.7 1.2)
			(layers "F.Cu" "F.Paste" "F.Mask")
			(net 99 "+5V")
			(pinfunction "IN")
			(pintype "power_in")
		)
	)
	(footprint "antmicro-footprints:R_Array_4x0402"
		(layer "F.Cu")
		(at 139.25 105.6 90)
		(property "Reference" "R63"
			(at -1.05 -0.95 90)
			(layer "F.SilkS")
			(effects
				(font
					(size 0.7 0.7)
					(thickness 0.15)
				)
				(justify left bottom)
			)
		)
		(property "Value" "R_4x330R_0402_array"
			(at -1.5 2 90)
			(layer "F.Fab")
			(effects
				(font
					(size 0.7 0.7)
					(thickness 0.15)
				)
				(justify left bottom)
			)
		)
		(property "Footprint" "antmicro-footprints:R_Array_4x0402"
			(at 0 0 90)
			(layer "F.Fab")
			(hide yes)
			(effects
				(font
					(size 1.27 1.27)
					(thickness 0.15)
				)
			)
		)
		(property "Datasheet" "http://industrial.panasonic.com/cdbs/www-data/pdf/AOC0000/AOC0000C14.pdf"
			(at 0 0 90)
			(layer "F.Fab")
			(hide yes)
			(effects
				(font
					(size 1.27 1.27)
					(thickness 0.15)
				)
			)
		)
		(property "Author" "Antmicro"
			(at 244.85 -33.65 0)
			(layer "F.Fab")
			(hide yes)
			(effects
				(font
					(size 1 1)
					(thickness 0.15)
				)
			)
		)
		(property "License" "Apache-2.0"
			(at 244.85 -33.65 0)
			(layer "F.Fab")
			(hide yes)
			(effects
				(font
					(size 1 1)
					(thickness 0.15)
				)
			)
		)
		(property "MPN" "EXB-28V331JX"
			(at 244.85 -33.65 0)
			(layer "F.Fab")
			(hide yes)
			(effects
				(font
					(size 1 1)
					(thickness 0.15)
				)
			)
		)
		(property "Manufacturer" "Panasonic"
			(at 244.85 -33.65 0)
			(layer "F.Fab")
			(hide yes)
			(effects
				(font
					(size 1 1)
					(thickness 0.15)
				)
			)
		)
		(property "Val" "R_4x330R_0402"
			(at 244.85 -33.65 0)
			(layer "F.Fab")
			(hide yes)
			(effects
				(font
					(size 1 1)
					(thickness 0.15)
				)
			)
		)
		(sheetname "Peripherals")
		(sheetfile "peripherals.kicad_sch")
		(attr smd)
		(fp_line
			(start -1.17 -0.5)
			(end -1.17 0.498)
			(stroke
				(width 0.15)
				(type solid)
			)
			(layer "F.SilkS")
		)
		(fp_line
			(start 1.167 0.498)
			(end 1.167 -0.5)
			(stroke
				(width 0.15)
				(type solid)
			)
			(layer "F.SilkS")
		)
		(fp_rect
			(start -1.2 -0.9)
			(end 1.2 0.9)
			(stroke
				(width 0.05)
				(type solid)
			)
			(fill none)
			(layer "F.CrtYd")
		)
		(fp_line
			(start 0.998 -0.5)
			(end 0.998 0.498)
			(stroke
				(width 0.15)
				(type solid)
			)
			(layer "F.Fab")
		)
		(fp_line
			(start -1 -0.5)
			(end 0.998 -0.5)
			(stroke
				(width 0.15)
				(type solid)
			)
			(layer "F.Fab")
		)
		(fp_line
			(start 0.998 0.498)
			(end -1 0.498)
			(stroke
				(width 0.15)
				(type solid)
			)
			(layer "F.Fab")
		)
		(fp_line
			(start -1 0.498)
			(end -1 -0.5)
			(stroke
				(width 0.15)
				(type solid)
			)
			(layer "F.Fab")
		)
		(fp_text user "Author: Antmicro"
			(at -1.5 4.5 90)
			(layer "F.Fab")
			(hide yes)
			(effects
				(font
					(size 0.7 0.7)
					(thickness 0.15)
				)
				(justify left bottom)
			)
		)
		(fp_text user "License: Apache-2.0"
			(at -1.5 5.75 90)
			(layer "F.Fab")
			(hide yes)
			(effects
				(font
					(size 0.7 0.7)
					(thickness 0.15)
				)
				(justify left bottom)
			)
		)
		(fp_text user "${REFERENCE}"
			(at -1.5 3.25 90)
			(layer "F.Fab")
			(hide yes)
			(effects
				(font
					(size 0.7 0.7)
					(thickness 0.15)
				)
				(justify left bottom)
			)
		)
		(pad "1" smd roundrect
			(at -0.802 0.45 90)
			(size 0.4 0.5)
			(layers "F.Cu" "F.Paste" "F.Mask")
			(roundrect_rratio 0.25)
			(net 607 "/Peripherals/~{SPI0_CS1_CONN}")
			(pinfunction "R1.1")
			(pintype "passive")
		)
		(pad "2" smd roundrect
			(at -0.272 0.45 90)
			(size 0.4 0.5)
			(layers "F.Cu" "F.Paste" "F.Mask")
			(roundrect_rratio 0.25)
			(net 595 "/Peripherals/~{SPI0_CS0_CONN}")
			(pinfunction "R2.1")
			(pintype "passive")
		)
		(pad "3" smd roundrect
			(at 0.27 0.45 90)
			(size 0.4 0.5)
			(layers "F.Cu" "F.Paste" "F.Mask")
			(roundrect_rratio 0.25)
			(net 593 "/Peripherals/SPIO_MISO_CONN")
			(pinfunction "R3.1")
			(pintype "passive")
		)
		(pad "4" smd roundrect
			(at 0.8 0.45 90)
			(size 0.4 0.5)
			(layers "F.Cu" "F.Paste" "F.Mask")
			(roundrect_rratio 0.25)
			(net 655 "unconnected-(R63-R4.1-Pad4)")
			(pinfunction "R4.1")
			(pintype "passive+no_connect")
		)
		(pad "5" smd roundrect
			(at 0.8 -0.452 90)
			(size 0.4 0.5)
			(layers "F.Cu" "F.Paste" "F.Mask")
			(roundrect_rratio 0.25)
			(net 656 "unconnected-(R63-R4.2-Pad5)")
			(pinfunction "R4.2")
			(pintype "passive+no_connect")
		)
		(pad "6" smd roundrect
			(at 0.27 -0.452 90)
			(size 0.4 0.5)
			(layers "F.Cu" "F.Paste" "F.Mask")
			(roundrect_rratio 0.25)
			(net 32 "SPIO_MISO")
			(pinfunction "R3.2")
			(pintype "passive")
		)
		(pad "7" smd roundrect
			(at -0.272 -0.452 90)
			(size 0.4 0.5)
			(layers "F.Cu" "F.Paste" "F.Mask")
			(roundrect_rratio 0.25)
			(net 33 "~{SPI0_CS0}")
			(pinfunction "R2.2")
			(pintype "passive")
		)
		(pad "8" smd roundrect
			(at -0.802 -0.452 90)
			(size 0.4 0.5)
			(layers "F.Cu" "F.Paste" "F.Mask")
			(roundrect_rratio 0.25)
			(net 34 "~{SPI0_CS1}")
			(pinfunction "R1.2")
			(pintype "passive")
		)
	)
	(footprint "antmicro-footprints:LED_0603_1608Metric_G"
		(layer "F.Cu")
		(at 132 101.95 -90)
		(descr "LED SMD 0603 Green")
		(tags "LED SMD 0603 Green")
		(property "Reference" "D1"
			(at -1.2 -0.5 -90)
			(layer "F.SilkS")
			(effects
				(font
					(size 0.7 0.7)
					(thickness 0.15)
				)
				(justify left bottom)
			)
		)
		(property "Value" "LED_G_0603_LTST-C190GKT"
			(at -0.001 1.599 -90)
			(layer "F.Fab")
			(effects
				(font
					(size 0.7 0.7)
					(thickness 0.15)
				)
				(justify left bottom)
			)
		)
		(property "Footprint" "antmicro-footprints:LED_0603_1608Metric_G"
			(at 0 0 -90)
			(layer "F.Fab")
			(hide yes)
			(effects
				(font
					(size 1.27 1.27)
					(thickness 0.15)
				)
			)
		)
		(property "Datasheet" "https://media.digikey.com/pdf/Data%20Sheets/Lite-On%20PDFs/LTST-C190GKT.pdf"
			(at 0 0 -90)
			(layer "F.Fab")
			(hide yes)
			(effects
				(font
					(size 1.27 1.27)
					(thickness 0.15)
				)
			)
		)
		(property "Author" "Antmicro"
			(at 30.05 233.95 0)
			(layer "F.Fab")
			(hide yes)
			(effects
				(font
					(size 1 1)
					(thickness 0.15)
				)
			)
		)
		(property "Color" "Green"
			(at 30.05 233.95 0)
			(layer "F.Fab")
			(hide yes)
			(effects
				(font
					(size 1 1)
					(thickness 0.15)
				)
			)
		)
		(property "License" "Apache-2.0"
			(at 30.05 233.95 0)
			(layer "F.Fab")
			(hide yes)
			(effects
				(font
					(size 1 1)
					(thickness 0.15)
				)
			)
		)
		(property "MPN" "LTST-C190GKT"
			(at 30.05 233.95 0)
			(layer "F.Fab")
			(hide yes)
			(effects
				(font
					(size 1 1)
					(thickness 0.15)
				)
			)
		)
		(property "Manufacturer" "Lite-On"
			(at 30.05 233.95 0)
			(layer "F.Fab")
			(hide yes)
			(effects
				(font
					(size 1 1)
					(thickness 0.15)
				)
			)
		)
		(sheetname "M.2")
		(sheetfile "m-2.kicad_sch")
		(attr smd)
		(fp_line
			(start 0.22 0.35)
			(end -0.22 0.35)
			(stroke
				(width 0.15)
				(type solid)
			)
			(layer "F.SilkS")
		)
		(fp_line
			(start -0.094672 0.201008)
			(end -0.094672 -0.198992)
			(stroke
				(width 0.1)
				(type solid)
			)
			(layer "F.SilkS")
		)
		(fp_line
			(start 0.105328 0.201008)
			(end -0.094672 0.001008)
			(stroke
				(width 0.1)
				(type solid)
			)
			(layer "F.SilkS")
		)
		(fp_line
			(start 0.105328 0.201008)
			(end 0.105328 -0.198992)
			(stroke
				(width 0.1)
				(type solid)
			)
			(layer "F.SilkS")
		)
		(fp_line
			(start -0.094672 0.001008)
			(end -0.24 0.001008)
			(stroke
				(width 0.1)
				(type solid)
			)
			(layer "F.SilkS")
		)
		(fp_line
			(start -0.094672 0.001008)
			(end 0.105328 -0.198992)
			(stroke
				(width 0.1)
				(type solid)
			)
			(layer "F.SilkS")
		)
		(fp_line
			(start 0.105328 0.001008)
			(end 0.24 0.001)
			(stroke
				(width 0.1)
				(type solid)
			)
			(layer "F.SilkS")
		)
		(fp_line
			(start -1.18 -0.319)
			(end -1.18 0.321)
			(stroke
				(width 0.15)
				(type solid)
			)
			(layer "F.SilkS")
		)
		(fp_line
			(start 0.22 -0.35)
			(end -0.22 -0.35)
			(stroke
				(width 0.15)
				(type solid)
			)
			(layer "F.SilkS")
		)
		(fp_rect
			(start 1.25 0.65)
			(end -1.25 -0.65)
			(stroke
				(width 0.05)
				(type solid)
			)
			(fill none)
			(layer "F.CrtYd")
		)
		(fp_line
			(start -0.199 0.2)
			(end -0.199 0.1)
			(stroke
				(width 0.15)
				(type solid)
			)
			(layer "F.Fab")
		)
		(fp_line
			(start 0.201 0.2)
			(end 0.201 0)
			(stroke
				(width 0.15)
				(type solid)
			)
			(layer "F.Fab")
		)
		(fp_line
			(start -0.199 0)
			(end -0.597 0)
			(stroke
				(width 0.15)
				(type solid)
			)
			(layer "F.Fab")
		)
		(fp_line
			(start -0.101 0)
			(end 0.201 0.2)
			(stroke
				(width 0.15)
				(type solid)
			)
			(layer "F.Fab")
		)
		(fp_line
			(start 0.201 0)
			(end 0.201 -0.202)
			(stroke
				(width 0.15)
				(type solid)
			)
			(layer "F.Fab")
		)
		(fp_line
			(start 0.599 0)
			(end 0.201 0)
			(stroke
				(width 0.15)
				(type solid)
			)
			(layer "F.Fab")
		)
		(fp_line
			(start -0.199 -0.202)
			(end -0.199 0.1)
			(stroke
				(width 0.15)
				(type solid)
			)
			(layer "F.Fab")
		)
		(fp_line
			(start 0.201 -0.202)
			(end -0.101 0)
			(stroke
				(width 0.15)
				(type solid)
			)
			(layer "F.Fab")
		)
		(fp_rect
			(start 0.848 0.4)
			(end -0.85 -0.402)
			(stroke
				(width 0.15)
				(type solid)
			)
			(fill none)
			(layer "F.Fab")
		)
		(fp_text user "${REFERENCE}"
			(at -1.4224 5.999 -90)
			(layer "F.Fab")
			(hide yes)
			(effects
				(font
					(size 0.7 0.7)
					(thickness 0.15)
				)
				(justify left bottom)
			)
		)
		(fp_text user "Author: Antmicro"
			(at -1.4224 4.799 -90)
			(layer "F.Fab")
			(hide yes)
			(effects
				(font
					(size 0.7 0.7)
					(thickness 0.15)
				)
				(justify left bottom)
			)
		)
		(fp_text user "License: Apache-2.0"
			(at -1.4224 3.599 -90)
			(layer "F.Fab")
			(hide yes)
			(effects
				(font
					(size 0.7 0.7)
					(thickness 0.15)
				)
				(justify left bottom)
			)
		)
		(pad "1" smd roundrect
			(at -0.7 0 90)
			(size 0.8 1)
			(layers "F.Cu" "F.Paste" "F.Mask")
			(roundrect_rratio 0.2)
			(net 140 "Net-(D1-C)")
			(pinfunction "C")
			(pintype "passive")
		)
		(pad "2" smd roundrect
			(at 0.7 0 90)
			(size 0.8 1)
			(layers "F.Cu" "F.Paste" "F.Mask")
			(roundrect_rratio 0.2)
			(net 141 "Net-(D1-A)")
			(pinfunction "A")
			(pintype "passive")
		)
	)
	(footprint "antmicro-footprints:SW_KMR211NGLFS_SMD"
		(layer "F.Cu")
		(at 104 125.9)
		(property "Reference" "S1"
			(at -3.78 -1.57 0)
			(layer "F.SilkS")
			(effects
				(font
					(size 0.7 0.7)
					(thickness 0.15)
				)
				(justify left bottom)
			)
		)
		(property "Value" "SW_KMR211NGLFS_SMD"
			(at -3 3 0)
			(layer "F.Fab")
			(effects
				(font
					(size 0.7 0.7)
					(thickness 0.15)
				)
				(justify left bottom)
			)
		)
		(property "Footprint" "antmicro-footprints:SW_KMR211NGLFS_SMD"
			(at 0 0 0)
			(layer "F.Fab")
			(hide yes)
			(effects
				(font
					(size 1.27 1.27)
					(thickness 0.15)
				)
			)
		)
		(property "Datasheet" "http://www.farnell.com/datasheets/2631211.pdf"
			(at 0 0 0)
			(layer "F.Fab")
			(hide yes)
			(effects
				(font
					(size 1.27 1.27)
					(thickness 0.15)
				)
			)
		)
		(property "Author" "Antmicro"
			(at 0 0 0)
			(layer "F.Fab")
			(hide yes)
			(effects
				(font
					(size 1 1)
					(thickness 0.15)
				)
			)
		)
		(property "License" "Apache-2.0"
			(at 0 0 0)
			(layer "F.Fab")
			(hide yes)
			(effects
				(font
					(size 1 1)
					(thickness 0.15)
				)
			)
		)
		(property "MPN" "KMR211NGLFS"
			(at 0 0 0)
			(layer "F.Fab")
			(hide yes)
			(effects
				(font
					(size 1 1)
					(thickness 0.15)
				)
			)
		)
		(property "Manufacturer" "C&K"
			(at 0 0 0)
			(layer "F.Fab")
			(hide yes)
			(effects
				(font
					(size 1 1)
					(thickness 0.15)
				)
			)
		)
		(sheetname "SoM")
		(sheetfile "som.kicad_sch")
		(attr smd)
		(fp_line
			(start -2.1 -1.6)
			(end -2.1 -1.499)
			(stroke
				(width 0.15)
				(type solid)
			)
			(layer "F.SilkS")
		)
		(fp_line
			(start -2.1 1.601)
			(end -2.1 1.48)
			(stroke
				(width 0.15)
				(type solid)
			)
			(layer "F.SilkS")
		)
		(fp_line
			(start 2.101 -1.6)
			(end -2.1 -1.6)
			(stroke
				(width 0.15)
				(type solid)
			)
			(layer "F.SilkS")
		)
		(fp_line
			(start 2.101 -1.58)
			(end 2.101 -1.459)
			(stroke
				(width 0.15)
				(type solid)
			)
			(layer "F.SilkS")
		)
		(fp_line
			(start 2.101 1.601)
			(end -2.1 1.601)
			(stroke
				(width 0.15)
				(type solid)
			)
			(layer "F.SilkS")
		)
		(fp_line
			(start 2.101 1.601)
			(end 2.101 1.48)
			(stroke
				(width 0.15)
				(type solid)
			)
			(layer "F.SilkS")
		)
		(fp_rect
			(start 2.751 1.75)
			(end -2.748 -1.749)
			(stroke
				(width 0.05)
				(type solid)
			)
			(fill none)
			(layer "F.CrtYd")
		)
		(fp_line
			(start -2.1 -1.6)
			(end -2.1 1.601)
			(stroke
				(width 0.15)
				(type solid)
			)
			(layer "F.Fab")
		)
		(fp_line
			(start -2.1 1.601)
			(end 2.101 1.601)
			(stroke
				(width 0.15)
				(type solid)
			)
			(layer "F.Fab")
		)
		(fp_line
			(start -0.248 -0.8)
			(end 0.25 -0.8)
			(stroke
				(width 0.15)
				(type solid)
			)
			(layer "F.Fab")
		)
		(fp_line
			(start 0.25 0.802)
			(end -0.248 0.802)
			(stroke
				(width 0.15)
				(type solid)
			)
			(layer "F.Fab")
		)
		(fp_line
			(start 2.101 -1.6)
			(end -2.1 -1.6)
			(stroke
				(width 0.15)
				(type solid)
			)
			(layer "F.Fab")
		)
		(fp_line
			(start 2.101 1.601)
			(end 2.101 -1.6)
			(stroke
				(width 0.15)
				(type solid)
			)
			(layer "F.Fab")
		)
		(fp_arc
			(start -0.248 0.802)
			(mid -1.050001 0.001)
			(end -0.248 -0.8)
			(stroke
				(width 0.15)
				(type solid)
			)
			(layer "F.Fab")
		)
		(fp_arc
			(start 0.25 -0.8)
			(mid 1.051001 0.001)
			(end 0.25 0.802)
			(stroke
				(width 0.15)
				(type solid)
			)
			(layer "F.Fab")
		)
		(fp_text user "${REFERENCE}"
			(at -3 4.25 0)
			(layer "F.Fab")
			(hide yes)
			(effects
				(font
					(size 0.7 0.7)
					(thickness 0.15)
				)
				(justify left bottom)
			)
		)
		(fp_text user "Author: Antmicro"
			(at -3 5.5 0)
			(layer "F.Fab")
			(hide yes)
			(effects
				(font
					(size 0.7 0.7)
					(thickness 0.15)
				)
				(justify left bottom)
			)
		)
		(fp_text user "License: Apache-2.0"
			(at -3 6.75 0)
			(layer "F.Fab")
			(hide yes)
			(effects
				(font
					(size 0.7 0.7)
					(thickness 0.15)
				)
				(justify left bottom)
			)
		)
		(pad "1" smd rect
			(at -2.048 -0.8 180)
			(size 0.9 1)
			(layers "F.Cu" "F.Paste" "F.Mask")
			(net 80 "/SoM/~{FORCE_RECOVERY}")
			(pinfunction "1")
			(pintype "passive")
		)
		(pad "2" smd rect
			(at 2.05 -0.8 180)
			(size 0.9 1)
			(layers "F.Cu" "F.Paste" "F.Mask")
			(net 80 "/SoM/~{FORCE_RECOVERY}")
			(pinfunction "2")
			(pintype "passive")
		)
		(pad "3" smd rect
			(at -2.048 0.802 180)
			(size 0.9 1)
			(layers "F.Cu" "F.Paste" "F.Mask")
			(net 1 "GND")
			(pinfunction "3")
			(pintype "passive")
		)
		(pad "4" smd rect
			(at 2.05 0.802 180)
			(size 0.9 1)
			(layers "F.Cu" "F.Paste" "F.Mask")
			(net 1 "GND")
			(pinfunction "4")
			(pintype "passive")
		)
	)
	(footprint "antmicro-footprints:SW_KMR211NGLFS_SMD"
		(layer "F.Cu")
		(at 83.9 125.9)
		(property "Reference" "S5"
			(at 0.55 -1.73 0)
			(layer "F.SilkS")
			(effects
				(font
					(size 0.7 0.7)
					(thickness 0.15)
				)
				(justify left bottom)
			)
		)
		(property "Value" "SW_KMR211NGLFS_SMD"
			(at -3 3 0)
			(layer "F.Fab")
			(effects
				(font
					(size 0.7 0.7)
					(thickness 0.15)
				)
				(justify left bottom)
			)
		)
		(property "Footprint" "antmicro-footprints:SW_KMR211NGLFS_SMD"
			(at 0 0 0)
			(layer "F.Fab")
			(hide yes)
			(effects
				(font
					(size 1.27 1.27)
					(thickness 0.15)
				)
			)
		)
		(property "Datasheet" "http://www.farnell.com/datasheets/2631211.pdf"
			(at 0 0 0)
			(layer "F.Fab")
			(hide yes)
			(effects
				(font
					(size 1.27 1.27)
					(thickness 0.15)
				)
			)
		)
		(property "Author" "Antmicro"
			(at 0 0 0)
			(layer "F.Fab")
			(hide yes)
			(effects
				(font
					(size 1 1)
					(thickness 0.15)
				)
			)
		)
		(property "License" "Apache-2.0"
			(at 0 0 0)
			(layer "F.Fab")
			(hide yes)
			(effects
				(font
					(size 1 1)
					(thickness 0.15)
				)
			)
		)
		(property "MPN" "KMR211NGLFS"
			(at 0 0 0)
			(layer "F.Fab")
			(hide yes)
			(effects
				(font
					(size 1 1)
					(thickness 0.15)
				)
			)
		)
		(property "Manufacturer" "C&K"
			(at 0 0 0)
			(layer "F.Fab")
			(hide yes)
			(effects
				(font
					(size 1 1)
					(thickness 0.15)
				)
			)
		)
		(sheetname "Supply")
		(sheetfile "supply.kicad_sch")
		(attr smd)
		(fp_line
			(start -2.1 -1.6)
			(end -2.1 -1.499)
			(stroke
				(width 0.15)
				(type solid)
			)
			(layer "F.SilkS")
		)
		(fp_line
			(start -2.1 1.601)
			(end -2.1 1.48)
			(stroke
				(width 0.15)
				(type solid)
			)
			(layer "F.SilkS")
		)
		(fp_line
			(start 2.101 -1.6)
			(end -2.1 -1.6)
			(stroke
				(width 0.15)
				(type solid)
			)
			(layer "F.SilkS")
		)
		(fp_line
			(start 2.101 -1.58)
			(end 2.101 -1.459)
			(stroke
				(width 0.15)
				(type solid)
			)
			(layer "F.SilkS")
		)
		(fp_line
			(start 2.101 1.601)
			(end -2.1 1.601)
			(stroke
				(width 0.15)
				(type solid)
			)
			(layer "F.SilkS")
		)
		(fp_line
			(start 2.101 1.601)
			(end 2.101 1.48)
			(stroke
				(width 0.15)
				(type solid)
			)
			(layer "F.SilkS")
		)
		(fp_rect
			(start 2.751 1.75)
			(end -2.748 -1.749)
			(stroke
				(width 0.05)
				(type solid)
			)
			(fill none)
			(layer "F.CrtYd")
		)
		(fp_line
			(start -2.1 -1.6)
			(end -2.1 1.601)
			(stroke
				(width 0.15)
				(type solid)
			)
			(layer "F.Fab")
		)
		(fp_line
			(start -2.1 1.601)
			(end 2.101 1.601)
			(stroke
				(width 0.15)
				(type solid)
			)
			(layer "F.Fab")
		)
		(fp_line
			(start -0.248 -0.8)
			(end 0.25 -0.8)
			(stroke
				(width 0.15)
				(type solid)
			)
			(layer "F.Fab")
		)
		(fp_line
			(start 0.25 0.802)
			(end -0.248 0.802)
			(stroke
				(width 0.15)
				(type solid)
			)
			(layer "F.Fab")
		)
		(fp_line
			(start 2.101 -1.6)
			(end -2.1 -1.6)
			(stroke
				(width 0.15)
				(type solid)
			)
			(layer "F.Fab")
		)
		(fp_line
			(start 2.101 1.601)
			(end 2.101 -1.6)
			(stroke
				(width 0.15)
				(type solid)
			)
			(layer "F.Fab")
		)
		(fp_arc
			(start -0.248 0.802)
			(mid -1.050001 0.001)
			(end -0.248 -0.8)
			(stroke
				(width 0.15)
				(type solid)
			)
			(layer "F.Fab")
		)
		(fp_arc
			(start 0.25 -0.8)
			(mid 1.051001 0.001)
			(end 0.25 0.802)
			(stroke
				(width 0.15)
				(type solid)
			)
			(layer "F.Fab")
		)
		(fp_text user "Author: Antmicro"
			(at -3 5.5 0)
			(layer "F.Fab")
			(hide yes)
			(effects
				(font
					(size 0.7 0.7)
					(thickness 0.15)
				)
				(justify left bottom)
			)
		)
		(fp_text user "${REFERENCE}"
			(at -3 4.25 0)
			(layer "F.Fab")
			(hide yes)
			(effects
				(font
					(size 0.7 0.7)
					(thickness 0.15)
				)
				(justify left bottom)
			)
		)
		(fp_text user "License: Apache-2.0"
			(at -3 6.75 0)
			(layer "F.Fab")
			(hide yes)
			(effects
				(font
					(size 0.7 0.7)
					(thickness 0.15)
				)
				(justify left bottom)
			)
		)
		(pad "1" smd rect
			(at -2.048 -0.8 180)
			(size 0.9 1)
			(layers "F.Cu" "F.Paste" "F.Mask")
			(net 117 "3V3_STDB")
			(pinfunction "1")
			(pintype "passive")
		)
		(pad "2" smd rect
			(at 2.05 -0.8 180)
			(size 0.9 1)
			(layers "F.Cu" "F.Paste" "F.Mask")
			(net 117 "3V3_STDB")
			(pinfunction "2")
			(pintype "passive")
		)
		(pad "3" smd rect
			(at -2.048 0.802 180)
			(size 0.9 1)
			(layers "F.Cu" "F.Paste" "F.Mask")
			(net 179 "Net-(D61-A)")
			(pinfunction "3")
			(pintype "passive")
		)
		(pad "4" smd rect
			(at 2.05 0.802 180)
			(size 0.9 1)
			(layers "F.Cu" "F.Paste" "F.Mask")
			(net 179 "Net-(D61-A)")
			(pinfunction "4")
			(pintype "passive")
		)
	)
	(footprint "antmicro-footprints:C_0402_1005Metric"
		(layer "F.Cu")
		(at 63.31 100.52 180)
		(descr "Capacitor SMD 0402")
		(tags "capacitor SMD 0402")
		(property "Reference" "C93"
			(at -5.84 -3.555 0)
			(layer "F.SilkS")
			(effects
				(font
					(size 0.7 0.7)
					(thickness 0.15)
				)
				(justify right bottom)
			)
		)
		(property "Value" "C_1u_0402"
			(at -1.022927 2.155213 0)
			(layer "F.Fab")
			(effects
				(font
					(size 0.7 0.7)
					(thickness 0.15)
				)
				(justify right bottom)
			)
		)
		(property "Footprint" "antmicro-footprints:C_0402_1005Metric"
			(at 0 0 180)
			(layer "F.Fab")
			(hide yes)
			(effects
				(font
					(size 1.27 1.27)
					(thickness 0.15)
				)
			)
		)
		(property "Datasheet" "https://product.tdk.com/en/search/capacitor/ceramic/mlcc/info?part_no=C1005X6S1A105K050BC"
			(at 0 0 180)
			(layer "F.Fab")
			(hide yes)
			(effects
				(font
					(size 1.27 1.27)
					(thickness 0.15)
				)
			)
		)
		(property "Author" "Antmicro"
			(at 126.62 201.04 0)
			(layer "F.Fab")
			(hide yes)
			(effects
				(font
					(size 1 1)
					(thickness 0.15)
				)
			)
		)
		(property "Dielectric" ""
			(at 126.62 201.04 0)
			(layer "F.Fab")
			(hide yes)
			(effects
				(font
					(size 1 1)
					(thickness 0.15)
				)
			)
		)
		(property "License" "Apache-2.0"
			(at 126.62 201.04 0)
			(layer "F.Fab")
			(hide yes)
			(effects
				(font
					(size 1 1)
					(thickness 0.15)
				)
			)
		)
		(property "MPN" "C1005X6S1A105K050BC"
			(at 126.62 201.04 0)
			(layer "F.Fab")
			(hide yes)
			(effects
				(font
					(size 1 1)
					(thickness 0.15)
				)
			)
		)
		(property "Manufacturer" "TDK"
			(at 126.62 201.04 0)
			(layer "F.Fab")
			(hide yes)
			(effects
				(font
					(size 1 1)
					(thickness 0.15)
				)
			)
		)
		(property "Val" "1u"
			(at 126.62 201.04 0)
			(layer "F.Fab")
			(hide yes)
			(effects
				(font
					(size 1 1)
					(thickness 0.15)
				)
			)
		)
		(property "Voltage" ""
			(at 126.62 201.04 0)
			(layer "F.Fab")
			(hide yes)
			(effects
				(font
					(size 1 1)
					(thickness 0.15)
				)
			)
		)
		(sheetname "Supply")
		(sheetfile "supply.kicad_sch")
		(attr smd)
		(fp_rect
			(start -0.925 -0.47)
			(end 0.925 0.47)
			(stroke
				(width 0.05)
				(type default)
			)
			(fill none)
			(layer "F.CrtYd")
		)
		(fp_line
			(start 0.504 0.248)
			(end -0.494 0.248)
			(stroke
				(width 0.15)
				(type solid)
			)
			(layer "F.Fab")
		)
		(fp_line
			(start 0.504 -0.25)
			(end 0.504 0.248)
			(stroke
				(width 0.15)
				(type solid)
			)
			(layer "F.Fab")
		)
		(fp_line
			(start -0.494 0.248)
			(end -0.494 -0.25)
			(stroke
				(width 0.15)
				(type solid)
			)
			(layer "F.Fab")
		)
		(fp_line
			(start -0.494 -0.25)
			(end 0.504 -0.25)
			(stroke
				(width 0.15)
				(type solid)
			)
			(layer "F.Fab")
		)
		(fp_text user "License: Apache-2.0"
			(at -0.939 5.799 0)
			(layer "F.Fab")
			(hide yes)
			(effects
				(font
					(size 0.7 0.7)
					(thickness 0.15)
				)
				(justify right bottom)
			)
		)
		(fp_text user "Author: Antmicro"
			(at -0.939 3.399 0)
			(layer "F.Fab")
			(hide yes)
			(effects
				(font
					(size 0.7 0.7)
					(thickness 0.15)
				)
				(justify right bottom)
			)
		)
		(fp_text user "${REFERENCE}"
			(at -0.939 4.599 0)
			(layer "F.Fab")
			(hide yes)
			(effects
				(font
					(size 0.7 0.7)
					(thickness 0.15)
				)
				(justify right bottom)
			)
		)
		(pad "1" smd roundrect
			(at -0.48 0 180)
			(size 0.59 0.64)
			(layers "F.Cu" "F.Paste" "F.Mask")
			(roundrect_rratio 0.25)
			(net 1 "GND")
			(pintype "passive")
		)
		(pad "2" smd roundrect
			(at 0.48 0 180)
			(size 0.59 0.64)
			(layers "F.Cu" "F.Paste" "F.Mask")
			(roundrect_rratio 0.25)
			(net 759 "/Supply/5V_VDD")
			(pintype "passive")
		)
	)
	(footprint "antmicro-footprints:LED_0603_1608Metric_G"
		(layer "F.Cu")
		(at 130.55 101.95 -90)
		(descr "LED SMD 0603 Green")
		(tags "LED SMD 0603 Green")
		(property "Reference" "D52"
			(at -3.4 -0.45 90)
			(layer "F.SilkS")
			(effects
				(font
					(size 0.7 0.7)
					(thickness 0.15)
				)
				(justify right bottom)
			)
		)
		(property "Value" "LED_G_0603_LTST-C190GKT"
			(at -0.001 1.599 90)
			(layer "F.Fab")
			(effects
				(font
					(size 0.7 0.7)
					(thickness 0.15)
				)
				(justify right bottom)
			)
		)
		(property "Footprint" "antmicro-footprints:LED_0603_1608Metric_G"
			(at 0 0 -90)
			(layer "F.Fab")
			(hide yes)
			(effects
				(font
					(size 1.27 1.27)
					(thickness 0.15)
				)
			)
		)
		(property "Datasheet" "https://media.digikey.com/pdf/Data%20Sheets/Lite-On%20PDFs/LTST-C190GKT.pdf"
			(at 0 0 -90)
			(layer "F.Fab")
			(hide yes)
			(effects
				(font
					(size 1.27 1.27)
					(thickness 0.15)
				)
			)
		)
		(property "Author" "Antmicro"
			(at 28.6 232.5 0)
			(layer "F.Fab")
			(hide yes)
			(effects
				(font
					(size 1 1)
					(thickness 0.15)
				)
			)
		)
		(property "Color" "Green"
			(at 28.6 232.5 0)
			(layer "F.Fab")
			(hide yes)
			(effects
				(font
					(size 1 1)
					(thickness 0.15)
				)
			)
		)
		(property "License" "Apache-2.0"
			(at 28.6 232.5 0)
			(layer "F.Fab")
			(hide yes)
			(effects
				(font
					(size 1 1)
					(thickness 0.15)
				)
			)
		)
		(property "MPN" "LTST-C190GKT"
			(at 28.6 232.5 0)
			(layer "F.Fab")
			(hide yes)
			(effects
				(font
					(size 1 1)
					(thickness 0.15)
				)
			)
		)
		(property "Manufacturer" "Lite-On"
			(at 28.6 232.5 0)
			(layer "F.Fab")
			(hide yes)
			(effects
				(font
					(size 1 1)
					(thickness 0.15)
				)
			)
		)
		(sheetname "M.2")
		(sheetfile "m-2.kicad_sch")
		(attr smd)
		(fp_line
			(start 0.22 0.35)
			(end -0.22 0.35)
			(stroke
				(width 0.15)
				(type solid)
			)
			(layer "F.SilkS")
		)
		(fp_line
			(start -0.094672 0.201008)
			(end -0.094672 -0.198992)
			(stroke
				(width 0.1)
				(type solid)
			)
			(layer "F.SilkS")
		)
		(fp_line
			(start 0.105328 0.201008)
			(end -0.094672 0.001008)
			(stroke
				(width 0.1)
				(type solid)
			)
			(layer "F.SilkS")
		)
		(fp_line
			(start 0.105328 0.201008)
			(end 0.105328 -0.198992)
			(stroke
				(width 0.1)
				(type solid)
			)
			(layer "F.SilkS")
		)
		(fp_line
			(start -0.094672 0.001008)
			(end -0.24 0.001008)
			(stroke
				(width 0.1)
				(type solid)
			)
			(layer "F.SilkS")
		)
		(fp_line
			(start -0.094672 0.001008)
			(end 0.105328 -0.198992)
			(stroke
				(width 0.1)
				(type solid)
			)
			(layer "F.SilkS")
		)
		(fp_line
			(start 0.105328 0.001008)
			(end 0.24 0.001)
			(stroke
				(width 0.1)
				(type solid)
			)
			(layer "F.SilkS")
		)
		(fp_line
			(start -1.18 -0.319)
			(end -1.18 0.321)
			(stroke
				(width 0.15)
				(type solid)
			)
			(layer "F.SilkS")
		)
		(fp_line
			(start 0.22 -0.35)
			(end -0.22 -0.35)
			(stroke
				(width 0.15)
				(type solid)
			)
			(layer "F.SilkS")
		)
		(fp_rect
			(start 1.25 0.65)
			(end -1.25 -0.65)
			(stroke
				(width 0.05)
				(type solid)
			)
			(fill none)
			(layer "F.CrtYd")
		)
		(fp_line
			(start -0.199 0.2)
			(end -0.199 0.1)
			(stroke
				(width 0.15)
				(type solid)
			)
			(layer "F.Fab")
		)
		(fp_line
			(start 0.201 0.2)
			(end 0.201 0)
			(stroke
				(width 0.15)
				(type solid)
			)
			(layer "F.Fab")
		)
		(fp_line
			(start -0.199 0)
			(end -0.597 0)
			(stroke
				(width 0.15)
				(type solid)
			)
			(layer "F.Fab")
		)
		(fp_line
			(start -0.101 0)
			(end 0.201 0.2)
			(stroke
				(width 0.15)
				(type solid)
			)
			(layer "F.Fab")
		)
		(fp_line
			(start 0.201 0)
			(end 0.201 -0.202)
			(stroke
				(width 0.15)
				(type solid)
			)
			(layer "F.Fab")
		)
		(fp_line
			(start 0.599 0)
			(end 0.201 0)
			(stroke
				(width 0.15)
				(type solid)
			)
			(layer "F.Fab")
		)
		(fp_line
			(start -0.199 -0.202)
			(end -0.199 0.1)
			(stroke
				(width 0.15)
				(type solid)
			)
			(layer "F.Fab")
		)
		(fp_line
			(start 0.201 -0.202)
			(end -0.101 0)
			(stroke
				(width 0.15)
				(type solid)
			)
			(layer "F.Fab")
		)
		(fp_rect
			(start 0.848 0.4)
			(end -0.85 -0.402)
			(stroke
				(width 0.15)
				(type solid)
			)
			(fill none)
			(layer "F.Fab")
		)
		(fp_text user "Author: Antmicro"
			(at -1.4224 4.799 90)
			(layer "F.Fab")
			(hide yes)
			(effects
				(font
					(size 0.7 0.7)
					(thickness 0.15)
				)
				(justify right bottom)
			)
		)
		(fp_text user "${REFERENCE}"
			(at -1.4224 5.999 90)
			(layer "F.Fab")
			(hide yes)
			(effects
				(font
					(size 0.7 0.7)
					(thickness 0.15)
				)
				(justify right bottom)
			)
		)
		(fp_text user "License: Apache-2.0"
			(at -1.4224 3.599 90)
			(layer "F.Fab")
			(hide yes)
			(effects
				(font
					(size 0.7 0.7)
					(thickness 0.15)
				)
				(justify right bottom)
			)
		)
		(pad "1" smd roundrect
			(at -0.7 0 90)
			(size 0.8 1)
			(layers "F.Cu" "F.Paste" "F.Mask")
			(roundrect_rratio 0.2)
			(net 652 "/M.2/~{LED2}")
			(pinfunction "C")
			(pintype "passive")
		)
		(pad "2" smd roundrect
			(at 0.7 0 90)
			(size 0.8 1)
			(layers "F.Cu" "F.Paste" "F.Mask")
			(roundrect_rratio 0.2)
			(net 653 "Net-(D52-A)")
			(pinfunction "A")
			(pintype "passive")
		)
	)
	(footprint "antmicro-footprints:MLP44-24L_4x4x0.75mm"
		(layer "F.Cu")
		(at 62.67 97.435 -90)
		(property "Reference" "U1"
			(at 1.015 -4.02 0)
			(layer "F.SilkS")
			(effects
				(font
					(size 0.7 0.7)
					(thickness 0.15)
				)
				(justify left bottom)
			)
		)
		(property "Value" "SIC431AED-T1-GE3"
			(at 0 3.6 90)
			(layer "F.Fab")
			(effects
				(font
					(size 0.7 0.7)
					(thickness 0.15)
				)
				(justify right bottom)
			)
		)
		(property "Footprint" "antmicro-footprints:MLP44-24L_4x4x0.75mm"
			(at 0 0 -90)
			(layer "F.Fab")
			(hide yes)
			(effects
				(font
					(size 1.27 1.27)
					(thickness 0.15)
				)
			)
		)
		(property "Datasheet" "https://www.vishay.com/docs/74589/sic431.pdf"
			(at 0 0 -90)
			(layer "F.Fab")
			(hide yes)
			(effects
				(font
					(size 1.27 1.27)
					(thickness 0.15)
				)
			)
		)
		(property "Author" "Antmicro"
			(at -34.765 160.105 0)
			(layer "F.Fab")
			(hide yes)
			(effects
				(font
					(size 1 1)
					(thickness 0.15)
				)
			)
		)
		(property "License" "Apache-2.0"
			(at -34.765 160.105 0)
			(layer "F.Fab")
			(hide yes)
			(effects
				(font
					(size 1 1)
					(thickness 0.15)
				)
			)
		)
		(property "MPN" "SIC431AED-T1-GE3 "
			(at -34.765 160.105 0)
			(layer "F.Fab")
			(hide yes)
			(effects
				(font
					(size 1 1)
					(thickness 0.15)
				)
			)
		)
		(property "Manufacturer" "Vishay"
			(at -34.765 160.105 0)
			(layer "F.Fab")
			(hide yes)
			(effects
				(font
					(size 1 1)
					(thickness 0.15)
				)
			)
		)
		(sheetname "Supply")
		(sheetfile "supply.kicad_sch")
		(attr smd)
		(net_tie_pad_groups "1,2,26" "3,4,27" "5,6,7,8,9")
		(fp_line
			(start -2.11 2.11)
			(end -2.11 1.39)
			(stroke
				(width 0.15)
				(type solid)
			)
			(layer "F.SilkS")
		)
		(fp_line
			(start -1.89 2.11)
			(end -2.11 2.11)
			(stroke
				(width 0.15)
				(type solid)
			)
			(layer "F.SilkS")
		)
		(fp_line
			(start 1.44 2.11)
			(end 2.11 2.11)
			(stroke
				(width 0.15)
				(type solid)
			)
			(layer "F.SilkS")
		)
		(fp_line
			(start 2.11 2.11)
			(end 2.11 1.84)
			(stroke
				(width 0.15)
				(type solid)
			)
			(layer "F.SilkS")
		)
		(fp_line
			(start -2.11 -1.38)
			(end -2.11 -2.1)
			(stroke
				(width 0.15)
				(type solid)
			)
			(layer "F.SilkS")
		)
		(fp_line
			(start -1.89 -2.1)
			(end -2.11 -2.1)
			(stroke
				(width 0.15)
				(type solid)
			)
			(layer "F.SilkS")
		)
		(fp_line
			(start 1.89 -2.11)
			(end 2.11 -2.11)
			(stroke
				(width 0.15)
				(type solid)
			)
			(layer "F.SilkS")
		)
		(fp_line
			(start 2.11 -2.11)
			(end 2.11 -1.69)
			(stroke
				(width 0.15)
				(type solid)
			)
			(layer "F.SilkS")
		)
		(fp_circle
			(center -2.25 -1.15)
			(end -2.2 -1.15)
			(stroke
				(width 0.15)
				(type solid)
			)
			(fill solid)
			(layer "F.SilkS")
		)
		(fp_line
			(start -2.55 2.55)
			(end -2.55 -2.55)
			(stroke
				(width 0.05)
				(type solid)
			)
			(layer "F.CrtYd")
		)
		(fp_line
			(start 2.55 2.55)
			(end -2.55 2.55)
			(stroke
				(width 0.05)
				(type solid)
			)
			(layer "F.CrtYd")
		)
		(fp_line
			(start -2.55 -2.55)
			(end 2.55 -2.55)
			(stroke
				(width 0.05)
				(type solid)
			)
			(layer "F.CrtYd")
		)
		(fp_line
			(start 2.55 -2.55)
			(end 2.55 2.55)
			(stroke
				(width 0.05)
				(type solid)
			)
			(layer "F.CrtYd")
		)
		(fp_line
			(start -2 2)
			(end 2 2)
			(stroke
				(width 0.15)
				(type solid)
			)
			(layer "F.Fab")
		)
		(fp_line
			(start 2 2)
			(end 2 -2)
			(stroke
				(width 0.15)
				(type solid)
			)
			(layer "F.Fab")
		)
		(fp_line
			(start -2 -1)
			(end -2 2)
			(stroke
				(width 0.15)
				(type solid)
			)
			(layer "F.Fab")
		)
		(fp_line
			(start -1 -2)
			(end -2 -1)
			(stroke
				(width 0.15)
				(type solid)
			)
			(layer "F.Fab")
		)
		(fp_line
			(start 2 -2)
			(end -1 -2)
			(stroke
				(width 0.15)
				(type solid)
			)
			(layer "F.Fab")
		)
		(fp_text user "${REFERENCE}"
			(at -2.9 6.8 90)
			(layer "F.Fab")
			(hide yes)
			(effects
				(font
					(size 0.7 0.7)
					(thickness 0.15)
				)
				(justify right bottom)
			)
		)
		(fp_text user "License: Apache-2.0"
			(at -2.7 5.6 -90)
			(layer "F.Fab")
			(hide yes)
			(effects
				(font
					(size 0.7 0.7)
					(thickness 0.15)
				)
				(justify left bottom)
			)
		)
		(fp_text user "License: "
			(at -2.9 5.6 90)
			(layer "F.Fab")
			(hide yes)
			(effects
				(font
					(size 0.7 0.7)
					(thickness 0.15)
				)
				(justify right bottom)
			)
		)
		(fp_text user "Author: Antmicro"
			(at -2.9 8 90)
			(layer "F.Fab")
			(hide yes)
			(effects
				(font
					(size 0.7 0.7)
					(thickness 0.15)
				)
				(justify right bottom)
			)
		)
		(pad "1" smd roundrect
			(at -1.94 -0.825)
			(size 0.3 0.725)
			(layers "F.Cu" "F.Paste" "F.Mask")
			(roundrect_rratio 0.25)
			(net 115 "VCC")
			(pinfunction "V_{IN}")
			(pintype "power_in")
		)
		(pad "2" smd roundrect
			(at -1.94 -0.375)
			(size 0.3 0.725)
			(layers "F.Cu" "F.Paste" "F.Mask")
			(roundrect_rratio 0.25)
			(net 115 "VCC")
			(pinfunction "V_{IN}")
			(pintype "passive")
		)
		(pad "3" smd roundrect
			(at -1.94 0.525)
			(size 0.3 0.725)
			(layers "F.Cu" "F.Paste" "F.Mask")
			(roundrect_rratio 0.25)
			(net 1 "GND")
			(pinfunction "P_{GND}")
			(pintype "passive")
		)
		(pad "4" smd roundrect
			(at -1.94 0.975)
			(size 0.3 0.725)
			(layers "F.Cu" "F.Paste" "F.Mask")
			(roundrect_rratio 0.25)
			(net 1 "GND")
			(pinfunction "P_{GND}")
			(pintype "passive")
		)
		(pad "5" smd custom
			(at -1.475 1.94 270)
			(size 0.3 0.3)
			(layers "F.Cu" "F.Paste" "F.Mask")
			(net 763 "/Supply/5V_SW")
			(pinfunction "SW")
			(pintype "passive")
			(options
				(clearance outline)
				(anchor circle)
			)
			(primitives
				(gr_poly
					(pts
						(xy -0.15 -0.2875) (xy -0.144291 -0.316201) (xy -0.128033 -0.340533) (xy -0.103701 -0.356791)
						(xy -0.075 -0.3625) (xy 0.075 -0.3625) (xy 0.103701 -0.356791) (xy 0.128033 -0.340533) (xy 0.144291 -0.316201)
						(xy 0.15 -0.2875) (xy 0.15 0.2875) (xy 0.144291 0.316201) (xy 0.128033 0.340533) (xy 0.103701 0.356791)
						(xy 0.075 0.3625) (xy -0.075 0.3625) (xy -0.103701 0.356791) (xy -0.128033 0.340533) (xy -0.144291 0.316201)
						(xy -0.15 0.2875)
					)
					(width 0)
					(fill yes)
				)
				(gr_poly
					(pts
						(xy -0.15 -0.3625) (xy 2.2 -0.3625) (xy 2.2 -0.0875) (xy -0.15 -0.0875)
					)
					(width 0)
					(fill yes)
				)
			)
		)
		(pad "6" smd roundrect
			(at -1.025 1.94 270)
			(size 0.3 0.725)
			(layers "F.Cu" "F.Paste" "F.Mask")
			(roundrect_rratio 0.25)
			(net 763 "/Supply/5V_SW")
			(pinfunction "SW")
			(pintype "passive")
		)
		(pad "7" smd roundrect
			(at -0.575 1.94 270)
			(size 0.3 0.725)
			(layers "F.Cu" "F.Paste" "F.Mask")
			(roundrect_rratio 0.25)
			(net 763 "/Supply/5V_SW")
			(pinfunction "SW")
			(pintype "passive")
		)
		(pad "8" smd roundrect
			(at 0.125 1.94 270)
			(size 0.3 0.725)
			(layers "F.Cu" "F.Paste" "F.Mask")
			(roundrect_rratio 0.25)
			(net 763 "/Supply/5V_SW")
			(pinfunction "SW")
			(pintype "passive")
		)
		(pad "9" smd roundrect
			(at 0.575 1.94 270)
			(size 0.3 0.725)
			(layers "F.Cu" "F.Paste" "F.Mask")
			(roundrect_rratio 0.25)
			(net 763 "/Supply/5V_SW")
			(pinfunction "SW")
			(pintype "passive")
		)
		(pad "10" smd roundrect
			(at 1.025 1.935 270)
			(size 0.3 0.725)
			(layers "F.Cu" "F.Paste" "F.Mask")
			(roundrect_rratio 0.25)
			(net 782 "unconnected-(U1-GL-Pad10)_2")
			(pinfunction "GL")
			(pintype "passive+no_connect")
		)
		(pad "11" smd roundrect
			(at 1.94 1.425)
			(size 0.3 0.725)
			(layers "F.Cu" "F.Paste" "F.Mask")
			(roundrect_rratio 0.25)
			(net 781 "unconnected-(U1-GL-Pad10)_1")
			(pinfunction "GL")
			(pintype "passive+no_connect")
		)
		(pad "12" smd roundrect
			(at 1.94 0.975)
			(size 0.3 0.725)
			(layers "F.Cu" "F.Paste" "F.Mask")
			(roundrect_rratio 0.25)
			(net 762 "/Supply/5V_VDRV")
			(pinfunction "V_{DRV}")
			(pintype "passive")
		)
		(pad "13" smd roundrect
			(at 1.94 0.525)
			(size 0.3 0.725)
			(layers "F.Cu" "F.Paste" "F.Mask")
			(roundrect_rratio 0.25)
			(net 1 "GND")
			(pinfunction "P_{GND}")
			(pintype "power_in")
		)
		(pad "14" smd roundrect
			(at 1.94 0.075)
			(size 0.3 0.725)
			(layers "F.Cu" "F.Paste" "F.Mask")
			(roundrect_rratio 0.25)
			(net 770 "unconnected-(U1-P_{GOOD}-Pad14)")
			(pinfunction "P_{GOOD}")
			(pintype "output+no_connect")
		)
		(pad "15" smd roundrect
			(at 1.94 -0.375)
			(size 0.3 0.725)
			(layers "F.Cu" "F.Paste" "F.Mask")
			(roundrect_rratio 0.25)
			(net 759 "/Supply/5V_VDD")
			(pinfunction "V_{DD}")
			(pintype "passive")
		)
		(pad "16" smd roundrect
			(at 1.94 -0.825)
			(size 0.3 0.725)
			(layers "F.Cu" "F.Paste" "F.Mask")
			(roundrect_rratio 0.25)
			(net 1 "GND")
			(pinfunction "A_{GND}")
			(pintype "power_in")
		)
		(pad "17" smd roundrect
			(at 1.94 -1.275)
			(size 0.3 0.725)
			(layers "F.Cu" "F.Paste" "F.Mask")
			(roundrect_rratio 0.25)
			(net 766 "/Supply/5V_FB")
			(pinfunction "FB")
			(pintype "passive")
		)
		(pad "18" smd roundrect
			(at 1.475 -1.94 270)
			(size 0.3 0.725)
			(layers "F.Cu" "F.Paste" "F.Mask")
			(roundrect_rratio 0.25)
			(net 761 "/Supply/5V_OUT")
			(pinfunction "V_{OUT}")
			(pintype "passive")
		)
		(pad "19" smd roundrect
			(at 1.025 -1.94 270)
			(size 0.3 0.725)
			(layers "F.Cu" "F.Paste" "F.Mask")
			(roundrect_rratio 0.25)
			(net 712 "/Supply/5V_EN")
			(pinfunction "EN")
			(pintype "input")
		)
		(pad "20" smd roundrect
			(at 0.575 -1.94 270)
			(size 0.3 0.725)
			(layers "F.Cu" "F.Paste" "F.Mask")
			(roundrect_rratio 0.25)
			(net 767 "/Supply/5V_MODE2")
			(pinfunction "MODE2")
			(pintype "input")
		)
		(pad "21" smd roundrect
			(at 0.125 -1.94 270)
			(size 0.3 0.725)
			(layers "F.Cu" "F.Paste" "F.Mask")
			(roundrect_rratio 0.25)
			(net 764 "/Supply/5V_MODE1")
			(pinfunction "MODE1")
			(pintype "input")
		)
		(pad "22" smd roundrect
			(at -0.575 -1.94 270)
			(size 0.3 0.725)
			(layers "F.Cu" "F.Paste" "F.Mask")
			(roundrect_rratio 0.25)
			(net 115 "VCC")
			(pinfunction "V_{IN}")
			(pintype "passive")
		)
		(pad "23" smd roundrect
			(at -1.025 -1.94 270)
			(size 0.3 0.725)
			(layers "F.Cu" "F.Paste" "F.Mask")
			(roundrect_rratio 0.25)
			(net 760 "/Supply/5V_BOOT")
			(pinfunction "BOOT")
			(pintype "passive")
		)
		(pad "24" smd roundrect
			(at -1.475 -1.94 270)
			(size 0.3 0.725)
			(layers "F.Cu" "F.Paste" "F.Mask")
			(roundrect_rratio 0.25)
			(net 765 "/Supply/5V_PHASE")
			(pinfunction "PHASE")
			(pintype "passive")
		)
		(pad "25" smd rect
			(at 0.49 -0.75 90)
			(size 1.575 1.05)
			(layers "F.Cu" "F.Paste" "F.Mask")
			(net 1 "GND")
			(pinfunction "A_{GND}")
			(pintype "passive")
		)
		(pad "26" smd rect
			(at -1.175 -0.75 90)
			(size 1.15 1.05)
			(layers "F.Cu" "F.Paste" "F.Mask")
			(net 115 "VCC")
			(pinfunction "V_{IN}")
			(pintype "passive")
		)
		(pad "27" smd custom
			(at -0.75 0.775 270)
			(size 1 1)
			(layers "F.Cu" "F.Paste" "F.Mask")
			(net 1 "GND")
			(pinfunction "P_{GND}")
			(pintype "passive")
			(options
				(clearance outline)
				(anchor rect)
			)
			(primitives
				(gr_poly
					(pts
						(xy -1 0.5) (xy -1 -0.7) (xy 1.825 -0.7) (xy 1.825 -0.245) (xy 1.175 -0.245) (xy 1.175 0.5)
					)
					(width 0)
					(fill yes)
				)
			)
		)
		(pad "28" smd rect
			(at 0.985 0.99 90)
			(size 0.58 0.38)
			(layers "F.Cu" "F.Paste" "F.Mask")
			(net 769 "unconnected-(U1-GL-Pad10)")
			(pinfunction "GL")
			(pintype "passive+no_connect")
		)
	)
	(footprint "antmicro-footprints:XSON-8_1x1.95mm_P0.5mm"
		(layer "F.Cu")
		(at 90.6 117 180)
		(property "Reference" "U43"
			(at 0.875 1.175 180)
			(layer "F.SilkS")
			(effects
				(font
					(size 0.7 0.7)
					(thickness 0.15)
				)
				(justify left bottom)
			)
		)
		(property "Value" "NTS0102_XSON"
			(at 0 2.2 180)
			(layer "F.Fab")
			(effects
				(font
					(size 0.7 0.7)
					(thickness 0.15)
				)
				(justify left bottom)
			)
		)
		(property "Footprint" "antmicro-footprints:XSON-8_1x1.95mm_P0.5mm"
			(at 0 0 180)
			(layer "F.Fab")
			(hide yes)
			(effects
				(font
					(size 1.27 1.27)
					(thickness 0.15)
				)
			)
		)
		(property "Datasheet" "http://www.farnell.com/datasheets/1760723.pdf"
			(at 0 0 180)
			(layer "F.Fab")
			(hide yes)
			(effects
				(font
					(size 1.27 1.27)
					(thickness 0.15)
				)
			)
		)
		(property "Author" "Antmicro"
			(at 181.2 234 0)
			(layer "F.Fab")
			(hide yes)
			(effects
				(font
					(size 1 1)
					(thickness 0.15)
				)
			)
		)
		(property "License" "Apache-2.0"
			(at 181.2 234 0)
			(layer "F.Fab")
			(hide yes)
			(effects
				(font
					(size 1 1)
					(thickness 0.15)
				)
			)
		)
		(property "MPN" "NTS0102GT"
			(at 181.2 234 0)
			(layer "F.Fab")
			(hide yes)
			(effects
				(font
					(size 1 1)
					(thickness 0.15)
				)
			)
		)
		(property "Manufacturer" "NXP"
			(at 181.2 234 0)
			(layer "F.Fab")
			(hide yes)
			(effects
				(font
					(size 1 1)
					(thickness 0.15)
				)
			)
		)
		(sheetname "HDMI")
		(sheetfile "hdmi.kicad_sch")
		(attr smd)
		(fp_line
			(start 0.5 1.1)
			(end -0.5 1.1)
			(stroke
				(width 0.15)
				(type solid)
			)
			(layer "F.SilkS")
		)
		(fp_line
			(start -0.5 -1.1)
			(end 0.5 -1.1)
			(stroke
				(width 0.15)
				(type solid)
			)
			(layer "F.SilkS")
		)
		(fp_circle
			(center -0.75 -1.1)
			(end -0.701 -1.1)
			(stroke
				(width 0.15)
				(type solid)
			)
			(fill none)
			(layer "F.SilkS")
		)
		(fp_rect
			(start -0.8 -1.2)
			(end 0.8 1.2)
			(stroke
				(width 0.05)
				(type solid)
			)
			(fill none)
			(layer "F.CrtYd")
		)
		(fp_line
			(start 0.5305 1)
			(end -0.5305 1)
			(stroke
				(width 0.15)
				(type solid)
			)
			(layer "F.Fab")
		)
		(fp_line
			(start 0.5305 -1.001)
			(end 0.5305 1)
			(stroke
				(width 0.15)
				(type solid)
			)
			(layer "F.Fab")
		)
		(fp_line
			(start -0.5305 1)
			(end -0.5305 -1.001)
			(stroke
				(width 0.15)
				(type solid)
			)
			(layer "F.Fab")
		)
		(fp_line
			(start -0.5305 -1.001)
			(end 0.5305 -1.001)
			(stroke
				(width 0.15)
				(type solid)
			)
			(layer "F.Fab")
		)
		(fp_text user "Author: Antmicro"
			(at -0.527 7.105 180)
			(layer "F.Fab")
			(hide yes)
			(effects
				(font
					(size 0.7 0.7)
					(thickness 0.15)
				)
				(justify left bottom)
			)
		)
		(fp_text user "License: Apache-2.0"
			(at -0.527 8.306 180)
			(layer "F.Fab")
			(hide yes)
			(effects
				(font
					(size 0.7 0.7)
					(thickness 0.15)
				)
				(justify left bottom)
			)
		)
		(fp_text user "${REFERENCE}"
			(at -0.527 5.905 180)
			(layer "F.Fab")
			(hide yes)
			(effects
				(font
					(size 0.7 0.7)
					(thickness 0.15)
				)
				(justify left bottom)
			)
		)
		(pad "1" smd roundrect
			(at -0.45 -0.75)
			(size 0.6 0.3)
			(layers "F.Cu" "F.Paste" "F.Mask")
			(roundrect_rratio 0.25)
			(net 519 "/HDMI/HDMI_SCL_5V")
			(pinfunction "B_{2}")
			(pintype "bidirectional")
		)
		(pad "2" smd roundrect
			(at -0.45 -0.25)
			(size 0.6 0.25)
			(layers "F.Cu" "F.Paste" "F.Mask")
			(roundrect_rratio 0.25)
			(net 1 "GND")
			(pinfunction "GND")
			(pintype "power_in")
		)
		(pad "3" smd roundrect
			(at -0.45 0.25)
			(size 0.6 0.25)
			(layers "F.Cu" "F.Paste" "F.Mask")
			(roundrect_rratio 0.25)
			(net 87 "+3V3")
			(pinfunction "VCC_{A}")
			(pintype "power_in")
		)
		(pad "4" smd roundrect
			(at -0.45 0.75)
			(size 0.6 0.3)
			(layers "F.Cu" "F.Paste" "F.Mask")
			(roundrect_rratio 0.25)
			(net 555 "/HDMI/HDMI_SCL_3V3")
			(pinfunction "A_{2}")
			(pintype "bidirectional")
		)
		(pad "5" smd roundrect
			(at 0.45 0.75)
			(size 0.6 0.3)
			(layers "F.Cu" "F.Paste" "F.Mask")
			(roundrect_rratio 0.25)
			(net 701 "/HDMI/HDMI_SDA_3V3")
			(pinfunction "A_{1}")
			(pintype "bidirectional")
		)
		(pad "6" smd roundrect
			(at 0.45 0.25)
			(size 0.6 0.25)
			(layers "F.Cu" "F.Paste" "F.Mask")
			(roundrect_rratio 0.25)
			(net 87 "+3V3")
			(pinfunction "OE")
			(pintype "input")
		)
		(pad "7" smd roundrect
			(at 0.45 -0.25)
			(size 0.6 0.25)
			(layers "F.Cu" "F.Paste" "F.Mask")
			(roundrect_rratio 0.25)
			(net 498 "/HDMI/5V_HDMI")
			(pinfunction "VCC_{B}")
			(pintype "power_in")
		)
		(pad "8" smd roundrect
			(at 0.45 -0.75)
			(size 0.6 0.3)
			(layers "F.Cu" "F.Paste" "F.Mask")
			(roundrect_rratio 0.25)
			(net 518 "/HDMI/HDMI_SDA_5V")
			(pinfunction "B_{1}")
			(pintype "bidirectional")
		)
	)
	(footprint "antmicro-footprints:Conv_Murata_ULS-60W"
		(layer "F.Cu")
		(at 34.048 99.491145 90)
		(property "Reference" "U23"
			(at -3.558855 -1.523 180)
			(layer "F.SilkS")
			(effects
				(font
					(size 0.7 0.7)
					(thickness 0.15)
				)
				(justify left bottom)
			)
		)
		(property "Value" "ULS-12_5-D48N-C"
			(at -2.8 20.1 90)
			(layer "F.Fab")
			(effects
				(font
					(size 0.7 0.7)
					(thickness 0.15)
				)
				(justify left bottom)
			)
		)
		(property "Footprint" "antmicro-footprints:Conv_Murata_ULS-60W"
			(at 0 0 90)
			(layer "F.Fab")
			(hide yes)
			(effects
				(font
					(size 1.27 1.27)
					(thickness 0.15)
				)
			)
		)
		(property "Datasheet" "https://www.murata.com/products/productdata/8807040286750/uls.pdf?1649388617000"
			(at 0 0 90)
			(layer "F.Fab")
			(hide yes)
			(effects
				(font
					(size 1.27 1.27)
					(thickness 0.15)
				)
			)
		)
		(property "Description" "Isolated Through Hole DC/DC Converter, ITE, 2:1, 60 W, 1 Output, 12 V, 5 A"
			(at 0 0 90)
			(layer "F.Fab")
			(hide yes)
			(effects
				(font
					(size 1.27 1.27)
					(thickness 0.15)
				)
			)
		)
		(property "Manufacturer" "Murata"
			(at 0 0 90)
			(unlocked yes)
			(layer "F.Fab")
			(hide yes)
			(effects
				(font
					(size 1 1)
					(thickness 0.15)
				)
			)
		)
		(property "MPN" "ULS-12/5-D48N-C"
			(at 0 0 90)
			(unlocked yes)
			(layer "F.Fab")
			(hide yes)
			(effects
				(font
					(size 1 1)
					(thickness 0.15)
				)
			)
		)
		(property "Author" "Antmicro"
			(at 0 0 90)
			(unlocked yes)
			(layer "F.Fab")
			(hide yes)
			(effects
				(font
					(size 1 1)
					(thickness 0.15)
				)
			)
		)
		(property "License" "Apache-2.0"
			(at 0 0 90)
			(unlocked yes)
			(layer "F.Fab")
			(hide yes)
			(effects
				(font
					(size 1 1)
					(thickness 0.15)
				)
			)
		)
		(property "Alternatives 50W" " VCB4812SBO-50WR3, V36SE12004NRFA, PKU5513ESI, KHHD004A2B41Z"
			(at 0 0 90)
			(unlocked yes)
			(layer "F.Fab")
			(hide yes)
			(effects
				(font
					(size 1 1)
					(thickness 0.15)
				)
			)
		)
		(property "Alternatives 75W" " VCB4812SBO-75WR3"
			(at 0 0 90)
			(unlocked yes)
			(layer "F.Fab")
			(hide yes)
			(effects
				(font
					(size 1 1)
					(thickness 0.15)
				)
			)
		)
		(property "Alternatives 100W" "PKU4913DPIHS, VCB4812SBO-100WFR3"
			(at 0 0 90)
			(unlocked yes)
			(layer "F.Fab")
			(hide yes)
			(effects
				(font
					(size 1 1)
					(thickness 0.15)
				)
			)
		)
		(property "Alternatives 120W" "PQC50-48-S12-O"
			(at 0 0 90)
			(unlocked yes)
			(layer "F.Fab")
			(hide yes)
			(effects
				(font
					(size 1 1)
					(thickness 0.15)
				)
			)
		)
		(sheetname "Ethernet")
		(sheetfile "ethernet.kicad_sch")
		(attr through_hole)
		(fp_line
			(start 30.485 -3.807)
			(end -1.265 -3.807)
			(stroke
				(width 0.15)
				(type solid)
			)
			(layer "F.SilkS")
		)
		(fp_line
			(start -2.535 -2.537)
			(end -1.265 -3.807)
			(stroke
				(width 0.15)
				(type solid)
			)
			(layer "F.SilkS")
		)
		(fp_line
			(start 30.485 19.053)
			(end 30.485 -3.807)
			(stroke
				(width 0.15)
				(type solid)
			)
			(layer "F.SilkS")
		)
		(fp_line
			(start 30.485 19.053)
			(end -2.535 19.053)
			(stroke
				(width 0.15)
				(type solid)
			)
			(layer "F.SilkS")
		)
		(fp_line
			(start -2.535 19.053)
			(end -2.535 -2.537)
			(stroke
				(width 0.15)
				(type solid)
			)
			(layer "F.SilkS")
		)
		(fp_circle
			(center -1.9 0)
			(end -1.85 0)
			(stroke
				(width 0.15)
				(type solid)
			)
			(fill solid)
			(layer "F.SilkS")
		)
		(fp_rect
			(start -3.54 -4.81)
			(end 31.48 20.05)
			(stroke
				(width 0.05)
				(type solid)
			)
			(fill none)
			(layer "F.CrtYd")
		)
		(fp_line
			(start 30.485 -3.807)
			(end -1.265 -3.807)
			(stroke
				(width 0.15)
				(type solid)
			)
			(layer "F.Fab")
		)
		(fp_line
			(start -2.535 -2.537)
			(end -1.265 -3.807)
			(stroke
				(width 0.15)
				(type solid)
			)
			(layer "F.Fab")
		)
		(fp_line
			(start 30.485 19.053)
			(end 30.485 -3.807)
			(stroke
				(width 0.15)
				(type solid)
			)
			(layer "F.Fab")
		)
		(fp_line
			(start 30.485 19.053)
			(end -2.535 19.053)
			(stroke
				(width 0.15)
				(type solid)
			)
			(layer "F.Fab")
		)
		(fp_line
			(start -2.535 19.053)
			(end -2.535 -2.537)
			(stroke
				(width 0.15)
				(type solid)
			)
			(layer "F.Fab")
		)
		(fp_text user "License: Apache-2.0"
			(at -3.54 24.45 90)
			(layer "F.Fab")
			(hide yes)
			(effects
				(font
					(size 0.7 0.7)
					(thickness 0.15)
				)
				(justify left bottom)
			)
		)
		(fp_text user "${REFERENCE}"
			(at -3.54 23.25 90)
			(layer "F.Fab")
			(hide yes)
			(effects
				(font
					(size 0.7 0.7)
					(thickness 0.15)
				)
				(justify left bottom)
			)
		)
		(fp_text user "Author: Antmicro"
			(at -3.54 22.05 90)
			(layer "F.Fab")
			(hide yes)
			(effects
				(font
					(size 0.7 0.7)
					(thickness 0.15)
				)
				(justify left bottom)
			)
		)
		(pad "1" thru_hole rect
			(at 0 0 90)
			(size 2.54 2.54)
			(drill 1.4)
			(layers "*.Cu" "*.Mask")
			(remove_unused_layers no)
			(net 105 "/Ethernet/VDD")
			(pinfunction "VIN+")
			(pintype "power_in")
		)
		(pad "2" thru_hole circle
			(at 0 7.62 90)
			(size 2.54 2.54)
			(drill 1.4)
			(layers "*.Cu" "*.Mask")
			(remove_unused_layers no)
			(net 650 "/Ethernet/ULS-12_CTRL")
			(pinfunction "CTRL")
			(pintype "input")
		)
		(pad "3" thru_hole circle
			(at 0 15.24 90)
			(size 2.54 2.54)
			(drill 1.4)
			(layers "*.Cu" "*.Mask")
			(remove_unused_layers no)
			(net 106 "GNDD")
			(pinfunction "VIN-")
			(pintype "power_in")
		)
		(pad "4" thru_hole circle
			(at 27.94 15.24 90)
			(size 2.54 2.54)
			(drill 1.956)
			(layers "*.Cu" "*.Mask")
			(remove_unused_layers no)
			(net 1 "GND")
			(pinfunction "VOUT-")
			(pintype "power_out")
		)
		(pad "5" thru_hole circle
			(at 27.94 11.43 90)
			(size 2.54 2.54)
			(drill 1.4)
			(layers "*.Cu" "*.Mask")
			(remove_unused_layers no)
			(net 1 "GND")
			(pinfunction "SENSE-")
			(pintype "passive")
		)
		(pad "6" thru_hole circle
			(at 27.94 7.62 90)
			(size 2.54 2.54)
			(drill 1.4)
			(layers "*.Cu" "*.Mask")
			(remove_unused_layers no)
			(net 683 "Net-(U23-TRIM)")
			(pinfunction "TRIM")
			(pintype "input")
		)
		(pad "7" thru_hole circle
			(at 27.94 3.81 90)
			(size 2.54 2.54)
			(drill 1.4)
			(layers "*.Cu" "*.Mask")
			(remove_unused_layers no)
			(net 500 "POE_OUTPUT")
			(pinfunction "SENSE+")
			(pintype "passive")
		)
		(pad "8" thru_hole circle
			(at 27.94 0 90)
			(size 2.54 2.54)
			(drill 1.956)
			(layers "*.Cu" "*.Mask")
			(remove_unused_layers no)
			(net 500 "POE_OUTPUT")
			(pinfunction "VOUT+")
			(pintype "power_out")
		)
	)
	(footprint "antmicro-footprints:C_0402_1005Metric"
		(layer "F.Cu")
		(at 75.6 110.967469 -90)
		(descr "Capacitor SMD 0402")
		(tags "capacitor SMD 0402")
		(property "Reference" "C63"
			(at 2.982531 -0.45 -90)
			(layer "F.SilkS")
			(effects
				(font
					(size 0.7 0.7)
					(thickness 0.15)
				)
				(justify left bottom)
			)
		)
		(property "Value" "C_100n_0402"
			(at 0 1.4 -90)
			(layer "F.Fab")
			(effects
				(font
					(size 0.7 0.7)
					(thickness 0.15)
				)
				(justify left bottom)
			)
		)
		(property "Footprint" "antmicro-footprints:C_0402_1005Metric"
			(at 0 0 -90)
			(layer "F.Fab")
			(hide yes)
			(effects
				(font
					(size 1.27 1.27)
					(thickness 0.15)
				)
			)
		)
		(property "Datasheet" "https://www.murata.com/products/productdetail?partno=GRM155R61H104KE14%23"
			(at 0 0 -90)
			(layer "F.Fab")
			(hide yes)
			(effects
				(font
					(size 1.27 1.27)
					(thickness 0.15)
				)
			)
		)
		(property "Author" "Antmicro"
			(at -35.367469 186.567469 0)
			(layer "F.Fab")
			(hide yes)
			(effects
				(font
					(size 1 1)
					(thickness 0.15)
				)
			)
		)
		(property "Dielectric" "X5R"
			(at -35.367469 186.567469 0)
			(layer "F.Fab")
			(hide yes)
			(effects
				(font
					(size 1 1)
					(thickness 0.15)
				)
			)
		)
		(property "License" "Apache-2.0"
			(at -35.367469 186.567469 0)
			(layer "F.Fab")
			(hide yes)
			(effects
				(font
					(size 1 1)
					(thickness 0.15)
				)
			)
		)
		(property "MPN" "GRM155R61H104KE14D"
			(at -35.367469 186.567469 0)
			(layer "F.Fab")
			(hide yes)
			(effects
				(font
					(size 1 1)
					(thickness 0.15)
				)
			)
		)
		(property "Manufacturer" "Murata"
			(at -35.367469 186.567469 0)
			(layer "F.Fab")
			(hide yes)
			(effects
				(font
					(size 1 1)
					(thickness 0.15)
				)
			)
		)
		(property "Val" "100n"
			(at -35.367469 186.567469 0)
			(layer "F.Fab")
			(hide yes)
			(effects
				(font
					(size 1 1)
					(thickness 0.15)
				)
			)
		)
		(property "Voltage" "50V"
			(at -35.367469 186.567469 0)
			(layer "F.Fab")
			(hide yes)
			(effects
				(font
					(size 1 1)
					(thickness 0.15)
				)
			)
		)
		(sheetname "USB Debug, DP")
		(sheetfile "usb.kicad_sch")
		(attr smd)
		(fp_rect
			(start -0.925 -0.47)
			(end 0.925 0.47)
			(stroke
				(width 0.05)
				(type default)
			)
			(fill none)
			(layer "F.CrtYd")
		)
		(fp_line
			(start -0.494 0.248)
			(end -0.494 -0.25)
			(stroke
				(width 0.15)
				(type solid)
			)
			(layer "F.Fab")
		)
		(fp_line
			(start 0.504 0.248)
			(end -0.494 0.248)
			(stroke
				(width 0.15)
				(type solid)
			)
			(layer "F.Fab")
		)
		(fp_line
			(start -0.494 -0.25)
			(end 0.504 -0.25)
			(stroke
				(width 0.15)
				(type solid)
			)
			(layer "F.Fab")
		)
		(fp_line
			(start 0.504 -0.25)
			(end 0.504 0.248)
			(stroke
				(width 0.15)
				(type solid)
			)
			(layer "F.Fab")
		)
		(fp_text user "Author: Antmicro"
			(at -0.932 4.17 -90)
			(layer "F.Fab")
			(hide yes)
			(effects
				(font
					(size 0.7 0.7)
					(thickness 0.15)
				)
				(justify left bottom)
			)
		)
		(fp_text user "${REFERENCE}"
			(at -0.932 3.168 -90)
			(layer "F.Fab")
			(hide yes)
			(effects
				(font
					(size 0.7 0.7)
					(thickness 0.15)
				)
				(justify left bottom)
			)
		)
		(fp_text user "License: Apache-2.0"
			(at -0.932 5.17 -90)
			(layer "F.Fab")
			(hide yes)
			(effects
				(font
					(size 0.7 0.7)
					(thickness 0.15)
				)
				(justify left bottom)
			)
		)
		(pad "1" smd roundrect
			(at -0.48 0 270)
			(size 0.59 0.64)
			(layers "F.Cu" "F.Paste" "F.Mask")
			(roundrect_rratio 0.25)
			(net 200 "/USB Debug, DP/USBC0_TX2_N")
			(pintype "passive")
		)
		(pad "2" smd roundrect
			(at 0.48 0 270)
			(size 0.59 0.64)
			(layers "F.Cu" "F.Paste" "F.Mask")
			(roundrect_rratio 0.25)
			(net 201 "/USB Debug, DP/USBC0_CONN_TX2_N")
			(pintype "passive")
		)
	)
	(footprint "antmicro-footprints:R_0402_1005Metric"
		(layer "F.Cu")
		(at 134.85 112.3 -90)
		(descr "Resistor SMD 0402")
		(tags "resistor SMD 0402")
		(property "Reference" "R66"
			(at 1.15 3.27 -90)
			(layer "F.SilkS")
			(effects
				(font
					(size 0.7 0.7)
					(thickness 0.15)
				)
				(justify left bottom)
			)
		)
		(property "Value" "R_10k_0402"
			(at 0 1.4 -90)
			(layer "F.Fab")
			(effects
				(font
					(size 0.7 0.7)
					(thickness 0.15)
				)
				(justify left bottom)
			)
		)
		(property "Footprint" "antmicro-footprints:R_0402_1005Metric"
			(at 0 0 -90)
			(layer "F.Fab")
			(hide yes)
			(effects
				(font
					(size 1.27 1.27)
					(thickness 0.15)
				)
			)
		)
		(property "Datasheet" "https://www.bourns.com/docs/product-datasheets/cr.pdf"
			(at 0 0 -90)
			(layer "F.Fab")
			(hide yes)
			(effects
				(font
					(size 1.27 1.27)
					(thickness 0.15)
				)
			)
		)
		(property "Author" "Antmicro"
			(at 22.55 247.15 0)
			(layer "F.Fab")
			(hide yes)
			(effects
				(font
					(size 1 1)
					(thickness 0.15)
				)
			)
		)
		(property "License" "Apache-2.0"
			(at 22.55 247.15 0)
			(layer "F.Fab")
			(hide yes)
			(effects
				(font
					(size 1 1)
					(thickness 0.15)
				)
			)
		)
		(property "MPN" "CR0402-FX-1002GLF"
			(at 22.55 247.15 0)
			(layer "F.Fab")
			(hide yes)
			(effects
				(font
					(size 1 1)
					(thickness 0.15)
				)
			)
		)
		(property "Manufacturer" "Bourns"
			(at 22.55 247.15 0)
			(layer "F.Fab")
			(hide yes)
			(effects
				(font
					(size 1 1)
					(thickness 0.15)
				)
			)
		)
		(property "Tolerance" "1%"
			(at 22.55 247.15 0)
			(layer "F.Fab")
			(hide yes)
			(effects
				(font
					(size 1 1)
					(thickness 0.15)
				)
			)
		)
		(property "Val" "10k"
			(at 22.55 247.15 0)
			(layer "F.Fab")
			(hide yes)
			(effects
				(font
					(size 1 1)
					(thickness 0.15)
				)
			)
		)
		(sheetname "CSI")
		(sheetfile "csi.kicad_sch")
		(attr smd)
		(fp_rect
			(start -0.925 -0.47)
			(end 0.925 0.47)
			(stroke
				(width 0.05)
				(type default)
			)
			(fill none)
			(layer "F.CrtYd")
		)
		(fp_rect
			(start -0.5 -0.25)
			(end 0.5 0.25)
			(stroke
				(width 0.15)
				(type solid)
			)
			(fill none)
			(layer "F.Fab")
		)
		(fp_text user "License: Apache-2.0"
			(at -0.95 5.169 -90)
			(layer "F.Fab")
			(hide yes)
			(effects
				(font
					(size 0.7 0.7)
					(thickness 0.15)
				)
				(justify left bottom)
			)
		)
		(fp_text user "Author: Antmicro"
			(at -0.95 4.169 -90)
			(layer "F.Fab")
			(hide yes)
			(effects
				(font
					(size 0.7 0.7)
					(thickness 0.15)
				)
				(justify left bottom)
			)
		)
		(fp_text user "${REFERENCE}"
			(at -0.95 3.168 -90)
			(layer "F.Fab")
			(hide yes)
			(effects
				(font
					(size 0.7 0.7)
					(thickness 0.15)
				)
				(justify left bottom)
			)
		)
		(pad "1" smd roundrect
			(at -0.48 0 270)
			(size 0.59 0.64)
			(layers "F.Cu" "F.Paste" "F.Mask")
			(roundrect_rratio 0.25)
			(net 87 "+3V3")
			(pintype "passive")
		)
		(pad "2" smd roundrect
			(at 0.48 0 270)
			(size 0.59 0.64)
			(layers "F.Cu" "F.Paste" "F.Mask")
			(roundrect_rratio 0.25)
			(net 311 "CSIA_FLG")
			(pintype "passive")
		)
	)
	(footprint "antmicro-footprints:SOD-523"
		(layer "F.Cu")
		(at 83.71 122.4)
		(property "Reference" "D63"
			(at -1.01 -0.59 0)
			(layer "F.SilkS")
			(effects
				(font
					(size 0.7 0.7)
					(thickness 0.15)
				)
				(justify left bottom)
			)
		)
		(property "Value" "RB521S30T1G"
			(at 0 1.499 0)
			(layer "F.Fab")
			(effects
				(font
					(size 0.7 0.7)
					(thickness 0.15)
				)
				(justify left bottom)
			)
		)
		(property "Footprint" "antmicro-footprints:SOD-523"
			(at 0 0 0)
			(layer "F.Fab")
			(hide yes)
			(effects
				(font
					(size 1.27 1.27)
					(thickness 0.15)
				)
			)
		)
		(property "Datasheet" "https://www.onsemi.com/pdf/datasheet/rb521s30t1-d.pdf"
			(at 0 0 0)
			(layer "F.Fab")
			(hide yes)
			(effects
				(font
					(size 1.27 1.27)
					(thickness 0.15)
				)
			)
		)
		(property "Author" "Antmicro"
			(at 0 0 0)
			(layer "F.Fab")
			(hide yes)
			(effects
				(font
					(size 1 1)
					(thickness 0.15)
				)
			)
		)
		(property "License" "Apache-2.0"
			(at 0 0 0)
			(layer "F.Fab")
			(hide yes)
			(effects
				(font
					(size 1 1)
					(thickness 0.15)
				)
			)
		)
		(property "MPN" "RB521S30T1G"
			(at 0 0 0)
			(layer "F.Fab")
			(hide yes)
			(effects
				(font
					(size 1 1)
					(thickness 0.15)
				)
			)
		)
		(property "Manufacturer" "ON Semiconductor"
			(at 0 0 0)
			(layer "F.Fab")
			(hide yes)
			(effects
				(font
					(size 1 1)
					(thickness 0.15)
				)
			)
		)
		(sheetname "Peripherals")
		(sheetfile "peripherals.kicad_sch")
		(attr smd)
		(fp_line
			(start -0.35 -0.5)
			(end -0.35 0.5)
			(stroke
				(width 0.15)
				(type solid)
			)
			(layer "F.SilkS")
		)
		(fp_rect
			(start -1 -0.6)
			(end 1 0.6)
			(stroke
				(width 0.05)
				(type solid)
			)
			(fill none)
			(layer "F.CrtYd")
		)
		(fp_line
			(start -0.652 -0.425)
			(end 0.65 -0.425)
			(stroke
				(width 0.15)
				(type solid)
			)
			(layer "F.Fab")
		)
		(fp_line
			(start -0.652 0.423)
			(end -0.652 -0.425)
			(stroke
				(width 0.15)
				(type solid)
			)
			(layer "F.Fab")
		)
		(fp_line
			(start -0.652 0.423)
			(end 0.65 0.423)
			(stroke
				(width 0.15)
				(type solid)
			)
			(layer "F.Fab")
		)
		(fp_line
			(start -0.35 -0.4)
			(end -0.35 0.4)
			(stroke
				(width 0.15)
				(type solid)
			)
			(layer "F.Fab")
		)
		(fp_line
			(start 0.65 -0.425)
			(end 0.65 0.423)
			(stroke
				(width 0.15)
				(type solid)
			)
			(layer "F.Fab")
		)
		(fp_text user "Author: Antmicro"
			(at -1.276 4.7 0)
			(layer "F.Fab")
			(hide yes)
			(effects
				(font
					(size 0.7 0.7)
					(thickness 0.15)
				)
				(justify left bottom)
			)
		)
		(fp_text user "${REFERENCE}"
			(at -1.276 3.499 0)
			(layer "F.Fab")
			(hide yes)
			(effects
				(font
					(size 0.7 0.7)
					(thickness 0.15)
				)
				(justify left bottom)
			)
		)
		(fp_text user "License: Apache-2.0"
			(at -1.276 5.9 0)
			(layer "F.Fab")
			(hide yes)
			(effects
				(font
					(size 0.7 0.7)
					(thickness 0.15)
				)
				(justify left bottom)
			)
		)
		(pad "1" smd roundrect
			(at -0.701 0)
			(size 0.5 0.6)
			(layers "F.Cu" "F.Paste" "F.Mask")
			(roundrect_rratio 0.25)
			(net 671 "/Peripherals/SCK")
			(pinfunction "C")
			(pintype "passive")
		)
		(pad "2" smd roundrect
			(at 0.699 0)
			(size 0.5 0.6)
			(layers "F.Cu" "F.Paste" "F.Mask")
			(roundrect_rratio 0.25)
			(net 779 "Net-(D63-A)")
			(pinfunction "A")
			(pintype "passive")
		)
	)
	(footprint "antmicro-footprints:R_0402_1005Metric"
		(layer "F.Cu")
		(at 91.02 103.28 -135)
		(descr "Resistor SMD 0402")
		(tags "resistor SMD 0402")
		(property "Reference" "R220"
			(at 0.806102 0.636396 -135)
			(layer "F.SilkS")
			(effects
				(font
					(size 0.7 0.7)
					(thickness 0.15)
				)
				(justify left bottom)
			)
		)
		(property "Value" "R_499R_0402"
			(at -1.011843 1.772046 -135)
			(layer "F.Fab")
			(effects
				(font
					(size 0.7 0.7)
					(thickness 0.15)
				)
				(justify left bottom)
			)
		)
		(property "Footprint" "antmicro-footprints:R_0402_1005Metric"
			(at 0 0 -135)
			(layer "F.Fab")
			(hide yes)
			(effects
				(font
					(size 1.27 1.27)
					(thickness 0.15)
				)
			)
		)
		(property "Datasheet" "https://www.mouser.com/datasheet/2/54/cr-1858361.pdf"
			(at 0 0 -135)
			(layer "F.Fab")
			(hide yes)
			(effects
				(font
					(size 1.27 1.27)
					(thickness 0.15)
				)
			)
		)
		(property "Author" "Antmicro"
			(at 82.350871 240.670848 0)
			(layer "F.Fab")
			(hide yes)
			(effects
				(font
					(size 1 1)
					(thickness 0.15)
				)
			)
		)
		(property "License" "Apache-2.0"
			(at 82.350871 240.670848 0)
			(layer "F.Fab")
			(hide yes)
			(effects
				(font
					(size 1 1)
					(thickness 0.15)
				)
			)
		)
		(property "MPN" "CR0402-FX-4990GLF"
			(at 82.350871 240.670848 0)
			(layer "F.Fab")
			(hide yes)
			(effects
				(font
					(size 1 1)
					(thickness 0.15)
				)
			)
		)
		(property "Manufacturer" "Bourns"
			(at 82.350871 240.670848 0)
			(layer "F.Fab")
			(hide yes)
			(effects
				(font
					(size 1 1)
					(thickness 0.15)
				)
			)
		)
		(property "Tolerance" "1%"
			(at 82.350871 240.670848 0)
			(layer "F.Fab")
			(hide yes)
			(effects
				(font
					(size 1 1)
					(thickness 0.15)
				)
			)
		)
		(property "Val" "499R"
			(at 82.350871 240.670848 0)
			(layer "F.Fab")
			(hide yes)
			(effects
				(font
					(size 1 1)
					(thickness 0.15)
				)
			)
		)
		(sheetname "HDMI")
		(sheetfile "hdmi.kicad_sch")
		(attr smd)
		(fp_poly
			(pts
				(xy -0.925 -0.47) (xy 0.925 -0.47) (xy 0.925 0.47) (xy -0.925 0.47)
			)
			(stroke
				(width 0.05)
				(type default)
			)
			(fill none)
			(layer "F.CrtYd")
		)
		(fp_poly
			(pts
				(xy -0.5 -0.25) (xy 0.5 -0.25) (xy 0.5 0.25) (xy -0.5 0.25)
			)
			(stroke
				(width 0.15)
				(type solid)
			)
			(fill none)
			(layer "F.Fab")
		)
		(fp_text user "${REFERENCE}"
			(at -0.95 3.168 -135)
			(layer "F.Fab")
			(hide yes)
			(effects
				(font
					(size 0.7 0.7)
					(thickness 0.15)
				)
				(justify left bottom)
			)
		)
		(fp_text user "Author: Antmicro"
			(at -0.95 4.169 -135)
			(layer "F.Fab")
			(hide yes)
			(effects
				(font
					(size 0.7 0.7)
					(thickness 0.15)
				)
				(justify left bottom)
			)
		)
		(fp_text user "License: Apache-2.0"
			(at -0.949999 5.169 -135)
			(layer "F.Fab")
			(hide yes)
			(effects
				(font
					(size 0.7 0.7)
					(thickness 0.15)
				)
				(justify left bottom)
			)
		)
		(pad "1" smd roundrect
			(at -0.48 0 225)
			(size 0.59 0.64)
			(layers "F.Cu" "F.Paste" "F.Mask")
			(roundrect_rratio 0.25)
			(net 623 "Net-(Q2-D)")
			(pintype "passive")
		)
		(pad "2" smd roundrect
			(at 0.48 0 225)
			(size 0.59 0.64)
			(layers "F.Cu" "F.Paste" "F.Mask")
			(roundrect_rratio 0.25)
			(net 494 "/HDMI/HDMI_D0_P")
			(pintype "passive")
		)
	)
	(footprint "antmicro-footprints:R_0402_1005Metric"
		(layer "F.Cu")
		(at 108.175 110.625 90)
		(descr "Resistor SMD 0402")
		(tags "resistor SMD 0402")
		(property "Reference" "R118"
			(at -3.625 0.475 90)
			(layer "F.SilkS")
			(effects
				(font
					(size 0.7 0.7)
					(thickness 0.15)
				)
				(justify left bottom)
			)
		)
		(property "Value" "R_0R_0402"
			(at 0 1.4 90)
			(layer "F.Fab")
			(effects
				(font
					(size 0.7 0.7)
					(thickness 0.15)
				)
				(justify left bottom)
			)
		)
		(property "Footprint" "antmicro-footprints:R_0402_1005Metric"
			(at 0 0 90)
			(layer "F.Fab")
			(hide yes)
			(effects
				(font
					(size 1.27 1.27)
					(thickness 0.15)
				)
			)
		)
		(property "Datasheet" "https://industrial.panasonic.com/cdbs/www-data/pdf/RDA0000/AOA0000C301.pdf"
			(at 0 0 90)
			(layer "F.Fab")
			(hide yes)
			(effects
				(font
					(size 1.27 1.27)
					(thickness 0.15)
				)
			)
		)
		(property "Author" "Antmicro"
			(at 218.8 2.45 0)
			(layer "F.Fab")
			(hide yes)
			(effects
				(font
					(size 1 1)
					(thickness 0.15)
				)
			)
		)
		(property "Current" "1A"
			(at 218.8 2.45 0)
			(layer "F.Fab")
			(hide yes)
			(effects
				(font
					(size 1 1)
					(thickness 0.15)
				)
			)
		)
		(property "License" "Apache-2.0"
			(at 218.8 2.45 0)
			(layer "F.Fab")
			(hide yes)
			(effects
				(font
					(size 1 1)
					(thickness 0.15)
				)
			)
		)
		(property "MPN" "ERJ2GE0R00X"
			(at 218.8 2.45 0)
			(layer "F.Fab")
			(hide yes)
			(effects
				(font
					(size 1 1)
					(thickness 0.15)
				)
			)
		)
		(property "Manufacturer" "Panasonic"
			(at 218.8 2.45 0)
			(layer "F.Fab")
			(hide yes)
			(effects
				(font
					(size 1 1)
					(thickness 0.15)
				)
			)
		)
		(property "Tolerance" ""
			(at 218.8 2.45 0)
			(layer "F.Fab")
			(hide yes)
			(effects
				(font
					(size 1 1)
					(thickness 0.15)
				)
			)
		)
		(property "Val" "0R"
			(at 218.8 2.45 0)
			(layer "F.Fab")
			(hide yes)
			(effects
				(font
					(size 1 1)
					(thickness 0.15)
				)
			)
		)
		(sheetname "USB3")
		(sheetfile "usb3.kicad_sch")
		(attr smd)
		(fp_rect
			(start -0.925 -0.47)
			(end 0.925 0.47)
			(stroke
				(width 0.05)
				(type default)
			)
			(fill none)
			(layer "F.CrtYd")
		)
		(fp_rect
			(start -0.5 -0.25)
			(end 0.5 0.25)
			(stroke
				(width 0.15)
				(type solid)
			)
			(fill none)
			(layer "F.Fab")
		)
		(fp_text user "License: Apache-2.0"
			(at -0.95 5.169 90)
			(layer "F.Fab")
			(hide yes)
			(effects
				(font
					(size 0.7 0.7)
					(thickness 0.15)
				)
				(justify left bottom)
			)
		)
		(fp_text user "${REFERENCE}"
			(at -0.95 3.168 90)
			(layer "F.Fab")
			(hide yes)
			(effects
				(font
					(size 0.7 0.7)
					(thickness 0.15)
				)
				(justify left bottom)
			)
		)
		(fp_text user "Author: Antmicro"
			(at -0.95 4.169 90)
			(layer "F.Fab")
			(hide yes)
			(effects
				(font
					(size 0.7 0.7)
					(thickness 0.15)
				)
				(justify left bottom)
			)
		)
		(pad "1" smd roundrect
			(at -0.48 0 90)
			(size 0.59 0.64)
			(layers "F.Cu" "F.Paste" "F.Mask")
			(roundrect_rratio 0.25)
			(net 1 "GND")
			(pintype "passive")
		)
		(pad "2" smd roundrect
			(at 0.48 0 90)
			(size 0.59 0.64)
			(layers "F.Cu" "F.Paste" "F.Mask")
			(roundrect_rratio 0.25)
			(net 318 "/USB3/~{USBC1_EN_MUX}")
			(pintype "passive")
		)
	)
	(footprint "antmicro-footprints:C_0603_1608Metric_EIA"
		(layer "F.Cu")
		(at 58 94.63 90)
		(descr "Capacitor SMD 0603, IPC-7351 Density Level A")
		(tags "Capacitor 0603")
		(property "Reference" "C129"
			(at -2.32 28.186666 90)
			(layer "F.SilkS")
			(effects
				(font
					(size 0.7 0.7)
					(thickness 0.15)
				)
				(justify left bottom)
			)
		)
		(property "Value" "C_22u_16V_0603"
			(at -1.42757 1.770288 90)
			(layer "F.Fab")
			(effects
				(font
					(size 0.7 0.7)
					(thickness 0.15)
				)
				(justify left bottom)
			)
		)
		(property "Footprint" "antmicro-footprints:C_0603_1608Metric_EIA"
			(at 0 0 90)
			(layer "F.Fab")
			(hide yes)
			(effects
				(font
					(size 1.27 1.27)
					(thickness 0.15)
				)
			)
		)
		(property "Datasheet" "https://product.samsungsem.com/mlcc/CL10A226MO7JZN.do"
			(at 0 0 90)
			(layer "F.Fab")
			(hide yes)
			(effects
				(font
					(size 1.27 1.27)
					(thickness 0.15)
				)
			)
		)
		(property "Description" "SMD Multilayer Ceramic Capacitor"
			(at 0 0 90)
			(layer "F.Fab")
			(hide yes)
			(effects
				(font
					(size 1.27 1.27)
					(thickness 0.15)
				)
			)
		)
		(property "Manufacturer" "Samsung Electro-Mechanics"
			(at 0 0 90)
			(unlocked yes)
			(layer "F.Fab")
			(hide yes)
			(effects
				(font
					(size 1 1)
					(thickness 0.15)
				)
			)
		)
		(property "MPN" "CL10A226MO7JZNC"
			(at 0 0 90)
			(unlocked yes)
			(layer "F.Fab")
			(hide yes)
			(effects
				(font
					(size 1 1)
					(thickness 0.15)
				)
			)
		)
		(property "Val" "22u"
			(at 0 0 90)
			(unlocked yes)
			(layer "F.Fab")
			(hide yes)
			(effects
				(font
					(size 1 1)
					(thickness 0.15)
				)
			)
		)
		(property "License" "Apache-2.0"
			(at 0 0 90)
			(unlocked yes)
			(layer "F.Fab")
			(hide yes)
			(effects
				(font
					(size 1 1)
					(thickness 0.15)
				)
			)
		)
		(property "Author" "Antmicro"
			(at 0 0 90)
			(unlocked yes)
			(layer "F.Fab")
			(hide yes)
			(effects
				(font
					(size 1 1)
					(thickness 0.15)
				)
			)
		)
		(property "Voltage" "16V"
			(at 0 0 90)
			(unlocked yes)
			(layer "F.Fab")
			(hide yes)
			(effects
				(font
					(size 1 1)
					(thickness 0.15)
				)
			)
		)
		(property "Dielectric" ""
			(at 0 0 90)
			(unlocked yes)
			(layer "F.Fab")
			(hide yes)
			(effects
				(font
					(size 1 1)
					(thickness 0.15)
				)
			)
		)
		(sheetname "Supply")
		(sheetfile "supply.kicad_sch")
		(attr smd)
		(fp_line
			(start -0.15 -0.55)
			(end 0.15 -0.55)
			(stroke
				(width 0.15)
				(type solid)
			)
			(layer "F.SilkS")
		)
		(fp_line
			(start -0.15 0.55)
			(end 0.15 0.55)
			(stroke
				(width 0.15)
				(type solid)
			)
			(layer "F.SilkS")
		)
		(fp_rect
			(start -1.25 -0.65)
			(end 1.25 0.65)
			(stroke
				(width 0.05)
				(type solid)
			)
			(fill none)
			(layer "F.CrtYd")
		)
		(fp_rect
			(start -0.8 -0.45)
			(end 0.8 0.45)
			(stroke
				(width 0.15)
				(type solid)
			)
			(fill none)
			(layer "F.Fab")
		)
		(fp_text user "${REFERENCE}"
			(at -1.682 3.895 90)
			(layer "F.Fab")
			(hide yes)
			(effects
				(font
					(size 0.7 0.7)
					(thickness 0.15)
				)
				(justify left bottom)
			)
		)
		(fp_text user "License: Apache-2.0"
			(at -1.682 5.895 90)
			(layer "F.Fab")
			(hide yes)
			(effects
				(font
					(size 0.7 0.7)
					(thickness 0.15)
				)
				(justify left bottom)
			)
		)
		(fp_text user "Author: Antmicro"
			(at -1.682 4.894 90)
			(layer "F.Fab")
			(hide yes)
			(effects
				(font
					(size 0.7 0.7)
					(thickness 0.15)
				)
				(justify left bottom)
			)
		)
		(pad "1" smd roundrect
			(at -0.7 0 90)
			(size 0.8 1.1)
			(layers "F.Cu" "F.Paste" "F.Mask")
			(roundrect_rratio 0.2)
			(net 1 "GND")
			(pintype "passive")
		)
		(pad "2" smd roundrect
			(at 0.7 0 90)
			(size 0.8 1.1)
			(layers "F.Cu" "F.Paste" "F.Mask")
			(roundrect_rratio 0.2)
			(net 761 "/Supply/5V_OUT")
			(pintype "passive")
		)
	)
	(footprint "antmicro-footprints:USON-10_2.5x1mm_P0.5mm"
		(layer "F.Cu")
		(at 116.55 116.178749 90)
		(descr "USON-10 2.5x1mm_ Pitch 0.5mm")
		(tags "USON-10 2.5x1mm Pitch 0.5mm")
		(property "Reference" "U19"
			(at 0.878749 -1 180)
			(layer "F.SilkS")
			(effects
				(font
					(size 0.7 0.7)
					(thickness 0.15)
				)
				(justify left bottom)
			)
		)
		(property "Value" "TPD4E05U06QDQARQ1"
			(at 0.018 2.499 90)
			(layer "F.Fab")
			(effects
				(font
					(size 0.7 0.7)
					(thickness 0.15)
				)
				(justify left bottom)
			)
		)
		(property "Footprint" "antmicro-footprints:USON-10_2.5x1mm_P0.5mm"
			(at 0 0 90)
			(layer "F.Fab")
			(hide yes)
			(effects
				(font
					(size 1.27 1.27)
					(thickness 0.15)
				)
			)
		)
		(property "Datasheet" "https://www.ti.com/lit/ds/symlink/tpd4e05u06-q1.pdf?HQS=dis-mous-null-mousermode-dsf-pf-null-wwe&ts=1663591265741&ref_url=https%253A%252F%252Fwww.mouser.com%252F"
			(at 0 0 90)
			(layer "F.Fab")
			(hide yes)
			(effects
				(font
					(size 1.27 1.27)
					(thickness 0.15)
				)
			)
		)
		(property "Author" "Antmicro"
			(at 232.728749 -0.371251 0)
			(layer "F.Fab")
			(hide yes)
			(effects
				(font
					(size 1 1)
					(thickness 0.15)
				)
			)
		)
		(property "License" "Apache-2.0"
			(at 232.728749 -0.371251 0)
			(layer "F.Fab")
			(hide yes)
			(effects
				(font
					(size 1 1)
					(thickness 0.15)
				)
			)
		)
		(property "MPN" "TPD4E05U06QDQARQ1"
			(at 232.728749 -0.371251 0)
			(layer "F.Fab")
			(hide yes)
			(effects
				(font
					(size 1 1)
					(thickness 0.15)
				)
			)
		)
		(property "Manufacturer" "Texas Instruments"
			(at 232.728749 -0.371251 0)
			(layer "F.Fab")
			(hide yes)
			(effects
				(font
					(size 1 1)
					(thickness 0.15)
				)
			)
		)
		(sheetname "USB3")
		(sheetfile "usb3.kicad_sch")
		(attr smd)
		(fp_line
			(start 0.498 -1.401)
			(end -0.5 -1.401)
			(stroke
				(width 0.15)
				(type solid)
			)
			(layer "F.SilkS")
		)
		(fp_line
			(start 0.498 1.398)
			(end -0.5 1.398)
			(stroke
				(width 0.15)
				(type solid)
			)
			(layer "F.SilkS")
		)
		(fp_circle
			(center -0.68 -1.27)
			(end -0.63 -1.27)
			(stroke
				(width 0.15)
				(type solid)
			)
			(fill solid)
			(layer "F.SilkS")
		)
		(fp_rect
			(start -0.8 -1.5)
			(end 0.8 1.499)
			(stroke
				(width 0.05)
				(type solid)
			)
			(fill none)
			(layer "F.CrtYd")
		)
		(fp_line
			(start 0.498 -1.25)
			(end -0.25 -1.25)
			(stroke
				(width 0.15)
				(type solid)
			)
			(layer "F.Fab")
		)
		(fp_line
			(start 0.498 -1.25)
			(end 0.498 1.249)
			(stroke
				(width 0.15)
				(type solid)
			)
			(layer "F.Fab")
		)
		(fp_line
			(start -0.25 -1.25)
			(end -0.5 -1)
			(stroke
				(width 0.15)
				(type solid)
			)
			(layer "F.Fab")
		)
		(fp_line
			(start -0.5 -1)
			(end -0.5 1.249)
			(stroke
				(width 0.15)
				(type solid)
			)
			(layer "F.Fab")
		)
		(fp_line
			(start -0.5 1.249)
			(end 0.498 1.249)
			(stroke
				(width 0.15)
				(type solid)
			)
			(layer "F.Fab")
		)
		(fp_text user "Author: Antmicro"
			(at -0.802 5.7 90)
			(layer "F.Fab")
			(hide yes)
			(effects
				(font
					(size 0.7 0.7)
					(thickness 0.15)
				)
				(justify left bottom)
			)
		)
		(fp_text user "${REFERENCE}"
			(at -0.802 4.498 90)
			(layer "F.Fab")
			(hide yes)
			(effects
				(font
					(size 0.7 0.7)
					(thickness 0.15)
				)
				(justify left bottom)
			)
		)
		(fp_text user "License: Apache-2.0"
			(at -0.802 6.9 90)
			(layer "F.Fab")
			(hide yes)
			(effects
				(font
					(size 0.7 0.7)
					(thickness 0.15)
				)
				(justify left bottom)
			)
		)
		(pad "1" smd roundrect
			(at -0.387 -1)
			(size 0.25 0.55)
			(layers "F.Cu" "F.Paste" "F.Mask")
			(roundrect_rratio 0.25)
			(net 369 "/USB3/USBC1_RX2_N")
			(pintype "passive")
		)
		(pad "2" smd roundrect
			(at -0.387 -0.5)
			(size 0.25 0.55)
			(layers "F.Cu" "F.Paste" "F.Mask")
			(roundrect_rratio 0.25)
			(net 390 "/USB3/USBC1_RX2_P")
			(pintype "passive")
		)
		(pad "3" smd roundrect
			(at -0.387 0)
			(size 0.4 0.55)
			(layers "F.Cu" "F.Paste" "F.Mask")
			(roundrect_rratio 0.25)
			(net 1 "GND")
			(pintype "power_in")
		)
		(pad "4" smd roundrect
			(at -0.387 0.498)
			(size 0.25 0.55)
			(layers "F.Cu" "F.Paste" "F.Mask")
			(roundrect_rratio 0.25)
			(net 263 "/USB3/USBC1_CONN_TX2_N")
			(pintype "passive")
		)
		(pad "5" smd roundrect
			(at -0.387 0.998)
			(size 0.25 0.55)
			(layers "F.Cu" "F.Paste" "F.Mask")
			(roundrect_rratio 0.25)
			(net 269 "/USB3/USBC1_CONN_TX2_P")
			(pintype "passive")
		)
		(pad "6" smd roundrect
			(at 0.385 0.998)
			(size 0.25 0.55)
			(layers "F.Cu" "F.Paste" "F.Mask")
			(roundrect_rratio 0.25)
			(net 269 "/USB3/USBC1_CONN_TX2_P")
			(pintype "passive")
		)
		(pad "7" smd roundrect
			(at 0.385 0.498)
			(size 0.25 0.55)
			(layers "F.Cu" "F.Paste" "F.Mask")
			(roundrect_rratio 0.25)
			(net 263 "/USB3/USBC1_CONN_TX2_N")
			(pintype "passive")
		)
		(pad "8" smd roundrect
			(at 0.385 0)
			(size 0.4 0.55)
			(layers "F.Cu" "F.Paste" "F.Mask")
			(roundrect_rratio 0.25)
			(net 1 "GND")
			(pintype "passive")
		)
		(pad "9" smd roundrect
			(at 0.385 -0.5)
			(size 0.25 0.55)
			(layers "F.Cu" "F.Paste" "F.Mask")
			(roundrect_rratio 0.25)
			(net 390 "/USB3/USBC1_RX2_P")
			(pintype "passive")
		)
		(pad "10" smd roundrect
			(at 0.385 -1)
			(size 0.25 0.55)
			(layers "F.Cu" "F.Paste" "F.Mask")
			(roundrect_rratio 0.25)
			(net 369 "/USB3/USBC1_RX2_N")
			(pintype "passive")
		)
	)
	(footprint "antmicro-footprints:Spacer_Drill3.7mm_H6.5mm_9774065151R"
		(locked yes)
		(layer "F.Cu")
		(at 60.925 118.1)
		(descr "Spacer M=3 h=6.5mm fi=5.1mm")
		(property "Reference" "H1"
			(at -3.425 -2.6 0)
			(layer "F.SilkS")
			(effects
				(font
					(size 0.7 0.7)
					(thickness 0.15)
				)
				(justify left bottom)
			)
		)
		(property "Value" "Spacer_Drill3.7mm_H6.5mm_9774065151R"
			(at 0 4 0)
			(layer "F.Fab")
			(effects
				(font
					(size 0.7 0.7)
					(thickness 0.15)
				)
				(justify left bottom)
			)
		)
		(property "Footprint" "antmicro-footprints:Spacer_Drill3.7mm_H6.5mm_9774065151R"
			(at 0 0 0)
			(layer "F.Fab")
			(hide yes)
			(effects
				(font
					(size 1.27 1.27)
					(thickness 0.15)
				)
			)
		)
		(property "Datasheet" "https://www.we-online.com/components/products/datasheet/9774065151R.pdf"
			(at 0 0 0)
			(layer "F.Fab")
			(hide yes)
			(effects
				(font
					(size 1.27 1.27)
					(thickness 0.15)
				)
			)
		)
		(property "Author" "Antmicro"
			(at 0 0 0)
			(layer "F.Fab")
			(hide yes)
			(effects
				(font
					(size 1 1)
					(thickness 0.15)
				)
			)
		)
		(property "License" "Apache-2.0"
			(at 0 0 0)
			(layer "F.Fab")
			(hide yes)
			(effects
				(font
					(size 1 1)
					(thickness 0.15)
				)
			)
		)
		(property "MPN" "9774065151R"
			(at 0 0 0)
			(layer "F.Fab")
			(hide yes)
			(effects
				(font
					(size 1 1)
					(thickness 0.15)
				)
			)
		)
		(property "Manufacturer" "Würth Elektronik"
			(at 0 0 0)
			(layer "F.Fab")
			(hide yes)
			(effects
				(font
					(size 1 1)
					(thickness 0.15)
				)
			)
		)
		(sheetname "SoM")
		(sheetfile "som.kicad_sch")
		(solder_paste_ratio -1)
		(attr smd)
		(fp_circle
			(center 0 0)
			(end 3.05 0)
			(stroke
				(width 0.05)
				(type solid)
			)
			(fill none)
			(layer "F.CrtYd")
		)
		(fp_circle
			(center 0 0)
			(end 2.6 0)
			(stroke
				(width 0.15)
				(type solid)
			)
			(fill none)
			(layer "F.Fab")
		)
		(fp_text user "${REFERENCE}"
			(at -3.05041 8.3 0)
			(layer "F.Fab")
			(hide yes)
			(effects
				(font
					(size 0.7 0.7)
					(thickness 0.15)
				)
				(justify left bottom)
			)
		)
		(fp_text user "Author: Antmicro"
			(at -3.05041 7.1 0)
			(layer "F.Fab")
			(hide yes)
			(effects
				(font
					(size 0.7 0.7)
					(thickness 0.15)
				)
				(justify left bottom)
			)
		)
		(fp_text user "License: Apache-2.0"
			(at -3.05041 5.9 0)
			(layer "F.Fab")
			(hide yes)
			(effects
				(font
					(size 0.7 0.7)
					(thickness 0.15)
				)
				(justify left bottom)
			)
		)
		(pad "" smd custom
			(at -1.7 -1.7)
			(size 0.62 0.62)
			(layers "F.Paste")
			(thermal_bridge_angle 90)
			(options
				(clearance outline)
				(anchor circle)
			)
			(primitives
				(gr_arc
					(start -0.250195 1.279127)
					(mid 0.285453 0.294389)
					(end 1.266786 -0.24747)
					(width 0.2)
				)
				(gr_arc
					(start -0.34334 1.279127)
					(mid 0.218448 0.232561)
					(end 1.259603 -0.339191)
					(width 0.2)
				)
				(gr_arc
					(start -0.436309 1.279127)
					(mid 0.152481 0.169693)
					(end 1.255279 -0.431435)
					(width 0.2)
				)
				(gr_arc
					(start -0.529126 1.279127)
					(mid 0.087542 0.105784)
					(end 1.253811 -0.524161)
					(width 0.2)
				)
				(gr_arc
					(start -0.621807 1.279127)
					(mid 0.0309 0.033527)
					(end 1.275473 -0.621136)
					(width 0.2)
				)
				(gr_arc
					(start -0.71437 1.279127)
					(mid -0.037758 -0.026651)
					(end 1.263664 -0.711602)
					(width 0.2)
				)
				(gr_arc
					(start -0.806826 1.279127)
					(mid -0.105837 -0.087395)
					(end 1.253435 -0.802342)
					(width 0.2)
				)
				(gr_arc
					(start -0.899187 1.279127)
					(mid -0.165236 -0.156885)
					(end 1.267475 -0.897258)
					(width 0.2)
				)
				(gr_arc
					(start -0.991463 1.279127)
					(mid -0.228522 -0.222449)
					(end 1.270645 -0.990112)
					(width 0.2)
				)
				(gr_arc
					(start -1.083663 1.279127)
					(mid -0.294507 -0.285313)
					(end 1.266278 -1.081674)
					(width 0.2)
				)
				(gr_line
					(start 1.279127 -0.250195)
					(end 1.279127 -1.083663)
					(width 0.2)
				)
				(gr_line
					(start -0.250195 1.279127)
					(end -1.083663 1.279127)
					(width 0.2)
				)
			)
		)
		(pad "" smd custom
			(at -1.7 1.7 90)
			(size 0.62 0.62)
			(layers "F.Paste")
			(thermal_bridge_angle 90)
			(options
				(clearance outline)
				(anchor circle)
			)
			(primitives
				(gr_arc
					(start -0.250195 1.279127)
					(mid 0.285453 0.294389)
					(end 1.266786 -0.24747)
					(width 0.2)
				)
				(gr_arc
					(start -0.34334 1.279127)
					(mid 0.218448 0.232561)
					(end 1.259603 -0.339191)
					(width 0.2)
				)
				(gr_arc
					(start -0.436309 1.279127)
					(mid 0.152481 0.169693)
					(end 1.255279 -0.431435)
					(width 0.2)
				)
				(gr_arc
					(start -0.529126 1.279127)
					(mid 0.087542 0.105784)
					(end 1.253811 -0.524161)
					(width 0.2)
				)
				(gr_arc
					(start -0.621807 1.279127)
					(mid 0.0309 0.033527)
					(end 1.275473 -0.621136)
					(width 0.2)
				)
				(gr_arc
					(start -0.71437 1.279127)
					(mid -0.037758 -0.026651)
					(end 1.263664 -0.711602)
					(width 0.2)
				)
				(gr_arc
					(start -0.806826 1.279127)
					(mid -0.105837 -0.087395)
					(end 1.253435 -0.802342)
					(width 0.2)
				)
				(gr_arc
					(start -0.899187 1.279127)
					(mid -0.165236 -0.156885)
					(end 1.267475 -0.897258)
					(width 0.2)
				)
				(gr_arc
					(start -0.991463 1.279127)
					(mid -0.228522 -0.222449)
					(end 1.270645 -0.990112)
					(width 0.2)
				)
				(gr_arc
					(start -1.083663 1.279127)
					(mid -0.294507 -0.285313)
					(end 1.266278 -1.081674)
					(width 0.2)
				)
				(gr_line
					(start 1.279127 -0.250195)
					(end 1.279127 -1.083663)
					(width 0.2)
				)
				(gr_line
					(start -0.250195 1.279127)
					(end -1.083663 1.279127)
					(width 0.2)
				)
			)
		)
		(pad "" smd custom
			(at 1.7 -1.7 270)
			(size 0.62 0.62)
			(layers "F.Paste")
			(thermal_bridge_angle 90)
			(options
				(clearance outline)
				(anchor circle)
			)
			(primitives
				(gr_arc
					(start -0.250195 1.279127)
					(mid 0.285453 0.294389)
					(end 1.266786 -0.24747)
					(width 0.2)
				)
				(gr_arc
					(start -0.34334 1.279127)
					(mid 0.218448 0.232561)
					(end 1.259603 -0.339191)
					(width 0.2)
				)
				(gr_arc
					(start -0.436309 1.279127)
					(mid 0.152481 0.169693)
					(end 1.255279 -0.431435)
					(width 0.2)
				)
				(gr_arc
					(start -0.529126 1.279127)
					(mid 0.087542 0.105784)
					(end 1.253811 -0.524161)
					(width 0.2)
				)
				(gr_arc
					(start -0.621807 1.279127)
					(mid 0.0309 0.033527)
					(end 1.275473 -0.621136)
					(width 0.2)
				)
				(gr_arc
					(start -0.71437 1.279127)
					(mid -0.037758 -0.026651)
					(end 1.263664 -0.711602)
					(width 0.2)
				)
				(gr_arc
					(start -0.806826 1.279127)
					(mid -0.105837 -0.087395)
					(end 1.253435 -0.802342)
					(width 0.2)
				)
				(gr_arc
					(start -0.899187 1.279127)
					(mid -0.165236 -0.156885)
					(end 1.267475 -0.897258)
					(width 0.2)
				)
				(gr_arc
					(start -0.991463 1.279127)
					(mid -0.228522 -0.222449)
					(end 1.270645 -0.990112)
					(width 0.2)
				)
				(gr_arc
					(start -1.083663 1.279127)
					(mid -0.294507 -0.285313)
					(end 1.266278 -1.081674)
					(width 0.2)
				)
				(gr_line
					(start 1.279127 -0.250195)
					(end 1.279127 -1.083663)
					(width 0.2)
				)
				(gr_line
					(start -0.250195 1.279127)
					(end -1.083663 1.279127)
					(width 0.2)
				)
			)
		)
		(pad "" smd custom
			(at 1.7 1.7 180)
			(size 0.62 0.62)
			(layers "F.Paste")
			(thermal_bridge_angle 90)
			(options
				(clearance outline)
				(anchor circle)
			)
			(primitives
				(gr_arc
					(start -0.250195 1.279127)
					(mid 0.285453 0.294389)
					(end 1.266786 -0.24747)
					(width 0.2)
				)
				(gr_arc
					(start -0.34334 1.279127)
					(mid 0.218448 0.232561)
					(end 1.259603 -0.339191)
					(width 0.2)
				)
				(gr_arc
					(start -0.436309 1.279127)
					(mid 0.152481 0.169693)
					(end 1.255279 -0.431435)
					(width 0.2)
				)
				(gr_arc
					(start -0.529126 1.279127)
					(mid 0.087542 0.105784)
					(end 1.253811 -0.524161)
					(width 0.2)
				)
				(gr_arc
					(start -0.621807 1.279127)
					(mid 0.0309 0.033527)
					(end 1.275473 -0.621136)
					(width 0.2)
				)
				(gr_arc
					(start -0.71437 1.279127)
					(mid -0.037758 -0.026651)
					(end 1.263664 -0.711602)
					(width 0.2)
				)
				(gr_arc
					(start -0.806826 1.279127)
					(mid -0.105837 -0.087395)
					(end 1.253435 -0.802342)
					(width 0.2)
				)
				(gr_arc
					(start -0.899187 1.279127)
					(mid -0.165236 -0.156885)
					(end 1.267475 -0.897258)
					(width 0.2)
				)
				(gr_arc
					(start -0.991463 1.279127)
					(mid -0.228522 -0.222449)
					(end 1.270645 -0.990112)
					(width 0.2)
				)
				(gr_arc
					(start -1.083663 1.279127)
					(mid -0.294507 -0.285313)
					(end 1.266278 -1.081674)
					(width 0.2)
				)
				(gr_line
					(start 1.279127 -0.250195)
					(end 1.279127 -1.083663)
					(width 0.2)
				)
				(gr_line
					(start -0.250195 1.279127)
					(end -1.083663 1.279127)
					(width 0.2)
				)
			)
		)
		(pad "1" thru_hole circle
			(at 0 0)
			(size 6 6)
			(drill 3.7)
			(layers "*.Cu" "*.Mask")
			(remove_unused_layers no)
			(net 1 "GND")
			(pintype "passive")
		)
	)
	(footprint "antmicro-footprints:R_0402_1005Metric"
		(layer "F.Cu")
		(at 61.6 105)
		(descr "Resistor SMD 0402")
		(tags "resistor SMD 0402")
		(property "Reference" "R76"
			(at 0.75 0.475 0)
			(layer "F.SilkS")
			(effects
				(font
					(size 0.7 0.7)
					(thickness 0.15)
				)
				(justify left bottom)
			)
		)
		(property "Value" "R_0R_0402"
			(at 0 1.4 0)
			(layer "F.Fab")
			(effects
				(font
					(size 0.7 0.7)
					(thickness 0.15)
				)
				(justify left bottom)
			)
		)
		(property "Footprint" "antmicro-footprints:R_0402_1005Metric"
			(at 0 0 0)
			(layer "F.Fab")
			(hide yes)
			(effects
				(font
					(size 1.27 1.27)
					(thickness 0.15)
				)
			)
		)
		(property "Datasheet" "https://industrial.panasonic.com/cdbs/www-data/pdf/RDA0000/AOA0000C301.pdf"
			(at 0 0 0)
			(layer "F.Fab")
			(hide yes)
			(effects
				(font
					(size 1.27 1.27)
					(thickness 0.15)
				)
			)
		)
		(property "Author" "Antmicro"
			(at 0 0 0)
			(layer "F.Fab")
			(hide yes)
			(effects
				(font
					(size 1 1)
					(thickness 0.15)
				)
			)
		)
		(property "Current" "1A"
			(at 0 0 0)
			(layer "F.Fab")
			(hide yes)
			(effects
				(font
					(size 1 1)
					(thickness 0.15)
				)
			)
		)
		(property "License" "Apache-2.0"
			(at 0 0 0)
			(layer "F.Fab")
			(hide yes)
			(effects
				(font
					(size 1 1)
					(thickness 0.15)
				)
			)
		)
		(property "MPN" "ERJ2GE0R00X"
			(at 0 0 0)
			(layer "F.Fab")
			(hide yes)
			(effects
				(font
					(size 1 1)
					(thickness 0.15)
				)
			)
		)
		(property "Manufacturer" "Panasonic"
			(at 0 0 0)
			(layer "F.Fab")
			(hide yes)
			(effects
				(font
					(size 1 1)
					(thickness 0.15)
				)
			)
		)
		(property "Tolerance" ""
			(at 0 0 0)
			(layer "F.Fab")
			(hide yes)
			(effects
				(font
					(size 1 1)
					(thickness 0.15)
				)
			)
		)
		(property "Val" "0R"
			(at 0 0 0)
			(layer "F.Fab")
			(hide yes)
			(effects
				(font
					(size 1 1)
					(thickness 0.15)
				)
			)
		)
		(sheetname "USB Debug, DP")
		(sheetfile "usb.kicad_sch")
		(attr smd)
		(fp_rect
			(start -0.925 -0.47)
			(end 0.925 0.47)
			(stroke
				(width 0.05)
				(type default)
			)
			(fill none)
			(layer "F.CrtYd")
		)
		(fp_rect
			(start -0.5 -0.25)
			(end 0.5 0.25)
			(stroke
				(width 0.15)
				(type solid)
			)
			(fill none)
			(layer "F.Fab")
		)
		(fp_text user "${REFERENCE}"
			(at -0.95 3.168 0)
			(layer "F.Fab")
			(hide yes)
			(effects
				(font
					(size 0.7 0.7)
					(thickness 0.15)
				)
				(justify left bottom)
			)
		)
		(fp_text user "License: Apache-2.0"
			(at -0.95 5.169 0)
			(layer "F.Fab")
			(hide yes)
			(effects
				(font
					(size 0.7 0.7)
					(thickness 0.15)
				)
				(justify left bottom)
			)
		)
		(fp_text user "Author: Antmicro"
			(at -0.95 4.169 0)
			(layer "F.Fab")
			(hide yes)
			(effects
				(font
					(size 0.7 0.7)
					(thickness 0.15)
				)
				(justify left bottom)
			)
		)
		(pad "1" smd roundrect
			(at -0.48 0)
			(size 0.59 0.64)
			(layers "F.Cu" "F.Paste" "F.Mask")
			(roundrect_rratio 0.25)
			(net 549 "/USB Debug, DP/USBC3_5V_PEN")
			(pintype "passive")
		)
		(pad "2" smd roundrect
			(at 0.48 0)
			(size 0.59 0.64)
			(layers "F.Cu" "F.Paste" "F.Mask")
			(roundrect_rratio 0.25)
			(net 657 "Net-(U9-EN)")
			(pintype "passive")
		)
	)
	(footprint "antmicro-footprints:R_0402_1005Metric"
		(layer "F.Cu")
		(at 44.141 104.394 -90)
		(descr "Resistor SMD 0402")
		(tags "resistor SMD 0402")
		(property "Reference" "R185"
			(at 1.356 -1.309 -90)
			(layer "F.SilkS")
			(effects
				(font
					(size 0.7 0.7)
					(thickness 0.15)
				)
				(justify left bottom)
			)
		)
		(property "Value" "R_100k_0402"
			(at 0 1.4 -90)
			(layer "F.Fab")
			(effects
				(font
					(size 0.7 0.7)
					(thickness 0.15)
				)
				(justify left bottom)
			)
		)
		(property "Footprint" "antmicro-footprints:R_0402_1005Metric"
			(at 0 0 -90)
			(layer "F.Fab")
			(hide yes)
			(effects
				(font
					(size 1.27 1.27)
					(thickness 0.15)
				)
			)
		)
		(property "Datasheet" "https://www.bourns.com/docs/product-datasheets/cr.pdf"
			(at 0 0 -90)
			(layer "F.Fab")
			(hide yes)
			(effects
				(font
					(size 1.27 1.27)
					(thickness 0.15)
				)
			)
		)
		(property "Author" "Antmicro"
			(at -60.253 148.535 0)
			(layer "F.Fab")
			(hide yes)
			(effects
				(font
					(size 1 1)
					(thickness 0.15)
				)
			)
		)
		(property "License" "Apache-2.0"
			(at -60.253 148.535 0)
			(layer "F.Fab")
			(hide yes)
			(effects
				(font
					(size 1 1)
					(thickness 0.15)
				)
			)
		)
		(property "MPN" "CR0402-FX-1003GLF"
			(at -60.253 148.535 0)
			(layer "F.Fab")
			(hide yes)
			(effects
				(font
					(size 1 1)
					(thickness 0.15)
				)
			)
		)
		(property "Manufacturer" "Bourns"
			(at -60.253 148.535 0)
			(layer "F.Fab")
			(hide yes)
			(effects
				(font
					(size 1 1)
					(thickness 0.15)
				)
			)
		)
		(property "Tolerance" "1%"
			(at -60.253 148.535 0)
			(layer "F.Fab")
			(hide yes)
			(effects
				(font
					(size 1 1)
					(thickness 0.15)
				)
			)
		)
		(property "Val" "100k"
			(at -60.253 148.535 0)
			(layer "F.Fab")
			(hide yes)
			(effects
				(font
					(size 1 1)
					(thickness 0.15)
				)
			)
		)
		(sheetname "Ethernet")
		(sheetfile "ethernet.kicad_sch")
		(attr smd)
		(fp_rect
			(start -0.925 -0.47)
			(end 0.925 0.47)
			(stroke
				(width 0.05)
				(type default)
			)
			(fill none)
			(layer "F.CrtYd")
		)
		(fp_rect
			(start -0.5 -0.25)
			(end 0.5 0.25)
			(stroke
				(width 0.15)
				(type solid)
			)
			(fill none)
			(layer "F.Fab")
		)
		(fp_text user "Author: Antmicro"
			(at -0.95 4.169 -90)
			(layer "F.Fab")
			(hide yes)
			(effects
				(font
					(size 0.7 0.7)
					(thickness 0.15)
				)
				(justify left bottom)
			)
		)
		(fp_text user "${REFERENCE}"
			(at -0.95 3.168 -90)
			(layer "F.Fab")
			(hide yes)
			(effects
				(font
					(size 0.7 0.7)
					(thickness 0.15)
				)
				(justify left bottom)
			)
		)
		(fp_text user "License: Apache-2.0"
			(at -0.95 5.169 -90)
			(layer "F.Fab")
			(hide yes)
			(effects
				(font
					(size 0.7 0.7)
					(thickness 0.15)
				)
				(justify left bottom)
			)
		)
		(pad "1" smd roundrect
			(at -0.48 0 270)
			(size 0.59 0.64)
			(layers "F.Cu" "F.Paste" "F.Mask")
			(roundrect_rratio 0.25)
			(net 106 "GNDD")
			(pintype "passive")
		)
		(pad "2" smd roundrect
			(at 0.48 0 270)
			(size 0.59 0.64)
			(layers "F.Cu" "F.Paste" "F.Mask")
			(roundrect_rratio 0.25)
			(net 127 "/Ethernet/POE_ACTIVE")
			(pintype "passive")
		)
	)
	(footprint "antmicro-footprints:USON-10_2.5x1mm_P0.5mm"
		(layer "F.Cu")
		(at 96.675 119.9 90)
		(descr "USON-10 2.5x1mm_ Pitch 0.5mm")
		(tags "USON-10 2.5x1mm Pitch 0.5mm")
		(property "Reference" "U44"
			(at -0.1 3.325 -90)
			(layer "F.SilkS")
			(effects
				(font
					(size 0.7 0.7)
					(thickness 0.15)
				)
				(justify left bottom)
			)
		)
		(property "Value" "TPD4E05U06QDQARQ1"
			(at 0.018 2.499 90)
			(layer "F.Fab")
			(effects
				(font
					(size 0.7 0.7)
					(thickness 0.15)
				)
				(justify left bottom)
			)
		)
		(property "Footprint" "antmicro-footprints:USON-10_2.5x1mm_P0.5mm"
			(at 0 0 90)
			(layer "F.Fab")
			(hide yes)
			(effects
				(font
					(size 1.27 1.27)
					(thickness 0.15)
				)
			)
		)
		(property "Datasheet" "https://www.ti.com/lit/ds/symlink/tpd4e05u06-q1.pdf?HQS=dis-mous-null-mousermode-dsf-pf-null-wwe&ts=1663591265741&ref_url=https%253A%252F%252Fwww.mouser.com%252F"
			(at 0 0 90)
			(layer "F.Fab")
			(hide yes)
			(effects
				(font
					(size 1.27 1.27)
					(thickness 0.15)
				)
			)
		)
		(property "Author" "Antmicro"
			(at 216.575 23.225 0)
			(layer "F.Fab")
			(hide yes)
			(effects
				(font
					(size 1 1)
					(thickness 0.15)
				)
			)
		)
		(property "License" "Apache-2.0"
			(at 216.575 23.225 0)
			(layer "F.Fab")
			(hide yes)
			(effects
				(font
					(size 1 1)
					(thickness 0.15)
				)
			)
		)
		(property "MPN" "TPD4E05U06QDQARQ1"
			(at 216.575 23.225 0)
			(layer "F.Fab")
			(hide yes)
			(effects
				(font
					(size 1 1)
					(thickness 0.15)
				)
			)
		)
		(property "Manufacturer" "Texas Instruments"
			(at 216.575 23.225 0)
			(layer "F.Fab")
			(hide yes)
			(effects
				(font
					(size 1 1)
					(thickness 0.15)
				)
			)
		)
		(sheetname "HDMI")
		(sheetfile "hdmi.kicad_sch")
		(attr smd)
		(fp_line
			(start 0.498 -1.401)
			(end -0.5 -1.401)
			(stroke
				(width 0.15)
				(type solid)
			)
			(layer "F.SilkS")
		)
		(fp_line
			(start 0.498 1.398)
			(end -0.5 1.398)
			(stroke
				(width 0.15)
				(type solid)
			)
			(layer "F.SilkS")
		)
		(fp_circle
			(center -0.68 -1.27)
			(end -0.63 -1.27)
			(stroke
				(width 0.15)
				(type solid)
			)
			(fill solid)
			(layer "F.SilkS")
		)
		(fp_rect
			(start -0.8 -1.5)
			(end 0.8 1.499)
			(stroke
				(width 0.05)
				(type solid)
			)
			(fill none)
			(layer "F.CrtYd")
		)
		(fp_line
			(start 0.498 -1.25)
			(end -0.25 -1.25)
			(stroke
				(width 0.15)
				(type solid)
			)
			(layer "F.Fab")
		)
		(fp_line
			(start 0.498 -1.25)
			(end 0.498 1.249)
			(stroke
				(width 0.15)
				(type solid)
			)
			(layer "F.Fab")
		)
		(fp_line
			(start -0.25 -1.25)
			(end -0.5 -1)
			(stroke
				(width 0.15)
				(type solid)
			)
			(layer "F.Fab")
		)
		(fp_line
			(start -0.5 -1)
			(end -0.5 1.249)
			(stroke
				(width 0.15)
				(type solid)
			)
			(layer "F.Fab")
		)
		(fp_line
			(start -0.5 1.249)
			(end 0.498 1.249)
			(stroke
				(width 0.15)
				(type solid)
			)
			(layer "F.Fab")
		)
		(fp_text user "${REFERENCE}"
			(at -0.802 4.498 90)
			(layer "F.Fab")
			(hide yes)
			(effects
				(font
					(size 0.7 0.7)
					(thickness 0.15)
				)
				(justify left bottom)
			)
		)
		(fp_text user "License: Apache-2.0"
			(at -0.802 6.9 90)
			(layer "F.Fab")
			(hide yes)
			(effects
				(font
					(size 0.7 0.7)
					(thickness 0.15)
				)
				(justify left bottom)
			)
		)
		(fp_text user "Author: Antmicro"
			(at -0.802 5.7 90)
			(layer "F.Fab")
			(hide yes)
			(effects
				(font
					(size 0.7 0.7)
					(thickness 0.15)
				)
				(justify left bottom)
			)
		)
		(pad "1" smd roundrect
			(at -0.387 -1)
			(size 0.25 0.55)
			(layers "F.Cu" "F.Paste" "F.Mask")
			(roundrect_rratio 0.25)
			(net 525 "/HDMI/HDMI_D1_CONN_N")
			(pintype "passive")
		)
		(pad "2" smd roundrect
			(at -0.387 -0.5)
			(size 0.25 0.55)
			(layers "F.Cu" "F.Paste" "F.Mask")
			(roundrect_rratio 0.25)
			(net 526 "/HDMI/HDMI_D1_CONN_P")
			(pintype "passive")
		)
		(pad "3" smd roundrect
			(at -0.387 0)
			(size 0.4 0.55)
			(layers "F.Cu" "F.Paste" "F.Mask")
			(roundrect_rratio 0.25)
			(net 1 "GND")
			(pintype "power_in")
		)
		(pad "4" smd roundrect
			(at -0.387 0.498)
			(size 0.25 0.55)
			(layers "F.Cu" "F.Paste" "F.Mask")
			(roundrect_rratio 0.25)
			(net 527 "/HDMI/HDMI_D2_CONN_N")
			(pintype "passive")
		)
		(pad "5" smd roundrect
			(at -0.387 0.998)
			(size 0.25 0.55)
			(layers "F.Cu" "F.Paste" "F.Mask")
			(roundrect_rratio 0.25)
			(net 528 "/HDMI/HDMI_D2_CONN_P")
			(pintype "passive")
		)
		(pad "6" smd roundrect
			(at 0.385 0.998)
			(size 0.25 0.55)
			(layers "F.Cu" "F.Paste" "F.Mask")
			(roundrect_rratio 0.25)
			(net 528 "/HDMI/HDMI_D2_CONN_P")
			(pintype "passive")
		)
		(pad "7" smd roundrect
			(at 0.385 0.498)
			(size 0.25 0.55)
			(layers "F.Cu" "F.Paste" "F.Mask")
			(roundrect_rratio 0.25)
			(net 527 "/HDMI/HDMI_D2_CONN_N")
			(pintype "passive")
		)
		(pad "8" smd roundrect
			(at 0.385 0)
			(size 0.4 0.55)
			(layers "F.Cu" "F.Paste" "F.Mask")
			(roundrect_rratio 0.25)
			(net 1 "GND")
			(pintype "passive")
		)
		(pad "9" smd roundrect
			(at 0.385 -0.5)
			(size 0.25 0.55)
			(layers "F.Cu" "F.Paste" "F.Mask")
			(roundrect_rratio 0.25)
			(net 526 "/HDMI/HDMI_D1_CONN_P")
			(pintype "passive")
		)
		(pad "10" smd roundrect
			(at 0.385 -1)
			(size 0.25 0.55)
			(layers "F.Cu" "F.Paste" "F.Mask")
			(roundrect_rratio 0.25)
			(net 525 "/HDMI/HDMI_D1_CONN_N")
			(pintype "passive")
		)
	)
	(footprint "antmicro-footprints:R_0402_1005Metric"
		(layer "F.Cu")
		(at 62.32 101.52)
		(descr "Resistor SMD 0402")
		(tags "resistor SMD 0402")
		(property "Reference" "R159"
			(at 2.93 3.48 0)
			(layer "F.SilkS")
			(effects
				(font
					(size 0.7 0.7)
					(thickness 0.15)
				)
				(justify left bottom)
			)
		)
		(property "Value" "R_499k_0402"
			(at -1.011843 1.772047 0)
			(layer "F.Fab")
			(effects
				(font
					(size 0.7 0.7)
					(thickness 0.15)
				)
				(justify left bottom)
			)
		)
		(property "Footprint" "antmicro-footprints:R_0402_1005Metric"
			(at 0 0 0)
			(layer "F.Fab")
			(hide yes)
			(effects
				(font
					(size 1.27 1.27)
					(thickness 0.15)
				)
			)
		)
		(property "Datasheet" "https://www.mouser.com/datasheet/2/54/cr-1858361.pdf"
			(at 0 0 0)
			(layer "F.Fab")
			(hide yes)
			(effects
				(font
					(size 1.27 1.27)
					(thickness 0.15)
				)
			)
		)
		(property "Author" "Antmicro"
			(at 0 0 0)
			(layer "F.Fab")
			(hide yes)
			(effects
				(font
					(size 1 1)
					(thickness 0.15)
				)
			)
		)
		(property "License" "Apache-2.0"
			(at 0 0 0)
			(layer "F.Fab")
			(hide yes)
			(effects
				(font
					(size 1 1)
					(thickness 0.15)
				)
			)
		)
		(property "MPN" "CR0402-FX-4993GLF"
			(at 0 0 0)
			(layer "F.Fab")
			(hide yes)
			(effects
				(font
					(size 1 1)
					(thickness 0.15)
				)
			)
		)
		(property "Manufacturer" "Bourns"
			(at 0 0 0)
			(layer "F.Fab")
			(hide yes)
			(effects
				(font
					(size 1 1)
					(thickness 0.15)
				)
			)
		)
		(property "Tolerance" "1%"
			(at 0 0 0)
			(layer "F.Fab")
			(hide yes)
			(effects
				(font
					(size 1 1)
					(thickness 0.15)
				)
			)
		)
		(property "Val" "499k"
			(at 0 0 0)
			(layer "F.Fab")
			(hide yes)
			(effects
				(font
					(size 1 1)
					(thickness 0.15)
				)
			)
		)
		(sheetname "Supply")
		(sheetfile "supply.kicad_sch")
		(attr smd exclude_from_pos_files exclude_from_bom dnp)
		(fp_rect
			(start -0.925 -0.47)
			(end 0.925 0.47)
			(stroke
				(width 0.05)
				(type default)
			)
			(fill none)
			(layer "F.CrtYd")
		)
		(fp_rect
			(start -0.5 -0.25)
			(end 0.5 0.25)
			(stroke
				(width 0.15)
				(type solid)
			)
			(fill none)
			(layer "F.Fab")
		)
		(fp_text user "License: Apache-2.0"
			(at -0.95 5.169 0)
			(layer "F.Fab")
			(hide yes)
			(effects
				(font
					(size 0.7 0.7)
					(thickness 0.15)
				)
				(justify left bottom)
			)
		)
		(fp_text user "${REFERENCE}"
			(at -0.95 3.168 0)
			(layer "F.Fab")
			(hide yes)
			(effects
				(font
					(size 0.7 0.7)
					(thickness 0.15)
				)
				(justify left bottom)
			)
		)
		(fp_text user "Author: Antmicro"
			(at -0.95 4.169 0)
			(layer "F.Fab")
			(hide yes)
			(effects
				(font
					(size 0.7 0.7)
					(thickness 0.15)
				)
				(justify left bottom)
			)
		)
		(pad "1" smd roundrect
			(at -0.48 0)
			(size 0.59 0.64)
			(layers "F.Cu" "F.Paste" "F.Mask")
			(roundrect_rratio 0.25)
			(net 764 "/Supply/5V_MODE1")
			(pintype "passive")
		)
		(pad "2" smd roundrect
			(at 0.48 0)
			(size 0.59 0.64)
			(layers "F.Cu" "F.Paste" "F.Mask")
			(roundrect_rratio 0.25)
			(net 759 "/Supply/5V_VDD")
			(pintype "passive")
		)
	)
	(footprint "antmicro-footprints:R_0402_1005Metric"
		(layer "F.Cu")
		(at 65.05 113.1 -90)
		(descr "Resistor SMD 0402")
		(tags "resistor SMD 0402")
		(property "Reference" "R158"
			(at 1.2 -1.3 -90)
			(layer "F.SilkS")
			(effects
				(font
					(size 0.7 0.7)
					(thickness 0.15)
				)
				(justify left bottom)
			)
		)
		(property "Value" "R_0R_0402"
			(at 0 1.4 -90)
			(layer "F.Fab")
			(effects
				(font
					(size 0.7 0.7)
					(thickness 0.15)
				)
				(justify left bottom)
			)
		)
		(property "Footprint" "antmicro-footprints:R_0402_1005Metric"
			(at 0 0 -90)
			(layer "F.Fab")
			(hide yes)
			(effects
				(font
					(size 1.27 1.27)
					(thickness 0.15)
				)
			)
		)
		(property "Datasheet" "https://industrial.panasonic.com/cdbs/www-data/pdf/RDA0000/AOA0000C301.pdf"
			(at 0 0 -90)
			(layer "F.Fab")
			(hide yes)
			(effects
				(font
					(size 1.27 1.27)
					(thickness 0.15)
				)
			)
		)
		(property "Author" "Antmicro"
			(at -48.05 178.15 0)
			(layer "F.Fab")
			(hide yes)
			(effects
				(font
					(size 1 1)
					(thickness 0.15)
				)
			)
		)
		(property "Current" "1A"
			(at -48.05 178.15 0)
			(layer "F.Fab")
			(hide yes)
			(effects
				(font
					(size 1 1)
					(thickness 0.15)
				)
			)
		)
		(property "License" "Apache-2.0"
			(at -48.05 178.15 0)
			(layer "F.Fab")
			(hide yes)
			(effects
				(font
					(size 1 1)
					(thickness 0.15)
				)
			)
		)
		(property "MPN" "ERJ2GE0R00X"
			(at -48.05 178.15 0)
			(layer "F.Fab")
			(hide yes)
			(effects
				(font
					(size 1 1)
					(thickness 0.15)
				)
			)
		)
		(property "Manufacturer" "Panasonic"
			(at -48.05 178.15 0)
			(layer "F.Fab")
			(hide yes)
			(effects
				(font
					(size 1 1)
					(thickness 0.15)
				)
			)
		)
		(property "Tolerance" ""
			(at -48.05 178.15 0)
			(layer "F.Fab")
			(hide yes)
			(effects
				(font
					(size 1 1)
					(thickness 0.15)
				)
			)
		)
		(property "Val" "0R"
			(at -48.05 178.15 0)
			(layer "F.Fab")
			(hide yes)
			(effects
				(font
					(size 1 1)
					(thickness 0.15)
				)
			)
		)
		(sheetname "USB Debug, DP")
		(sheetfile "usb.kicad_sch")
		(attr smd exclude_from_pos_files exclude_from_bom dnp)
		(fp_rect
			(start -0.925 -0.47)
			(end 0.925 0.47)
			(stroke
				(width 0.05)
				(type default)
			)
			(fill none)
			(layer "F.CrtYd")
		)
		(fp_rect
			(start -0.5 -0.25)
			(end 0.5 0.25)
			(stroke
				(width 0.15)
				(type solid)
			)
			(fill none)
			(layer "F.Fab")
		)
		(fp_text user "Author: Antmicro"
			(at -0.95 4.169 -90)
			(layer "F.Fab")
			(hide yes)
			(effects
				(font
					(size 0.7 0.7)
					(thickness 0.15)
				)
				(justify left bottom)
			)
		)
		(fp_text user "License: Apache-2.0"
			(at -0.95 5.169 -90)
			(layer "F.Fab")
			(hide yes)
			(effects
				(font
					(size 0.7 0.7)
					(thickness 0.15)
				)
				(justify left bottom)
			)
		)
		(fp_text user "${REFERENCE}"
			(at -0.95 3.168 -90)
			(layer "F.Fab")
			(hide yes)
			(effects
				(font
					(size 0.7 0.7)
					(thickness 0.15)
				)
				(justify left bottom)
			)
		)
		(pad "1" smd roundrect
			(at -0.48 0 270)
			(size 0.59 0.64)
			(layers "F.Cu" "F.Paste" "F.Mask")
			(roundrect_rratio 0.25)
			(net 553 "/USB Debug, DP/USBC0_5V_PEN")
			(pintype "passive")
		)
		(pad "2" smd roundrect
			(at 0.48 0 270)
			(size 0.59 0.64)
			(layers "F.Cu" "F.Paste" "F.Mask")
			(roundrect_rratio 0.25)
			(net 99 "+5V")
			(pintype "passive")
		)
	)
	(footprint "antmicro-footprints:TP_SMD_0.75mm"
		(layer "F.Cu")
		(at 92.1 118.6 90)
		(property "Reference" "TP58"
			(at 0.2 0.35 90)
			(layer "F.SilkS")
			(effects
				(font
					(size 0.7 0.7)
					(thickness 0.15)
				)
				(justify left bottom)
			)
		)
		(property "Value" "TP_0.75mm_SMD"
			(at 0 1.2 90)
			(layer "F.Fab")
			(effects
				(font
					(size 0.7 0.7)
					(thickness 0.15)
				)
				(justify left bottom)
			)
		)
		(property "Footprint" "antmicro-footprints:TP_SMD_0.75mm"
			(at 0 0 90)
			(layer "F.Fab")
			(hide yes)
			(effects
				(font
					(size 1.27 1.27)
					(thickness 0.15)
				)
			)
		)
		(property "Author" "Antmicro"
			(at 210.7 26.5 0)
			(layer "F.Fab")
			(hide yes)
			(effects
				(font
					(size 1 1)
					(thickness 0.15)
				)
			)
		)
		(property "License" "Apache-2.0"
			(at 210.7 26.5 0)
			(layer "F.Fab")
			(hide yes)
			(effects
				(font
					(size 1 1)
					(thickness 0.15)
				)
			)
		)
		(property "MPN" ""
			(at 210.7 26.5 0)
			(layer "F.Fab")
			(hide yes)
			(effects
				(font
					(size 1 1)
					(thickness 0.15)
				)
			)
		)
		(property "Manufacturer" ""
			(at 210.7 26.5 0)
			(layer "F.Fab")
			(hide yes)
			(effects
				(font
					(size 1 1)
					(thickness 0.15)
				)
			)
		)
		(sheetname "HDMI")
		(sheetfile "hdmi.kicad_sch")
		(attr exclude_from_pos_files exclude_from_bom)
		(fp_circle
			(center 0 0)
			(end 0.475 0)
			(stroke
				(width 0.05)
				(type default)
			)
			(fill none)
			(layer "F.CrtYd")
		)
		(fp_text user "Author: Antmicro"
			(at -0.4 3.901 90)
			(layer "F.Fab")
			(hide yes)
			(effects
				(font
					(size 0.7 0.7)
					(thickness 0.15)
				)
				(justify left bottom)
			)
		)
		(fp_text user "License: Apache-2.0"
			(at -0.4 5.101 90)
			(layer "F.Fab")
			(hide yes)
			(effects
				(font
					(size 0.7 0.7)
					(thickness 0.15)
				)
				(justify left bottom)
			)
		)
		(fp_text user "${REFERENCE}"
			(at -0.4 2.7 90)
			(layer "F.Fab")
			(hide yes)
			(effects
				(font
					(size 0.7 0.7)
					(thickness 0.15)
				)
				(justify left bottom)
			)
		)
		(pad "1" smd circle
			(at 0 0 90)
			(size 0.75 0.75)
			(layers "F.Cu" "F.Mask")
			(net 520 "/HDMI/HDMI_CEC_5V")
			(pinfunction "1")
			(pintype "passive")
		)
	)
	(footprint "antmicro-footprints:R_0402_1005Metric"
		(layer "F.Cu")
		(at 92.59 105.41 45)
		(descr "Resistor SMD 0402")
		(tags "resistor SMD 0402")
		(property "Reference" "R209"
			(at -1.753625 1.484924 45)
			(layer "F.SilkS")
			(effects
				(font
					(size 0.7 0.7)
					(thickness 0.15)
				)
				(justify left bottom)
			)
		)
		(property "Value" "R_499R_0402"
			(at -1.011843 1.772046 45)
			(layer "F.Fab")
			(effects
				(font
					(size 0.7 0.7)
					(thickness 0.15)
				)
				(justify left bottom)
			)
		)
		(property "Footprint" "antmicro-footprints:R_0402_1005Metric"
			(at 0 0 45)
			(layer "F.Fab")
			(hide yes)
			(effects
				(font
					(size 1.27 1.27)
					(thickness 0.15)
				)
			)
		)
		(property "Datasheet" "https://www.mouser.com/datasheet/2/54/cr-1858361.pdf"
			(at 0 0 45)
			(layer "F.Fab")
			(hide yes)
			(effects
				(font
					(size 1.27 1.27)
					(thickness 0.15)
				)
			)
		)
		(property "Author" "Antmicro"
			(at 101.655109 -34.597142 0)
			(layer "F.Fab")
			(hide yes)
			(effects
				(font
					(size 1 1)
					(thickness 0.15)
				)
			)
		)
		(property "License" "Apache-2.0"
			(at 101.655109 -34.597142 0)
			(layer "F.Fab")
			(hide yes)
			(effects
				(font
					(size 1 1)
					(thickness 0.15)
				)
			)
		)
		(property "MPN" "CR0402-FX-4990GLF"
			(at 101.655109 -34.597142 0)
			(layer "F.Fab")
			(hide yes)
			(effects
				(font
					(size 1 1)
					(thickness 0.15)
				)
			)
		)
		(property "Manufacturer" "Bourns"
			(at 101.655109 -34.597142 0)
			(layer "F.Fab")
			(hide yes)
			(effects
				(font
					(size 1 1)
					(thickness 0.15)
				)
			)
		)
		(property "Tolerance" "1%"
			(at 101.655109 -34.597142 0)
			(layer "F.Fab")
			(hide yes)
			(effects
				(font
					(size 1 1)
					(thickness 0.15)
				)
			)
		)
		(property "Val" "499R"
			(at 101.655109 -34.597142 0)
			(layer "F.Fab")
			(hide yes)
			(effects
				(font
					(size 1 1)
					(thickness 0.15)
				)
			)
		)
		(sheetname "HDMI")
		(sheetfile "hdmi.kicad_sch")
		(attr smd)
		(fp_poly
			(pts
				(xy -0.925 -0.47) (xy 0.925 -0.47) (xy 0.925 0.47) (xy -0.925 0.47)
			)
			(stroke
				(width 0.05)
				(type default)
			)
			(fill none)
			(layer "F.CrtYd")
		)
		(fp_poly
			(pts
				(xy -0.5 -0.25) (xy 0.5 -0.25) (xy 0.5 0.25) (xy -0.5 0.25)
			)
			(stroke
				(width 0.15)
				(type solid)
			)
			(fill none)
			(layer "F.Fab")
		)
		(fp_text user "License: Apache-2.0"
			(at -0.949999 5.169 45)
			(layer "F.Fab")
			(hide yes)
			(effects
				(font
					(size 0.7 0.7)
					(thickness 0.15)
				)
				(justify left bottom)
			)
		)
		(fp_text user "${REFERENCE}"
			(at -0.95 3.168 45)
			(layer "F.Fab")
			(hide yes)
			(effects
				(font
					(size 0.7 0.7)
					(thickness 0.15)
				)
				(justify left bottom)
			)
		)
		(fp_text user "Author: Antmicro"
			(at -0.95 4.169 45)
			(layer "F.Fab")
			(hide yes)
			(effects
				(font
					(size 0.7 0.7)
					(thickness 0.15)
				)
				(justify left bottom)
			)
		)
		(pad "1" smd roundrect
			(at -0.48 0 45)
			(size 0.59 0.64)
			(layers "F.Cu" "F.Paste" "F.Mask")
			(roundrect_rratio 0.25)
			(net 623 "Net-(Q2-D)")
			(pintype "passive")
		)
		(pad "2" smd roundrect
			(at 0.48 0 45)
			(size 0.59 0.64)
			(layers "F.Cu" "F.Paste" "F.Mask")
			(roundrect_rratio 0.25)
			(net 486 "/HDMI/HDMI_D2_N")
			(pintype "passive")
		)
	)
	(footprint "antmicro-footprints:R_0402_1005Metric"
		(layer "F.Cu")
		(at 105.154938 106.045)
		(descr "Resistor SMD 0402")
		(tags "resistor SMD 0402")
		(property "Reference" "R203"
			(at -3.654938 0.405 0)
			(layer "F.SilkS")
			(effects
				(font
					(size 0.7 0.7)
					(thickness 0.15)
				)
				(justify left bottom)
			)
		)
		(property "Value" "R_0R_0402"
			(at 0 1.4 0)
			(layer "F.Fab")
			(effects
				(font
					(size 0.7 0.7)
					(thickness 0.15)
				)
				(justify left bottom)
			)
		)
		(property "Footprint" "antmicro-footprints:R_0402_1005Metric"
			(at 0 0 0)
			(layer "F.Fab")
			(hide yes)
			(effects
				(font
					(size 1.27 1.27)
					(thickness 0.15)
				)
			)
		)
		(property "Datasheet" "https://industrial.panasonic.com/cdbs/www-data/pdf/RDA0000/AOA0000C301.pdf"
			(at 0 0 0)
			(layer "F.Fab")
			(hide yes)
			(effects
				(font
					(size 1.27 1.27)
					(thickness 0.15)
				)
			)
		)
		(property "Author" "Antmicro"
			(at 0 0 0)
			(layer "F.Fab")
			(hide yes)
			(effects
				(font
					(size 1 1)
					(thickness 0.15)
				)
			)
		)
		(property "Current" "1A"
			(at 0 0 0)
			(layer "F.Fab")
			(hide yes)
			(effects
				(font
					(size 1 1)
					(thickness 0.15)
				)
			)
		)
		(property "License" "Apache-2.0"
			(at 0 0 0)
			(layer "F.Fab")
			(hide yes)
			(effects
				(font
					(size 1 1)
					(thickness 0.15)
				)
			)
		)
		(property "MPN" "ERJ2GE0R00X"
			(at 0 0 0)
			(layer "F.Fab")
			(hide yes)
			(effects
				(font
					(size 1 1)
					(thickness 0.15)
				)
			)
		)
		(property "Manufacturer" "Panasonic"
			(at 0 0 0)
			(layer "F.Fab")
			(hide yes)
			(effects
				(font
					(size 1 1)
					(thickness 0.15)
				)
			)
		)
		(property "Tolerance" ""
			(at 0 0 0)
			(layer "F.Fab")
			(hide yes)
			(effects
				(font
					(size 1 1)
					(thickness 0.15)
				)
			)
		)
		(property "Val" "0R"
			(at 0 0 0)
			(layer "F.Fab")
			(hide yes)
			(effects
				(font
					(size 1 1)
					(thickness 0.15)
				)
			)
		)
		(sheetname "USB3")
		(sheetfile "usb3.kicad_sch")
		(attr smd)
		(fp_rect
			(start -0.925 -0.47)
			(end 0.925 0.47)
			(stroke
				(width 0.05)
				(type default)
			)
			(fill none)
			(layer "F.CrtYd")
		)
		(fp_rect
			(start -0.5 -0.25)
			(end 0.5 0.25)
			(stroke
				(width 0.15)
				(type solid)
			)
			(fill none)
			(layer "F.Fab")
		)
		(fp_text user "${REFERENCE}"
			(at -0.95 3.168 0)
			(layer "F.Fab")
			(hide yes)
			(effects
				(font
					(size 0.7 0.7)
					(thickness 0.15)
				)
				(justify left bottom)
			)
		)
		(fp_text user "License: Apache-2.0"
			(at -0.95 5.169 0)
			(layer "F.Fab")
			(hide yes)
			(effects
				(font
					(size 0.7 0.7)
					(thickness 0.15)
				)
				(justify left bottom)
			)
		)
		(fp_text user "Author: Antmicro"
			(at -0.95 4.169 0)
			(layer "F.Fab")
			(hide yes)
			(effects
				(font
					(size 0.7 0.7)
					(thickness 0.15)
				)
				(justify left bottom)
			)
		)
		(pad "1" smd roundrect
			(at -0.48 0)
			(size 0.59 0.64)
			(layers "F.Cu" "F.Paste" "F.Mask")
			(roundrect_rratio 0.25)
			(net 167 "USBSS2_TX_N")
			(pintype "passive")
		)
		(pad "2" smd roundrect
			(at 0.48 0)
			(size 0.59 0.64)
			(layers "F.Cu" "F.Paste" "F.Mask")
			(roundrect_rratio 0.25)
			(net 612 "/USB3/USBSS1_C_TX_P")
			(pintype "passive")
		)
	)
	(footprint "antmicro-footprints:WQFN-30-1EP_4.6x2.6mm_P0.4mm"
		(layer "F.Cu")
		(at 108.889938 106.545)
		(property "Reference" "U17"
			(at 2.690062 -0.415 90)
			(layer "F.SilkS")
			(effects
				(font
					(size 0.7 0.7)
					(thickness 0.15)
				)
				(justify left bottom)
			)
		)
		(property "Value" "HD3SS3220RNH"
			(at 0 3.5 180)
			(layer "F.Fab")
			(effects
				(font
					(size 0.7 0.7)
					(thickness 0.15)
				)
				(justify left bottom)
			)
		)
		(property "Footprint" "antmicro-footprints:WQFN-30-1EP_4.6x2.6mm_P0.4mm"
			(at 0 0 0)
			(layer "F.Fab")
			(hide yes)
			(effects
				(font
					(size 1.27 1.27)
					(thickness 0.15)
				)
			)
		)
		(property "Datasheet" "https://www.ti.com/lit/ds/symlink/hd3ss3220.pdf?ts=1663000043694&ref_url=https%253A%252F%252Fwww.google.com%252F"
			(at 0 0 0)
			(layer "F.Fab")
			(hide yes)
			(effects
				(font
					(size 1.27 1.27)
					(thickness 0.15)
				)
			)
		)
		(property "Author" "Antmicro"
			(at 0 0 0)
			(layer "F.Fab")
			(hide yes)
			(effects
				(font
					(size 1 1)
					(thickness 0.15)
				)
			)
		)
		(property "License" "Apache-2.0"
			(at 0 0 0)
			(layer "F.Fab")
			(hide yes)
			(effects
				(font
					(size 1 1)
					(thickness 0.15)
				)
			)
		)
		(property "MPN" "HD3SS3220RNHT"
			(at 0 0 0)
			(layer "F.Fab")
			(hide yes)
			(effects
				(font
					(size 1 1)
					(thickness 0.15)
				)
			)
		)
		(property "Manufacturer" "Texas Instruments"
			(at 0 0 0)
			(layer "F.Fab")
			(hide yes)
			(effects
				(font
					(size 1 1)
					(thickness 0.15)
				)
			)
		)
		(sheetname "USB3")
		(sheetfile "usb3.kicad_sch")
		(attr smd)
		(fp_line
			(start -1.253 -2.26)
			(end -1.253 -2.01)
			(stroke
				(width 0.15)
				(type solid)
			)
			(layer "F.SilkS")
		)
		(fp_line
			(start -1.253 -2.26)
			(end -1.003 -2.26)
			(stroke
				(width 0.15)
				(type solid)
			)
			(layer "F.SilkS")
		)
		(fp_line
			(start -1.253 2.24)
			(end -1.253 1.99)
			(stroke
				(width 0.15)
				(type solid)
			)
			(layer "F.SilkS")
		)
		(fp_line
			(start -1.253 2.24)
			(end -1.003 2.24)
			(stroke
				(width 0.15)
				(type solid)
			)
			(layer "F.SilkS")
		)
		(fp_line
			(start 1.247 -2.26)
			(end 0.997 -2.26)
			(stroke
				(width 0.15)
				(type solid)
			)
			(layer "F.SilkS")
		)
		(fp_line
			(start 1.247 -2.26)
			(end 1.247 -2.01)
			(stroke
				(width 0.15)
				(type solid)
			)
			(layer "F.SilkS")
		)
		(fp_line
			(start 1.247 2.24)
			(end 0.997 2.24)
			(stroke
				(width 0.15)
				(type solid)
			)
			(layer "F.SilkS")
		)
		(fp_line
			(start 1.247 2.24)
			(end 1.247 1.99)
			(stroke
				(width 0.15)
				(type solid)
			)
			(layer "F.SilkS")
		)
		(fp_circle
			(center -1.5 -2.5)
			(end -1.45 -2.5)
			(stroke
				(width 0.15)
				(type solid)
			)
			(fill solid)
			(layer "F.SilkS")
		)
		(fp_rect
			(start -1.6 -2.6)
			(end 1.6 2.6)
			(stroke
				(width 0.05)
				(type solid)
			)
			(fill none)
			(layer "F.CrtYd")
		)
		(fp_rect
			(start -1.3 -2.3)
			(end 1.3 2.3)
			(stroke
				(width 0.15)
				(type solid)
			)
			(fill none)
			(layer "F.Fab")
		)
		(fp_text user "License: Apache-2.0"
			(at -1.6 7.199 0)
			(layer "F.Fab")
			(hide yes)
			(effects
				(font
					(size 0.7 0.7)
					(thickness 0.15)
				)
				(justify left bottom)
			)
		)
		(fp_text user "Author: Antmicro"
			(at -1.6 6 0)
			(layer "F.Fab")
			(hide yes)
			(effects
				(font
					(size 0.7 0.7)
					(thickness 0.15)
				)
				(justify left bottom)
			)
		)
		(fp_text user "${REFERENCE}"
			(at -1.6 4.8 0)
			(layer "F.Fab")
			(hide yes)
			(effects
				(font
					(size 0.7 0.7)
					(thickness 0.15)
				)
				(justify left bottom)
			)
		)
		(pad "1" smd rect
			(at -1.232 -1.809 90)
			(size 0.2 0.45)
			(layers "F.Cu" "F.Paste" "F.Mask")
			(net 283 "/USB3/USBC1_CC2")
			(pinfunction "CC2")
			(pintype "passive")
		)
		(pad "2" smd rect
			(at -1.203 -1.41 90)
			(size 0.2 0.5)
			(layers "F.Cu" "F.Paste" "F.Mask")
			(net 282 "/USB3/USBC1_CC1")
			(pinfunction "CC1")
			(pintype "passive")
		)
		(pad "3" smd rect
			(at -1.203 -1.01 90)
			(size 0.2 0.5)
			(layers "F.Cu" "F.Paste" "F.Mask")
			(net 316 "/USB3/USBC1_I_MODE")
			(pinfunction "CURRENT_MODE")
			(pintype "passive")
		)
		(pad "4" smd rect
			(at -1.203 -0.609 90)
			(size 0.2 0.5)
			(layers "F.Cu" "F.Paste" "F.Mask")
			(net 315 "/USB3/USBC1_PORT")
			(pinfunction "PORT")
			(pintype "passive")
		)
		(pad "5" smd rect
			(at -1.203 -0.21 90)
			(size 0.2 0.5)
			(layers "F.Cu" "F.Paste" "F.Mask")
			(net 365 "/USB3/USBC1_VBUS_DET")
			(pinfunction "VBUS_DET")
			(pintype "passive")
		)
		(pad "6" smd rect
			(at -1.203 0.191 90)
			(size 0.2 0.5)
			(layers "F.Cu" "F.Paste" "F.Mask")
			(net 612 "/USB3/USBSS1_C_TX_P")
			(pinfunction "TX+")
			(pintype "passive")
		)
		(pad "7" smd rect
			(at -1.203 0.59 90)
			(size 0.2 0.5)
			(layers "F.Cu" "F.Paste" "F.Mask")
			(net 610 "/USB3/USBSS1_C_TX_N")
			(pinfunction "TX-")
			(pintype "passive")
		)
		(pad "8" smd rect
			(at -1.203 0.99 90)
			(size 0.2 0.5)
			(layers "F.Cu" "F.Paste" "F.Mask")
			(net 87 "+3V3")
			(pinfunction "VCC33")
			(pintype "passive")
		)
		(pad "9" smd rect
			(at -1.203 1.391 90)
			(size 0.2 0.5)
			(layers "F.Cu" "F.Paste" "F.Mask")
			(net 611 "/USB3/USBSS1_C_RX_P")
			(pinfunction "RX+")
			(pintype "passive")
		)
		(pad "10" smd rect
			(at -1.232 1.79 90)
			(size 0.2 0.45)
			(layers "F.Cu" "F.Paste" "F.Mask")
			(net 609 "/USB3/USBSS1_C_RX_N")
			(pinfunction "RX-")
			(pintype "passive")
		)
		(pad "11" smd rect
			(at -0.804 2.191)
			(size 0.2 0.45)
			(layers "F.Cu" "F.Paste" "F.Mask")
			(net 364 "/USB3/USBC1_DIR")
			(pinfunction "DIR")
			(pintype "passive")
		)
		(pad "12" smd rect
			(at -0.403 2.191)
			(size 0.2 0.5)
			(layers "F.Cu" "F.Paste" "F.Mask")
			(net 318 "/USB3/~{USBC1_EN_MUX}")
			(pinfunction "ENn_MUX")
			(pintype "passive")
		)
		(pad "13" smd rect
			(at -0.003 2.191)
			(size 0.2 0.5)
			(layers "F.Cu" "F.Paste" "F.Mask")
			(net 1 "GND")
			(pinfunction "GND")
			(pintype "passive")
		)
		(pad "14" smd rect
			(at 0.396 2.191)
			(size 0.2 0.5)
			(layers "F.Cu" "F.Paste" "F.Mask")
			(net 366 "/USB3/USBC1_RX1_N")
			(pinfunction "RX1-")
			(pintype "passive")
		)
		(pad "15" smd rect
			(at 0.797 2.191)
			(size 0.2 0.45)
			(layers "F.Cu" "F.Paste" "F.Mask")
			(net 368 "/USB3/USBC1_RX1_P")
			(pinfunction "RX1+")
			(pintype "passive")
		)
		(pad "16" smd rect
			(at 1.222 1.79 90)
			(size 0.2 0.45)
			(layers "F.Cu" "F.Paste" "F.Mask")
			(net 264 "/USB3/USBC1_TX1_N")
			(pinfunction "TX1-")
			(pintype "passive")
		)
		(pad "17" smd rect
			(at 1.196 1.391 90)
			(size 0.2 0.5)
			(layers "F.Cu" "F.Paste" "F.Mask")
			(net 266 "/USB3/USBC1_TX1_P")
			(pinfunction "TX1+")
			(pintype "passive")
		)
		(pad "18" smd rect
			(at 1.196 0.99 90)
			(size 0.2 0.5)
			(layers "F.Cu" "F.Paste" "F.Mask")
			(net 369 "/USB3/USBC1_RX2_N")
			(pinfunction "RX2-")
			(pintype "passive")
		)
		(pad "19" smd rect
			(at 1.196 0.59 90)
			(size 0.2 0.5)
			(layers "F.Cu" "F.Paste" "F.Mask")
			(net 390 "/USB3/USBC1_RX2_P")
			(pinfunction "RX2+")
			(pintype "passive")
		)
		(pad "20" smd rect
			(at 1.196 0.191 90)
			(size 0.2 0.5)
			(layers "F.Cu" "F.Paste" "F.Mask")
			(net 262 "/USB3/USBC1_TX2_N")
			(pinfunction "TX2-")
			(pintype "passive")
		)
		(pad "21" smd rect
			(at 1.196 -0.21 90)
			(size 0.2 0.5)
			(layers "F.Cu" "F.Paste" "F.Mask")
			(net 268 "/USB3/USBC1_TX2_P")
			(pinfunction "TX2+")
			(pintype "passive")
		)
		(pad "22" smd rect
			(at 1.196 -0.609 90)
			(size 0.2 0.5)
			(layers "F.Cu" "F.Paste" "F.Mask")
			(net 314 "/USB3/USBC1_ADDR")
			(pinfunction "ADDR")
			(pintype "passive")
		)
		(pad "23" smd rect
			(at 1.196 -1.01 90)
			(size 0.2 0.5)
			(layers "F.Cu" "F.Paste" "F.Mask")
			(net 317 "/USB3/~{USBC1_INT}")
			(pinfunction "INT_N/OUT3")
			(pintype "passive")
		)
		(pad "24" smd rect
			(at 1.196 -1.41 90)
			(size 0.2 0.5)
			(layers "F.Cu" "F.Paste" "F.Mask")
			(net 391 "/USB3/USBC1_FAULT_N")
			(pinfunction "VCONN_FAULT_N")
			(pintype "passive")
		)
		(pad "25" smd rect
			(at 1.222 -1.809 90)
			(size 0.2 0.45)
			(layers "F.Cu" "F.Paste" "F.Mask")
			(net 362 "/USB3/USBC1_I2C_SDA")
			(pinfunction "SDA/OUT1")
			(pintype "passive")
		)
		(pad "26" smd rect
			(at 0.797 -2.21)
			(size 0.2 0.45)
			(layers "F.Cu" "F.Paste" "F.Mask")
			(net 363 "/USB3/USBC1_ISC_SCL")
			(pinfunction "SCL/OUT2")
			(pintype "passive")
		)
		(pad "27" smd rect
			(at 0.396 -2.21)
			(size 0.2 0.5)
			(layers "F.Cu" "F.Paste" "F.Mask")
			(net 284 "/USB3/USBC1_ID")
			(pinfunction "ID")
			(pintype "passive")
		)
		(pad "28" smd rect
			(at -0.003 -2.21)
			(size 0.2 0.5)
			(layers "F.Cu" "F.Paste" "F.Mask")
			(net 1 "GND")
			(pinfunction "GND")
			(pintype "passive")
		)
		(pad "29" smd rect
			(at -0.403 -2.21)
			(size 0.2 0.5)
			(layers "F.Cu" "F.Paste" "F.Mask")
			(net 319 "/USB3/~{USBC1_EN_CC}")
			(pinfunction "ENn_CC")
			(pintype "passive")
		)
		(pad "30" smd rect
			(at -0.804 -2.21)
			(size 0.2 0.45)
			(layers "F.Cu" "F.Paste" "F.Mask")
			(net 99 "+5V")
			(pinfunction "VDD5")
			(pintype "passive")
		)
		(pad "31" smd rect
			(at -0.003 -0.01)
			(size 1.2 3.2)
			(layers "F.Cu" "F.Paste" "F.Mask")
			(net 1 "GND")
			(pinfunction "GND")
			(pintype "passive")
		)
	)
	(footprint "antmicro-footprints:C_0402_1005Metric"
		(layer "F.Cu")
		(at 80.23 89.13 -90)
		(descr "Capacitor SMD 0402")
		(tags "capacitor SMD 0402")
		(property "Reference" "C123"
			(at -1.73 -2.43 90)
			(layer "F.SilkS")
			(effects
				(font
					(size 0.7 0.7)
					(thickness 0.15)
				)
				(justify right bottom)
			)
		)
		(property "Value" "C_1u_0402"
			(at -1.022927 2.155213 90)
			(layer "F.Fab")
			(effects
				(font
					(size 0.7 0.7)
					(thickness 0.15)
				)
				(justify right bottom)
			)
		)
		(property "Footprint" "antmicro-footprints:C_0402_1005Metric"
			(at 0 0 -90)
			(layer "F.Fab")
			(hide yes)
			(effects
				(font
					(size 1.27 1.27)
					(thickness 0.15)
				)
			)
		)
		(property "Datasheet" "https://product.tdk.com/en/search/capacitor/ceramic/mlcc/info?part_no=C1005X6S1A105K050BC"
			(at 0 0 -90)
			(layer "F.Fab")
			(hide yes)
			(effects
				(font
					(size 1.27 1.27)
					(thickness 0.15)
				)
			)
		)
		(property "Author" "Antmicro"
			(at -8.9 169.36 0)
			(layer "F.Fab")
			(hide yes)
			(effects
				(font
					(size 1 1)
					(thickness 0.15)
				)
			)
		)
		(property "Dielectric" ""
			(at -8.9 169.36 0)
			(layer "F.Fab")
			(hide yes)
			(effects
				(font
					(size 1 1)
					(thickness 0.15)
				)
			)
		)
		(property "License" "Apache-2.0"
			(at -8.9 169.36 0)
			(layer "F.Fab")
			(hide yes)
			(effects
				(font
					(size 1 1)
					(thickness 0.15)
				)
			)
		)
		(property "MPN" "C1005X6S1A105K050BC"
			(at -8.9 169.36 0)
			(layer "F.Fab")
			(hide yes)
			(effects
				(font
					(size 1 1)
					(thickness 0.15)
				)
			)
		)
		(property "Manufacturer" "TDK"
			(at -8.9 169.36 0)
			(layer "F.Fab")
			(hide yes)
			(effects
				(font
					(size 1 1)
					(thickness 0.15)
				)
			)
		)
		(property "Val" "1u"
			(at -8.9 169.36 0)
			(layer "F.Fab")
			(hide yes)
			(effects
				(font
					(size 1 1)
					(thickness 0.15)
				)
			)
		)
		(property "Voltage" ""
			(at -8.9 169.36 0)
			(layer "F.Fab")
			(hide yes)
			(effects
				(font
					(size 1 1)
					(thickness 0.15)
				)
			)
		)
		(sheetname "Supply")
		(sheetfile "supply.kicad_sch")
		(attr smd)
		(fp_rect
			(start -0.925 -0.47)
			(end 0.925 0.47)
			(stroke
				(width 0.05)
				(type default)
			)
			(fill none)
			(layer "F.CrtYd")
		)
		(fp_line
			(start -0.494 0.248)
			(end -0.494 -0.25)
			(stroke
				(width 0.15)
				(type solid)
			)
			(layer "F.Fab")
		)
		(fp_line
			(start 0.504 0.248)
			(end -0.494 0.248)
			(stroke
				(width 0.15)
				(type solid)
			)
			(layer "F.Fab")
		)
		(fp_line
			(start -0.494 -0.25)
			(end 0.504 -0.25)
			(stroke
				(width 0.15)
				(type solid)
			)
			(layer "F.Fab")
		)
		(fp_line
			(start 0.504 -0.25)
			(end 0.504 0.248)
			(stroke
				(width 0.15)
				(type solid)
			)
			(layer "F.Fab")
		)
		(fp_text user "License: Apache-2.0"
			(at -0.939 5.799 90)
			(layer "F.Fab")
			(hide yes)
			(effects
				(font
					(size 0.7 0.7)
					(thickness 0.15)
				)
				(justify right bottom)
			)
		)
		(fp_text user "${REFERENCE}"
			(at -0.939 4.599 90)
			(layer "F.Fab")
			(hide yes)
			(effects
				(font
					(size 0.7 0.7)
					(thickness 0.15)
				)
				(justify right bottom)
			)
		)
		(fp_text user "Author: Antmicro"
			(at -0.939 3.399 90)
			(layer "F.Fab")
			(hide yes)
			(effects
				(font
					(size 0.7 0.7)
					(thickness 0.15)
				)
				(justify right bottom)
			)
		)
		(pad "1" smd roundrect
			(at -0.48 0 270)
			(size 0.59 0.64)
			(layers "F.Cu" "F.Paste" "F.Mask")
			(roundrect_rratio 0.25)
			(net 1 "GND")
			(pintype "passive")
		)
		(pad "2" smd roundrect
			(at 0.48 0 270)
			(size 0.59 0.64)
			(layers "F.Cu" "F.Paste" "F.Mask")
			(roundrect_rratio 0.25)
			(net 177 "/Supply/3V3_VDD")
			(pintype "passive")
		)
	)
	(footprint "antmicro-footprints:R_0402_1005Metric"
		(layer "F.Cu")
		(at 102.2 115.8 -90)
		(descr "Resistor SMD 0402")
		(tags "resistor SMD 0402")
		(property "Reference" "R139"
			(at -0.9 -0.45 -90)
			(layer "F.SilkS")
			(effects
				(font
					(size 0.7 0.7)
					(thickness 0.15)
				)
				(justify left bottom)
			)
		)
		(property "Value" "R_2k2_0402"
			(at 0 1.4 -90)
			(layer "F.Fab")
			(effects
				(font
					(size 0.7 0.7)
					(thickness 0.15)
				)
				(justify left bottom)
			)
		)
		(property "Footprint" "antmicro-footprints:R_0402_1005Metric"
			(at 0 0 -90)
			(layer "F.Fab")
			(hide yes)
			(effects
				(font
					(size 1.27 1.27)
					(thickness 0.15)
				)
			)
		)
		(property "Datasheet" "https://www.bourns.com/docs/product-datasheets/cr.pdf"
			(at 0 0 -90)
			(layer "F.Fab")
			(hide yes)
			(effects
				(font
					(size 1.27 1.27)
					(thickness 0.15)
				)
			)
		)
		(property "Author" "Antmicro"
			(at -13.6 218 0)
			(layer "F.Fab")
			(hide yes)
			(effects
				(font
					(size 1 1)
					(thickness 0.15)
				)
			)
		)
		(property "License" "Apache-2.0"
			(at -13.6 218 0)
			(layer "F.Fab")
			(hide yes)
			(effects
				(font
					(size 1 1)
					(thickness 0.15)
				)
			)
		)
		(property "MPN" "CR0402-FX-2201GLF"
			(at -13.6 218 0)
			(layer "F.Fab")
			(hide yes)
			(effects
				(font
					(size 1 1)
					(thickness 0.15)
				)
			)
		)
		(property "Manufacturer" "Bourns"
			(at -13.6 218 0)
			(layer "F.Fab")
			(hide yes)
			(effects
				(font
					(size 1 1)
					(thickness 0.15)
				)
			)
		)
		(property "Tolerance" "1%"
			(at -13.6 218 0)
			(layer "F.Fab")
			(hide yes)
			(effects
				(font
					(size 1 1)
					(thickness 0.15)
				)
			)
		)
		(property "Val" "2k2"
			(at -13.6 218 0)
			(layer "F.Fab")
			(hide yes)
			(effects
				(font
					(size 1 1)
					(thickness 0.15)
				)
			)
		)
		(sheetname "USB3")
		(sheetfile "usb3.kicad_sch")
		(attr smd)
		(fp_rect
			(start -0.925 -0.47)
			(end 0.925 0.47)
			(stroke
				(width 0.05)
				(type default)
			)
			(fill none)
			(layer "F.CrtYd")
		)
		(fp_rect
			(start -0.5 -0.25)
			(end 0.5 0.25)
			(stroke
				(width 0.15)
				(type solid)
			)
			(fill none)
			(layer "F.Fab")
		)
		(fp_text user "Author: Antmicro"
			(at -0.95 4.169 -90)
			(layer "F.Fab")
			(hide yes)
			(effects
				(font
					(size 0.7 0.7)
					(thickness 0.15)
				)
				(justify left bottom)
			)
		)
		(fp_text user "${REFERENCE}"
			(at -0.95 3.168 -90)
			(layer "F.Fab")
			(hide yes)
			(effects
				(font
					(size 0.7 0.7)
					(thickness 0.15)
				)
				(justify left bottom)
			)
		)
		(fp_text user "License: Apache-2.0"
			(at -0.95 5.169 -90)
			(layer "F.Fab")
			(hide yes)
			(effects
				(font
					(size 0.7 0.7)
					(thickness 0.15)
				)
				(justify left bottom)
			)
		)
		(pad "1" smd roundrect
			(at -0.48 0 270)
			(size 0.59 0.64)
			(layers "F.Cu" "F.Paste" "F.Mask")
			(roundrect_rratio 0.25)
			(net 1 "GND")
			(pintype "passive")
		)
		(pad "2" smd roundrect
			(at 0.48 0 270)
			(size 0.59 0.64)
			(layers "F.Cu" "F.Paste" "F.Mask")
			(roundrect_rratio 0.25)
			(net 564 "/USB3/USBC1_ISET")
			(pintype "passive")
		)
	)
	(footprint "antmicro-footprints:R_0603_1608Metric"
		(layer "F.Cu")
		(at 55.34 92.59)
		(descr "Resistor SMD 0603")
		(tags "resistor SMD 0603")
		(property "Reference" "R172"
			(at 27.17 1.445 0)
			(layer "F.SilkS")
			(effects
				(font
					(size 0.7 0.7)
					(thickness 0.15)
				)
				(justify left bottom)
			)
		)
		(property "Value" "R_0R_22.4A_0603"
			(at 0 1.6 0)
			(layer "F.Fab")
			(effects
				(font
					(size 0.7 0.7)
					(thickness 0.15)
				)
				(justify left bottom)
			)
		)
		(property "Footprint" "antmicro-footprints:R_0603_1608Metric"
			(at 0 0 0)
			(layer "F.Fab")
			(hide yes)
			(effects
				(font
					(size 1.27 1.27)
					(thickness 0.15)
				)
			)
		)
		(property "Datasheet" "https://fscdn.rohm.com/en/products/databook/datasheet/passive/resistor/chip_resistor/pmr-jpw-e.pdf"
			(at 0 0 0)
			(layer "F.Fab")
			(hide yes)
			(effects
				(font
					(size 1.27 1.27)
					(thickness 0.15)
				)
			)
		)
		(property "Author" "Antmicro"
			(at 147.35 36.79 90)
			(layer "F.Fab")
			(hide yes)
			(effects
				(font
					(size 1 1)
					(thickness 0.15)
				)
			)
		)
		(property "License" "Apache-2.0"
			(at 147.35 36.79 90)
			(layer "F.Fab")
			(hide yes)
			(effects
				(font
					(size 1 1)
					(thickness 0.15)
				)
			)
		)
		(property "MPN" "PMR03EZPJ000"
			(at 147.35 36.79 90)
			(layer "F.Fab")
			(hide yes)
			(effects
				(font
					(size 1 1)
					(thickness 0.15)
				)
			)
		)
		(property "Manufacturer" "ROHM Semiconductor"
			(at 147.35 36.79 90)
			(layer "F.Fab")
			(hide yes)
			(effects
				(font
					(size 1 1)
					(thickness 0.15)
				)
			)
		)
		(property "Max. Curr." "22.4A"
			(at 147.35 36.79 90)
			(layer "F.Fab")
			(hide yes)
			(effects
				(font
					(size 1 1)
					(thickness 0.15)
				)
			)
		)
		(property "Tolerance" "template_tolerance"
			(at 147.35 36.79 90)
			(layer "F.Fab")
			(hide yes)
			(effects
				(font
					(size 1 1)
					(thickness 0.15)
				)
			)
		)
		(property "Val" "0R"
			(at 147.35 36.79 90)
			(layer "F.Fab")
			(hide yes)
			(effects
				(font
					(size 1 1)
					(thickness 0.15)
				)
			)
		)
		(sheetname "Supply")
		(sheetfile "supply.kicad_sch")
		(attr smd)
		(fp_line
			(start -0.15 -0.4)
			(end 0.15 -0.4)
			(stroke
				(width 0.15)
				(type solid)
			)
			(layer "F.SilkS")
		)
		(fp_line
			(start -0.15 0.4)
			(end 0.15 0.4)
			(stroke
				(width 0.15)
				(type solid)
			)
			(layer "F.SilkS")
		)
		(fp_rect
			(start -1.25 -0.65)
			(end 1.25 0.65)
			(stroke
				(width 0.05)
				(type solid)
			)
			(fill none)
			(layer "F.CrtYd")
		)
		(fp_rect
			(start -0.8 -0.4)
			(end 0.8 0.4)
			(stroke
				(width 0.15)
				(type solid)
			)
			(fill none)
			(layer "F.Fab")
		)
		(fp_text user "${REFERENCE}"
			(at -1.25 3.898 0)
			(layer "F.Fab")
			(hide yes)
			(effects
				(font
					(size 0.7 0.7)
					(thickness 0.15)
				)
				(justify left bottom)
			)
		)
		(fp_text user "Author: Antmicro"
			(at -1.25 4.9 0)
			(layer "F.Fab")
			(hide yes)
			(effects
				(font
					(size 0.7 0.7)
					(thickness 0.15)
				)
				(justify left bottom)
			)
		)
		(fp_text user "License: Apache-2.0"
			(at -1.25 5.9 0)
			(layer "F.Fab")
			(hide yes)
			(effects
				(font
					(size 0.7 0.7)
					(thickness 0.15)
				)
				(justify left bottom)
			)
		)
		(pad "1" smd roundrect
			(at -0.7 0)
			(size 0.8 1)
			(layers "F.Cu" "F.Paste" "F.Mask")
			(roundrect_rratio 0.2)
			(net 761 "/Supply/5V_OUT")
			(pintype "passive")
		)
		(pad "2" smd roundrect
			(at 0.7 0)
			(size 0.8 1)
			(layers "F.Cu" "F.Paste" "F.Mask")
			(roundrect_rratio 0.2)
			(net 787 "+5V_SoM")
			(pintype "passive")
		)
	)
	(footprint "antmicro-footprints:XSON-8_1x1.95mm_P0.5mm"
		(layer "F.Cu")
		(at 56.9 105.1 180)
		(property "Reference" "U33"
			(at 1.025 1.25 0)
			(layer "F.SilkS")
			(effects
				(font
					(size 0.7 0.7)
					(thickness 0.15)
				)
				(justify left bottom)
			)
		)
		(property "Value" "NTS0102_XSON"
			(at 0 2.2 180)
			(layer "F.Fab")
			(effects
				(font
					(size 0.7 0.7)
					(thickness 0.15)
				)
				(justify left bottom)
			)
		)
		(property "Footprint" "antmicro-footprints:XSON-8_1x1.95mm_P0.5mm"
			(at 0 0 180)
			(layer "F.Fab")
			(hide yes)
			(effects
				(font
					(size 1.27 1.27)
					(thickness 0.15)
				)
			)
		)
		(property "Datasheet" "http://www.farnell.com/datasheets/1760723.pdf"
			(at 0 0 180)
			(layer "F.Fab")
			(hide yes)
			(effects
				(font
					(size 1.27 1.27)
					(thickness 0.15)
				)
			)
		)
		(property "Author" "Antmicro"
			(at 113.8 210.2 0)
			(layer "F.Fab")
			(hide yes)
			(effects
				(font
					(size 1 1)
					(thickness 0.15)
				)
			)
		)
		(property "License" "Apache-2.0"
			(at 113.8 210.2 0)
			(layer "F.Fab")
			(hide yes)
			(effects
				(font
					(size 1 1)
					(thickness 0.15)
				)
			)
		)
		(property "MPN" "NTS0102GT"
			(at 113.8 210.2 0)
			(layer "F.Fab")
			(hide yes)
			(effects
				(font
					(size 1 1)
					(thickness 0.15)
				)
			)
		)
		(property "Manufacturer" "NXP"
			(at 113.8 210.2 0)
			(layer "F.Fab")
			(hide yes)
			(effects
				(font
					(size 1 1)
					(thickness 0.15)
				)
			)
		)
		(sheetname "Peripherals")
		(sheetfile "peripherals.kicad_sch")
		(attr smd)
		(fp_line
			(start 0.5 1.1)
			(end -0.5 1.1)
			(stroke
				(width 0.15)
				(type solid)
			)
			(layer "F.SilkS")
		)
		(fp_line
			(start -0.5 -1.1)
			(end 0.5 -1.1)
			(stroke
				(width 0.15)
				(type solid)
			)
			(layer "F.SilkS")
		)
		(fp_circle
			(center -0.75 -1.1)
			(end -0.701 -1.1)
			(stroke
				(width 0.15)
				(type solid)
			)
			(fill none)
			(layer "F.SilkS")
		)
		(fp_rect
			(start -0.8 -1.2)
			(end 0.8 1.2)
			(stroke
				(width 0.05)
				(type solid)
			)
			(fill none)
			(layer "F.CrtYd")
		)
		(fp_line
			(start 0.5305 1)
			(end -0.5305 1)
			(stroke
				(width 0.15)
				(type solid)
			)
			(layer "F.Fab")
		)
		(fp_line
			(start 0.5305 -1.001)
			(end 0.5305 1)
			(stroke
				(width 0.15)
				(type solid)
			)
			(layer "F.Fab")
		)
		(fp_line
			(start -0.5305 1)
			(end -0.5305 -1.001)
			(stroke
				(width 0.15)
				(type solid)
			)
			(layer "F.Fab")
		)
		(fp_line
			(start -0.5305 -1.001)
			(end 0.5305 -1.001)
			(stroke
				(width 0.15)
				(type solid)
			)
			(layer "F.Fab")
		)
		(fp_text user "Author: Antmicro"
			(at -0.527 7.105 180)
			(layer "F.Fab")
			(hide yes)
			(effects
				(font
					(size 0.7 0.7)
					(thickness 0.15)
				)
				(justify left bottom)
			)
		)
		(fp_text user "${REFERENCE}"
			(at -0.527 5.905 180)
			(layer "F.Fab")
			(hide yes)
			(effects
				(font
					(size 0.7 0.7)
					(thickness 0.15)
				)
				(justify left bottom)
			)
		)
		(fp_text user "License: Apache-2.0"
			(at -0.527 8.306 180)
			(layer "F.Fab")
			(hide yes)
			(effects
				(font
					(size 0.7 0.7)
					(thickness 0.15)
				)
				(justify left bottom)
			)
		)
		(pad "1" smd roundrect
			(at -0.45 -0.75)
			(size 0.6 0.3)
			(layers "F.Cu" "F.Paste" "F.Mask")
			(roundrect_rratio 0.25)
			(net 541 "/Peripherals/FAN_TACH_5V")
			(pinfunction "B_{2}")
			(pintype "bidirectional")
		)
		(pad "2" smd roundrect
			(at -0.45 -0.25)
			(size 0.6 0.25)
			(layers "F.Cu" "F.Paste" "F.Mask")
			(roundrect_rratio 0.25)
			(net 1 "GND")
			(pinfunction "GND")
			(pintype "power_in")
		)
		(pad "3" smd roundrect
			(at -0.45 0.25)
			(size 0.6 0.25)
			(layers "F.Cu" "F.Paste" "F.Mask")
			(roundrect_rratio 0.25)
			(net 112 "+1V8")
			(pinfunction "VCC_{A}")
			(pintype "power_in")
		)
		(pad "4" smd roundrect
			(at -0.45 0.75)
			(size 0.6 0.3)
			(layers "F.Cu" "F.Paste" "F.Mask")
			(roundrect_rratio 0.25)
			(net 463 "FAN_TACH")
			(pinfunction "A_{2}")
			(pintype "bidirectional")
		)
		(pad "5" smd roundrect
			(at 0.45 0.75)
			(size 0.6 0.3)
			(layers "F.Cu" "F.Paste" "F.Mask")
			(roundrect_rratio 0.25)
			(net 473 "FAN_PWM")
			(pinfunction "A_{1}")
			(pintype "bidirectional")
		)
		(pad "6" smd roundrect
			(at 0.45 0.25)
			(size 0.6 0.25)
			(layers "F.Cu" "F.Paste" "F.Mask")
			(roundrect_rratio 0.25)
			(net 112 "+1V8")
			(pinfunction "OE")
			(pintype "input")
		)
		(pad "7" smd roundrect
			(at 0.45 -0.25)
			(size 0.6 0.25)
			(layers "F.Cu" "F.Paste" "F.Mask")
			(roundrect_rratio 0.25)
			(net 99 "+5V")
			(pinfunction "VCC_{B}")
			(pintype "power_in")
		)
		(pad "8" smd roundrect
			(at 0.45 -0.75)
			(size 0.6 0.3)
			(layers "F.Cu" "F.Paste" "F.Mask")
			(roundrect_rratio 0.25)
			(net 540 "/Peripherals/FAN_PWM_5V")
			(pinfunction "B_{1}")
			(pintype "bidirectional")
		)
	)
	(footprint "antmicro-footprints:C_0402_1005Metric"
		(layer "F.Cu")
		(at 136.35 87.25 180)
		(descr "Capacitor SMD 0402")
		(tags "capacitor SMD 0402")
		(property "Reference" "C109"
			(at 3.65 -0.45 180)
			(layer "F.SilkS")
			(effects
				(font
					(size 0.7 0.7)
					(thickness 0.15)
				)
				(justify left bottom)
			)
		)
		(property "Value" "C_220n_0402"
			(at 0 1.4 180)
			(layer "F.Fab")
			(effects
				(font
					(size 0.7 0.7)
					(thickness 0.15)
				)
				(justify left bottom)
			)
		)
		(property "Footprint" "antmicro-footprints:C_0402_1005Metric"
			(at 0 0 180)
			(layer "F.Fab")
			(hide yes)
			(effects
				(font
					(size 1.27 1.27)
					(thickness 0.15)
				)
			)
		)
		(property "Datasheet" "https://www.yageo.com/en/Chart/Download/pdf/CC0402KRX5R6BB224"
			(at 0 0 180)
			(layer "F.Fab")
			(hide yes)
			(effects
				(font
					(size 1.27 1.27)
					(thickness 0.15)
				)
			)
		)
		(property "Author" "Antmicro"
			(at 272.7 174.5 0)
			(layer "F.Fab")
			(hide yes)
			(effects
				(font
					(size 1 1)
					(thickness 0.15)
				)
			)
		)
		(property "Dielectric" ""
			(at 272.7 174.5 0)
			(layer "F.Fab")
			(hide yes)
			(effects
				(font
					(size 1 1)
					(thickness 0.15)
				)
			)
		)
		(property "License" "Apache-2.0"
			(at 272.7 174.5 0)
			(layer "F.Fab")
			(hide yes)
			(effects
				(font
					(size 1 1)
					(thickness 0.15)
				)
			)
		)
		(property "MPN" "CC0402KRX5R6BB224"
			(at 272.7 174.5 0)
			(layer "F.Fab")
			(hide yes)
			(effects
				(font
					(size 1 1)
					(thickness 0.15)
				)
			)
		)
		(property "Manufacturer" "YAGEO"
			(at 272.7 174.5 0)
			(layer "F.Fab")
			(hide yes)
			(effects
				(font
					(size 1 1)
					(thickness 0.15)
				)
			)
		)
		(property "Val" "220n"
			(at 272.7 174.5 0)
			(layer "F.Fab")
			(hide yes)
			(effects
				(font
					(size 1 1)
					(thickness 0.15)
				)
			)
		)
		(property "Voltage" ""
			(at 272.7 174.5 0)
			(layer "F.Fab")
			(hide yes)
			(effects
				(font
					(size 1 1)
					(thickness 0.15)
				)
			)
		)
		(sheetname "Peripherals")
		(sheetfile "peripherals.kicad_sch")
		(attr smd)
		(fp_rect
			(start -0.925 -0.47)
			(end 0.925 0.47)
			(stroke
				(width 0.05)
				(type default)
			)
			(fill none)
			(layer "F.CrtYd")
		)
		(fp_line
			(start 0.504 0.248)
			(end -0.494 0.248)
			(stroke
				(width 0.15)
				(type solid)
			)
			(layer "F.Fab")
		)
		(fp_line
			(start 0.504 -0.25)
			(end 0.504 0.248)
			(stroke
				(width 0.15)
				(type solid)
			)
			(layer "F.Fab")
		)
		(fp_line
			(start -0.494 0.248)
			(end -0.494 -0.25)
			(stroke
				(width 0.15)
				(type solid)
			)
			(layer "F.Fab")
		)
		(fp_line
			(start -0.494 -0.25)
			(end 0.504 -0.25)
			(stroke
				(width 0.15)
				(type solid)
			)
			(layer "F.Fab")
		)
		(fp_text user "${REFERENCE}"
			(at -0.932 3.168 180)
			(layer "F.Fab")
			(hide yes)
			(effects
				(font
					(size 0.7 0.7)
					(thickness 0.15)
				)
				(justify left bottom)
			)
		)
		(fp_text user "Author: Antmicro"
			(at -0.932 4.17 180)
			(layer "F.Fab")
			(hide yes)
			(effects
				(font
					(size 0.7 0.7)
					(thickness 0.15)
				)
				(justify left bottom)
			)
		)
		(fp_text user "License: Apache-2.0"
			(at -0.932 5.17 180)
			(layer "F.Fab")
			(hide yes)
			(effects
				(font
					(size 0.7 0.7)
					(thickness 0.15)
				)
				(justify left bottom)
			)
		)
		(pad "1" smd roundrect
			(at -0.48 0 180)
			(size 0.59 0.64)
			(layers "F.Cu" "F.Paste" "F.Mask")
			(roundrect_rratio 0.25)
			(net 412 "/Peripherals/PCIE2_TX0_CONN_P")
			(pintype "passive")
		)
		(pad "2" smd roundrect
			(at 0.48 0 180)
			(size 0.59 0.64)
			(layers "F.Cu" "F.Paste" "F.Mask")
			(roundrect_rratio 0.25)
			(net 158 "PCIE2_TX0_P")
			(pintype "passive")
		)
	)
	(footprint "antmicro-footprints:LED_0603_1608Metric_G"
		(layer "F.Cu")
		(at 132.8 127.2 -90)
		(descr "LED SMD 0603 Green")
		(tags "LED SMD 0603 Green")
		(property "Reference" "D27"
			(at -1.2 0.5 90)
			(layer "F.SilkS")
			(effects
				(font
					(size 0.7 0.7)
					(thickness 0.15)
				)
				(justify right bottom)
			)
		)
		(property "Value" "LED_G_0603_LTST-C190GKT"
			(at -0.001 1.599 90)
			(layer "F.Fab")
			(effects
				(font
					(size 0.7 0.7)
					(thickness 0.15)
				)
				(justify right bottom)
			)
		)
		(property "Footprint" "antmicro-footprints:LED_0603_1608Metric_G"
			(at 0 0 -90)
			(layer "F.Fab")
			(hide yes)
			(effects
				(font
					(size 1.27 1.27)
					(thickness 0.15)
				)
			)
		)
		(property "Datasheet" "https://media.digikey.com/pdf/Data%20Sheets/Lite-On%20PDFs/LTST-C190GKT.pdf"
			(at 0 0 -90)
			(layer "F.Fab")
			(hide yes)
			(effects
				(font
					(size 1.27 1.27)
					(thickness 0.15)
				)
			)
		)
		(property "Author" "Antmicro"
			(at 5.6 260 0)
			(layer "F.Fab")
			(hide yes)
			(effects
				(font
					(size 1 1)
					(thickness 0.15)
				)
			)
		)
		(property "Color" "Green"
			(at 5.6 260 0)
			(layer "F.Fab")
			(hide yes)
			(effects
				(font
					(size 1 1)
					(thickness 0.15)
				)
			)
		)
		(property "License" "Apache-2.0"
			(at 5.6 260 0)
			(layer "F.Fab")
			(hide yes)
			(effects
				(font
					(size 1 1)
					(thickness 0.15)
				)
			)
		)
		(property "MPN" "LTST-C190GKT"
			(at 5.6 260 0)
			(layer "F.Fab")
			(hide yes)
			(effects
				(font
					(size 1 1)
					(thickness 0.15)
				)
			)
		)
		(property "Manufacturer" "Lite-On"
			(at 5.6 260 0)
			(layer "F.Fab")
			(hide yes)
			(effects
				(font
					(size 1 1)
					(thickness 0.15)
				)
			)
		)
		(sheetname "Peripherals")
		(sheetfile "peripherals.kicad_sch")
		(attr smd)
		(fp_line
			(start 0.22 0.35)
			(end -0.22 0.35)
			(stroke
				(width 0.15)
				(type solid)
			)
			(layer "F.SilkS")
		)
		(fp_line
			(start -0.094672 0.201008)
			(end -0.094672 -0.198992)
			(stroke
				(width 0.1)
				(type solid)
			)
			(layer "F.SilkS")
		)
		(fp_line
			(start 0.105328 0.201008)
			(end -0.094672 0.001008)
			(stroke
				(width 0.1)
				(type solid)
			)
			(layer "F.SilkS")
		)
		(fp_line
			(start 0.105328 0.201008)
			(end 0.105328 -0.198992)
			(stroke
				(width 0.1)
				(type solid)
			)
			(layer "F.SilkS")
		)
		(fp_line
			(start -0.094672 0.001008)
			(end -0.24 0.001008)
			(stroke
				(width 0.1)
				(type solid)
			)
			(layer "F.SilkS")
		)
		(fp_line
			(start -0.094672 0.001008)
			(end 0.105328 -0.198992)
			(stroke
				(width 0.1)
				(type solid)
			)
			(layer "F.SilkS")
		)
		(fp_line
			(start 0.105328 0.001008)
			(end 0.24 0.001)
			(stroke
				(width 0.1)
				(type solid)
			)
			(layer "F.SilkS")
		)
		(fp_line
			(start -1.18 -0.319)
			(end -1.18 0.321)
			(stroke
				(width 0.15)
				(type solid)
			)
			(layer "F.SilkS")
		)
		(fp_line
			(start 0.22 -0.35)
			(end -0.22 -0.35)
			(stroke
				(width 0.15)
				(type solid)
			)
			(layer "F.SilkS")
		)
		(fp_rect
			(start 1.25 0.65)
			(end -1.25 -0.65)
			(stroke
				(width 0.05)
				(type solid)
			)
			(fill none)
			(layer "F.CrtYd")
		)
		(fp_line
			(start -0.199 0.2)
			(end -0.199 0.1)
			(stroke
				(width 0.15)
				(type solid)
			)
			(layer "F.Fab")
		)
		(fp_line
			(start 0.201 0.2)
			(end 0.201 0)
			(stroke
				(width 0.15)
				(type solid)
			)
			(layer "F.Fab")
		)
		(fp_line
			(start -0.199 0)
			(end -0.597 0)
			(stroke
				(width 0.15)
				(type solid)
			)
			(layer "F.Fab")
		)
		(fp_line
			(start -0.101 0)
			(end 0.201 0.2)
			(stroke
				(width 0.15)
				(type solid)
			)
			(layer "F.Fab")
		)
		(fp_line
			(start 0.201 0)
			(end 0.201 -0.202)
			(stroke
				(width 0.15)
				(type solid)
			)
			(layer "F.Fab")
		)
		(fp_line
			(start 0.599 0)
			(end 0.201 0)
			(stroke
				(width 0.15)
				(type solid)
			)
			(layer "F.Fab")
		)
		(fp_line
			(start -0.199 -0.202)
			(end -0.199 0.1)
			(stroke
				(width 0.15)
				(type solid)
			)
			(layer "F.Fab")
		)
		(fp_line
			(start 0.201 -0.202)
			(end -0.101 0)
			(stroke
				(width 0.15)
				(type solid)
			)
			(layer "F.Fab")
		)
		(fp_rect
			(start 0.848 0.4)
			(end -0.85 -0.402)
			(stroke
				(width 0.15)
				(type solid)
			)
			(fill none)
			(layer "F.Fab")
		)
		(fp_text user "License: Apache-2.0"
			(at -1.4224 3.599 90)
			(layer "F.Fab")
			(hide yes)
			(effects
				(font
					(size 0.7 0.7)
					(thickness 0.15)
				)
				(justify right bottom)
			)
		)
		(fp_text user "Author: Antmicro"
			(at -1.4224 4.799 90)
			(layer "F.Fab")
			(hide yes)
			(effects
				(font
					(size 0.7 0.7)
					(thickness 0.15)
				)
				(justify right bottom)
			)
		)
		(fp_text user "${REFERENCE}"
			(at -1.4224 5.999 90)
			(layer "F.Fab")
			(hide yes)
			(effects
				(font
					(size 0.7 0.7)
					(thickness 0.15)
				)
				(justify right bottom)
			)
		)
		(pad "1" smd roundrect
			(at -0.7 0 90)
			(size 0.8 1)
			(layers "F.Cu" "F.Paste" "F.Mask")
			(roundrect_rratio 0.2)
			(net 181 "Net-(D27-C)")
			(pinfunction "C")
			(pintype "passive")
		)
		(pad "2" smd roundrect
			(at 0.7 0 90)
			(size 0.8 1)
			(layers "F.Cu" "F.Paste" "F.Mask")
			(roundrect_rratio 0.2)
			(net 182 "Net-(D27-A)")
			(pinfunction "A")
			(pintype "passive")
		)
	)
	(footprint "antmicro-footprints:C_Pol_EIA-X"
		(layer "F.Cu")
		(at 63.505 88.43)
		(property "Reference" "C2"
			(at -5.135 -2.26 0)
			(layer "F.SilkS")
			(effects
				(font
					(size 0.7 0.7)
					(thickness 0.15)
				)
				(justify left bottom)
			)
		)
		(property "Value" "C_Pol_100u_25V_KEMET-T521-D-107"
			(at 0 3.3 0)
			(layer "F.Fab")
			(effects
				(font
					(size 0.7 0.7)
					(thickness 0.15)
				)
				(justify left bottom)
			)
		)
		(property "Footprint" "antmicro-footprints:C_Pol_EIA-X"
			(at 0 0 0)
			(layer "F.Fab")
			(hide yes)
			(effects
				(font
					(size 1.27 1.27)
					(thickness 0.15)
				)
			)
		)
		(property "Datasheet" "https://content.kemet.com/datasheets/KEM_T2076_T52X-530.pdf"
			(at 0 0 0)
			(layer "F.Fab")
			(hide yes)
			(effects
				(font
					(size 1.27 1.27)
					(thickness 0.15)
				)
			)
		)
		(property "Description" "Surface Mount Tantalum Capacitor, 100 µF, 25 V, 2917 [7343 Metric], ± 20%, 0.04 ohm"
			(at 0 0 0)
			(layer "F.Fab")
			(hide yes)
			(effects
				(font
					(size 1.27 1.27)
					(thickness 0.15)
				)
			)
		)
		(property "Val" "100u"
			(at 0 0 0)
			(unlocked yes)
			(layer "F.Fab")
			(hide yes)
			(effects
				(font
					(size 1 1)
					(thickness 0.15)
				)
			)
		)
		(property "MPN" "T521D107M025ATE040"
			(at 0 0 0)
			(unlocked yes)
			(layer "F.Fab")
			(hide yes)
			(effects
				(font
					(size 1 1)
					(thickness 0.15)
				)
			)
		)
		(property "Manufacturer" "KEMET"
			(at 0 0 0)
			(unlocked yes)
			(layer "F.Fab")
			(hide yes)
			(effects
				(font
					(size 1 1)
					(thickness 0.15)
				)
			)
		)
		(property "License" "Apache-2.0"
			(at 0 0 0)
			(unlocked yes)
			(layer "F.Fab")
			(hide yes)
			(effects
				(font
					(size 1 1)
					(thickness 0.15)
				)
			)
		)
		(property "Author" "Antmicro"
			(at 0 0 0)
			(unlocked yes)
			(layer "F.Fab")
			(hide yes)
			(effects
				(font
					(size 1 1)
					(thickness 0.15)
				)
			)
		)
		(property "Voltage" "25V"
			(at 0 0 0)
			(unlocked yes)
			(layer "F.Fab")
			(hide yes)
			(effects
				(font
					(size 1 1)
					(thickness 0.15)
				)
			)
		)
		(property "Dielectric" "template_dielectric"
			(at 0 0 0)
			(unlocked yes)
			(layer "F.Fab")
			(hide yes)
			(effects
				(font
					(size 1 1)
					(thickness 0.15)
				)
			)
		)
		(sheetname "SoM")
		(sheetfile "som.kicad_sch")
		(attr smd)
		(fp_line
			(start -4.5 -1.8)
			(end -4 -1.8)
			(stroke
				(width 0.15)
				(type solid)
			)
			(layer "F.SilkS")
		)
		(fp_line
			(start -4.25 -2.05)
			(end -4.25 -1.551)
			(stroke
				(width 0.15)
				(type solid)
			)
			(layer "F.SilkS")
		)
		(fp_line
			(start -3.6 -2.2)
			(end 3.6 -2.2)
			(stroke
				(width 0.15)
				(type solid)
			)
			(layer "F.SilkS")
		)
		(fp_line
			(start -3.6 -1.44)
			(end -3.6 -2.2)
			(stroke
				(width 0.15)
				(type solid)
			)
			(layer "F.SilkS")
		)
		(fp_line
			(start -3.6 2.2)
			(end -3.6 1.44)
			(stroke
				(width 0.15)
				(type solid)
			)
			(layer "F.SilkS")
		)
		(fp_line
			(start -3.6 2.2)
			(end 3.6 2.2)
			(stroke
				(width 0.15)
				(type solid)
			)
			(layer "F.SilkS")
		)
		(fp_line
			(start 3.6 -1.44)
			(end 3.6 -2.2)
			(stroke
				(width 0.15)
				(type solid)
			)
			(layer "F.SilkS")
		)
		(fp_line
			(start 3.6 2.2)
			(end 3.6 1.44)
			(stroke
				(width 0.15)
				(type solid)
			)
			(layer "F.SilkS")
		)
		(fp_line
			(start -4.7 -1.4)
			(end -4.7 1.45)
			(stroke
				(width 0.05)
				(type solid)
			)
			(layer "F.CrtYd")
		)
		(fp_line
			(start -4.7 -1.4)
			(end -3.75 -1.4)
			(stroke
				(width 0.05)
				(type solid)
			)
			(layer "F.CrtYd")
		)
		(fp_line
			(start -3.75 -2.4)
			(end -3.75 -1.4)
			(stroke
				(width 0.05)
				(type solid)
			)
			(layer "F.CrtYd")
		)
		(fp_line
			(start -3.75 -2.4)
			(end 3.8 -2.4)
			(stroke
				(width 0.05)
				(type solid)
			)
			(layer "F.CrtYd")
		)
		(fp_line
			(start -3.75 1.45)
			(end -4.7 1.45)
			(stroke
				(width 0.05)
				(type solid)
			)
			(layer "F.CrtYd")
		)
		(fp_line
			(start -3.75 1.45)
			(end -3.75 2.4)
			(stroke
				(width 0.05)
				(type solid)
			)
			(layer "F.CrtYd")
		)
		(fp_line
			(start -3.75 2.4)
			(end 3.8 2.4)
			(stroke
				(width 0.05)
				(type solid)
			)
			(layer "F.CrtYd")
		)
		(fp_line
			(start 3.8 -1.45)
			(end 3.8 -2.4)
			(stroke
				(width 0.05)
				(type solid)
			)
			(layer "F.CrtYd")
		)
		(fp_line
			(start 3.8 -1.45)
			(end 4.75 -1.45)
			(stroke
				(width 0.05)
				(type solid)
			)
			(layer "F.CrtYd")
		)
		(fp_line
			(start 3.8 2.4)
			(end 3.8 1.4)
			(stroke
				(width 0.05)
				(type solid)
			)
			(layer "F.CrtYd")
		)
		(fp_line
			(start 4.75 1.4)
			(end 3.8 1.4)
			(stroke
				(width 0.05)
				(type solid)
			)
			(layer "F.CrtYd")
		)
		(fp_line
			(start 4.75 1.4)
			(end 4.75 -1.45)
			(stroke
				(width 0.05)
				(type solid)
			)
			(layer "F.CrtYd")
		)
		(fp_line
			(start -3.799 -2.3)
			(end 3.799 -2.3)
			(stroke
				(width 0.15)
				(type solid)
			)
			(layer "F.Fab")
		)
		(fp_line
			(start -3.799 2.3)
			(end -3.799 -2.3)
			(stroke
				(width 0.15)
				(type solid)
			)
			(layer "F.Fab")
		)
		(fp_line
			(start 3.799 -2.3)
			(end 3.799 2.3)
			(stroke
				(width 0.15)
				(type solid)
			)
			(layer "F.Fab")
		)
		(fp_line
			(start 3.799 2.3)
			(end -3.799 2.3)
			(stroke
				(width 0.15)
				(type solid)
			)
			(layer "F.Fab")
		)
		(fp_text user "License: Apache-2.0"
			(at -4.5 6.79 0)
			(layer "F.Fab")
			(hide yes)
			(effects
				(font
					(size 0.7 0.7)
					(thickness 0.15)
				)
				(justify left bottom)
			)
		)
		(fp_text user "${REFERENCE}"
			(at -4.5 4.39 0)
			(layer "F.Fab")
			(hide yes)
			(effects
				(font
					(size 0.7 0.7)
					(thickness 0.15)
				)
				(justify left bottom)
			)
		)
		(fp_text user "Author: Antmicro"
			(at -4.5 5.59 0)
			(layer "F.Fab")
			(hide yes)
			(effects
				(font
					(size 0.7 0.7)
					(thickness 0.15)
				)
				(justify left bottom)
			)
		)
		(pad "1" smd roundrect
			(at -3.25 0)
			(size 2.5 2.33)
			(layers "F.Cu" "F.Paste" "F.Mask")
			(roundrect_rratio 0.1)
			(net 438 "/SoM/SoM_VIN")
			(pintype "passive")
		)
		(pad "2" smd roundrect
			(at 3.25 0)
			(size 2.5 2.33)
			(layers "F.Cu" "F.Paste" "F.Mask")
			(roundrect_rratio 0.1)
			(net 1 "GND")
			(pintype "passive")
		)
	)
	(footprint "antmicro-footprints:R_Array_4x0402"
		(layer "F.Cu")
		(at 139.3 102.3 90)
		(property "Reference" "R54"
			(at -1.025 -0.95 90)
			(layer "F.SilkS")
			(effects
				(font
					(size 0.7 0.7)
					(thickness 0.15)
				)
				(justify left bottom)
			)
		)
		(property "Value" "R_4x330R_0402_array"
			(at -1.5 2 90)
			(layer "F.Fab")
			(effects
				(font
					(size 0.7 0.7)
					(thickness 0.15)
				)
				(justify left bottom)
			)
		)
		(property "Footprint" "antmicro-footprints:R_Array_4x0402"
			(at 0 0 90)
			(layer "F.Fab")
			(hide yes)
			(effects
				(font
					(size 1.27 1.27)
					(thickness 0.15)
				)
			)
		)
		(property "Datasheet" "http://industrial.panasonic.com/cdbs/www-data/pdf/AOC0000/AOC0000C14.pdf"
			(at 0 0 90)
			(layer "F.Fab")
			(hide yes)
			(effects
				(font
					(size 1.27 1.27)
					(thickness 0.15)
				)
			)
		)
		(property "Author" "Antmicro"
			(at 241.6 -37 0)
			(layer "F.Fab")
			(hide yes)
			(effects
				(font
					(size 1 1)
					(thickness 0.15)
				)
			)
		)
		(property "License" "Apache-2.0"
			(at 241.6 -37 0)
			(layer "F.Fab")
			(hide yes)
			(effects
				(font
					(size 1 1)
					(thickness 0.15)
				)
			)
		)
		(property "MPN" "EXB-28V331JX"
			(at 241.6 -37 0)
			(layer "F.Fab")
			(hide yes)
			(effects
				(font
					(size 1 1)
					(thickness 0.15)
				)
			)
		)
		(property "Manufacturer" "Panasonic"
			(at 241.6 -37 0)
			(layer "F.Fab")
			(hide yes)
			(effects
				(font
					(size 1 1)
					(thickness 0.15)
				)
			)
		)
		(property "Val" "R_4x330R_0402"
			(at 241.6 -37 0)
			(layer "F.Fab")
			(hide yes)
			(effects
				(font
					(size 1 1)
					(thickness 0.15)
				)
			)
		)
		(sheetname "Peripherals")
		(sheetfile "peripherals.kicad_sch")
		(attr smd)
		(fp_line
			(start -1.17 -0.5)
			(end -1.17 0.498)
			(stroke
				(width 0.15)
				(type solid)
			)
			(layer "F.SilkS")
		)
		(fp_line
			(start 1.167 0.498)
			(end 1.167 -0.5)
			(stroke
				(width 0.15)
				(type solid)
			)
			(layer "F.SilkS")
		)
		(fp_rect
			(start -1.2 -0.9)
			(end 1.2 0.9)
			(stroke
				(width 0.05)
				(type solid)
			)
			(fill none)
			(layer "F.CrtYd")
		)
		(fp_line
			(start 0.998 -0.5)
			(end 0.998 0.498)
			(stroke
				(width 0.15)
				(type solid)
			)
			(layer "F.Fab")
		)
		(fp_line
			(start -1 -0.5)
			(end 0.998 -0.5)
			(stroke
				(width 0.15)
				(type solid)
			)
			(layer "F.Fab")
		)
		(fp_line
			(start 0.998 0.498)
			(end -1 0.498)
			(stroke
				(width 0.15)
				(type solid)
			)
			(layer "F.Fab")
		)
		(fp_line
			(start -1 0.498)
			(end -1 -0.5)
			(stroke
				(width 0.15)
				(type solid)
			)
			(layer "F.Fab")
		)
		(fp_text user "${REFERENCE}"
			(at -1.5 3.25 90)
			(layer "F.Fab")
			(hide yes)
			(effects
				(font
					(size 0.7 0.7)
					(thickness 0.15)
				)
				(justify left bottom)
			)
		)
		(fp_text user "Author: Antmicro"
			(at -1.5 4.5 90)
			(layer "F.Fab")
			(hide yes)
			(effects
				(font
					(size 0.7 0.7)
					(thickness 0.15)
				)
				(justify left bottom)
			)
		)
		(fp_text user "License: Apache-2.0"
			(at -1.5 5.75 90)
			(layer "F.Fab")
			(hide yes)
			(effects
				(font
					(size 0.7 0.7)
					(thickness 0.15)
				)
				(justify left bottom)
			)
		)
		(pad "1" smd roundrect
			(at -0.802 0.45 90)
			(size 0.4 0.5)
			(layers "F.Cu" "F.Paste" "F.Mask")
			(roundrect_rratio 0.25)
			(net 591 "/Peripherals/SPIO_MOSI_CONN")
			(pinfunction "R1.1")
			(pintype "passive")
		)
		(pad "2" smd roundrect
			(at -0.272 0.45 90)
			(size 0.4 0.5)
			(layers "F.Cu" "F.Paste" "F.Mask")
			(roundrect_rratio 0.25)
			(net 589 "/Peripherals/SPIO_SCK_CONN")
			(pinfunction "R2.1")
			(pintype "passive")
		)
		(pad "3" smd roundrect
			(at 0.27 0.45 90)
			(size 0.4 0.5)
			(layers "F.Cu" "F.Paste" "F.Mask")
			(roundrect_rratio 0.25)
			(net 587 "/Peripherals/I2S0_LRCK_CONN")
			(pinfunction "R3.1")
			(pintype "passive")
		)
		(pad "4" smd roundrect
			(at 0.8 0.45 90)
			(size 0.4 0.5)
			(layers "F.Cu" "F.Paste" "F.Mask")
			(roundrect_rratio 0.25)
			(net 585 "/Peripherals/I2S0_SDIN_CONN")
			(pinfunction "R4.1")
			(pintype "passive")
		)
		(pad "5" smd roundrect
			(at 0.8 -0.452 90)
			(size 0.4 0.5)
			(layers "F.Cu" "F.Paste" "F.Mask")
			(roundrect_rratio 0.25)
			(net 71 "I2S0_SDIN")
			(pinfunction "R4.2")
			(pintype "passive")
		)
		(pad "6" smd roundrect
			(at 0.27 -0.452 90)
			(size 0.4 0.5)
			(layers "F.Cu" "F.Paste" "F.Mask")
			(roundrect_rratio 0.25)
			(net 73 "I2S0_LRCK")
			(pinfunction "R3.2")
			(pintype "passive")
		)
		(pad "7" smd roundrect
			(at -0.272 -0.452 90)
			(size 0.4 0.5)
			(layers "F.Cu" "F.Paste" "F.Mask")
			(roundrect_rratio 0.25)
			(net 31 "SPIO_SCK")
			(pinfunction "R2.2")
			(pintype "passive")
		)
		(pad "8" smd roundrect
			(at -0.802 -0.452 90)
			(size 0.4 0.5)
			(layers "F.Cu" "F.Paste" "F.Mask")
			(roundrect_rratio 0.25)
			(net 30 "SPIO_MOSI")
			(pinfunction "R1.2")
			(pintype "passive")
		)
	)
	(footprint "antmicro-footprints:R_0402_1005Metric"
		(layer "F.Cu")
		(at 86.55 103.8 180)
		(descr "Resistor SMD 0402")
		(tags "resistor SMD 0402")
		(property "Reference" "R208"
			(at 1.35 0.57 180)
			(layer "F.SilkS")
			(effects
				(font
					(size 0.7 0.7)
					(thickness 0.15)
				)
				(justify left bottom)
			)
		)
		(property "Value" "R_2k2_0402"
			(at 0 1.4 180)
			(layer "F.Fab")
			(effects
				(font
					(size 0.7 0.7)
					(thickness 0.15)
				)
				(justify left bottom)
			)
		)
		(property "Footprint" "antmicro-footprints:R_0402_1005Metric"
			(at 0 0 180)
			(layer "F.Fab")
			(hide yes)
			(effects
				(font
					(size 1.27 1.27)
					(thickness 0.15)
				)
			)
		)
		(property "Datasheet" "https://www.bourns.com/docs/product-datasheets/cr.pdf"
			(at 0 0 180)
			(layer "F.Fab")
			(hide yes)
			(effects
				(font
					(size 1.27 1.27)
					(thickness 0.15)
				)
			)
		)
		(property "Author" "Antmicro"
			(at 173.1 207.6 0)
			(layer "F.Fab")
			(hide yes)
			(effects
				(font
					(size 1 1)
					(thickness 0.15)
				)
			)
		)
		(property "License" "Apache-2.0"
			(at 173.1 207.6 0)
			(layer "F.Fab")
			(hide yes)
			(effects
				(font
					(size 1 1)
					(thickness 0.15)
				)
			)
		)
		(property "MPN" "CR0402-FX-2201GLF"
			(at 173.1 207.6 0)
			(layer "F.Fab")
			(hide yes)
			(effects
				(font
					(size 1 1)
					(thickness 0.15)
				)
			)
		)
		(property "Manufacturer" "Bourns"
			(at 173.1 207.6 0)
			(layer "F.Fab")
			(hide yes)
			(effects
				(font
					(size 1 1)
					(thickness 0.15)
				)
			)
		)
		(property "Tolerance" "1%"
			(at 173.1 207.6 0)
			(layer "F.Fab")
			(hide yes)
			(effects
				(font
					(size 1 1)
					(thickness 0.15)
				)
			)
		)
		(property "Val" "2k2"
			(at 173.1 207.6 0)
			(layer "F.Fab")
			(hide yes)
			(effects
				(font
					(size 1 1)
					(thickness 0.15)
				)
			)
		)
		(sheetname "HDMI")
		(sheetfile "hdmi.kicad_sch")
		(attr smd exclude_from_pos_files exclude_from_bom dnp)
		(fp_rect
			(start -0.925 -0.47)
			(end 0.925 0.47)
			(stroke
				(width 0.05)
				(type default)
			)
			(fill none)
			(layer "F.CrtYd")
		)
		(fp_rect
			(start -0.5 -0.25)
			(end 0.5 0.25)
			(stroke
				(width 0.15)
				(type solid)
			)
			(fill none)
			(layer "F.Fab")
		)
		(fp_text user "${REFERENCE}"
			(at -0.95 3.168 180)
			(layer "F.Fab")
			(hide yes)
			(effects
				(font
					(size 0.7 0.7)
					(thickness 0.15)
				)
				(justify left bottom)
			)
		)
		(fp_text user "Author: Antmicro"
			(at -0.95 4.169 180)
			(layer "F.Fab")
			(hide yes)
			(effects
				(font
					(size 0.7 0.7)
					(thickness 0.15)
				)
				(justify left bottom)
			)
		)
		(fp_text user "License: Apache-2.0"
			(at -0.95 5.169 180)
			(layer "F.Fab")
			(hide yes)
			(effects
				(font
					(size 0.7 0.7)
					(thickness 0.15)
				)
				(justify left bottom)
			)
		)
		(pad "1" smd roundrect
			(at -0.48 0 180)
			(size 0.59 0.64)
			(layers "F.Cu" "F.Paste" "F.Mask")
			(roundrect_rratio 0.25)
			(net 703 "/HDMI/HDMI_HPD")
			(pintype "passive")
		)
		(pad "2" smd roundrect
			(at 0.48 0 180)
			(size 0.59 0.64)
			(layers "F.Cu" "F.Paste" "F.Mask")
			(roundrect_rratio 0.25)
			(net 87 "+3V3")
			(pintype "passive")
		)
	)
	(footprint "antmicro-footprints:TP_SMD_0.75mm"
		(layer "F.Cu")
		(at 127.905 112.21 180)
		(property "Reference" "TP9"
			(at -0.425 -0.43 180)
			(layer "F.SilkS")
			(effects
				(font
					(size 0.7 0.7)
					(thickness 0.15)
				)
				(justify left bottom)
			)
		)
		(property "Value" "TP_0.75mm_SMD"
			(at 0 1.2 180)
			(layer "F.Fab")
			(effects
				(font
					(size 0.7 0.7)
					(thickness 0.15)
				)
				(justify left bottom)
			)
		)
		(property "Footprint" "antmicro-footprints:TP_SMD_0.75mm"
			(at 0 0 180)
			(layer "F.Fab")
			(hide yes)
			(effects
				(font
					(size 1.27 1.27)
					(thickness 0.15)
				)
			)
		)
		(property "Author" "Antmicro"
			(at 255.81 224.42 0)
			(layer "F.Fab")
			(hide yes)
			(effects
				(font
					(size 1 1)
					(thickness 0.15)
				)
			)
		)
		(property "License" "Apache-2.0"
			(at 255.81 224.42 0)
			(layer "F.Fab")
			(hide yes)
			(effects
				(font
					(size 1 1)
					(thickness 0.15)
				)
			)
		)
		(property "MPN" ""
			(at 255.81 224.42 0)
			(layer "F.Fab")
			(hide yes)
			(effects
				(font
					(size 1 1)
					(thickness 0.15)
				)
			)
		)
		(property "Manufacturer" ""
			(at 255.81 224.42 0)
			(layer "F.Fab")
			(hide yes)
			(effects
				(font
					(size 1 1)
					(thickness 0.15)
				)
			)
		)
		(sheetname "M.2")
		(sheetfile "m-2.kicad_sch")
		(attr exclude_from_pos_files exclude_from_bom)
		(fp_circle
			(center 0 0)
			(end 0.475 0)
			(stroke
				(width 0.05)
				(type default)
			)
			(fill none)
			(layer "F.CrtYd")
		)
		(fp_text user "Author: Antmicro"
			(at -0.4 3.901 180)
			(layer "F.Fab")
			(hide yes)
			(effects
				(font
					(size 0.7 0.7)
					(thickness 0.15)
				)
				(justify left bottom)
			)
		)
		(fp_text user "License: Apache-2.0"
			(at -0.4 5.101 180)
			(layer "F.Fab")
			(hide yes)
			(effects
				(font
					(size 0.7 0.7)
					(thickness 0.15)
				)
				(justify left bottom)
			)
		)
		(fp_text user "${REFERENCE}"
			(at -0.4 2.7 180)
			(layer "F.Fab")
			(hide yes)
			(effects
				(font
					(size 0.7 0.7)
					(thickness 0.15)
				)
				(justify left bottom)
			)
		)
		(pad "1" smd circle
			(at 0 0 180)
			(size 0.75 0.75)
			(layers "F.Cu" "F.Mask")
			(net 183 "/M.2/~{M2_E_UART_WAKE}")
			(pinfunction "1")
			(pintype "passive")
		)
	)
	(footprint "antmicro-footprints:R_0402_1005Metric"
		(layer "F.Cu")
		(at 105.15 120.75)
		(descr "Resistor SMD 0402")
		(tags "resistor SMD 0402")
		(property "Reference" "R138"
			(at -1.03 1.37 0)
			(layer "F.SilkS")
			(effects
				(font
					(size 0.7 0.7)
					(thickness 0.15)
				)
				(justify left bottom)
			)
		)
		(property "Value" "R_10k_0402"
			(at 0 1.4 0)
			(layer "F.Fab")
			(effects
				(font
					(size 0.7 0.7)
					(thickness 0.15)
				)
				(justify left bottom)
			)
		)
		(property "Footprint" "antmicro-footprints:R_0402_1005Metric"
			(at 0 0 0)
			(layer "F.Fab")
			(hide yes)
			(effects
				(font
					(size 1.27 1.27)
					(thickness 0.15)
				)
			)
		)
		(property "Datasheet" "https://www.bourns.com/docs/product-datasheets/cr.pdf"
			(at 0 0 0)
			(layer "F.Fab")
			(hide yes)
			(effects
				(font
					(size 1.27 1.27)
					(thickness 0.15)
				)
			)
		)
		(property "Author" "Antmicro"
			(at 0 0 0)
			(layer "F.Fab")
			(hide yes)
			(effects
				(font
					(size 1 1)
					(thickness 0.15)
				)
			)
		)
		(property "License" "Apache-2.0"
			(at 0 0 0)
			(layer "F.Fab")
			(hide yes)
			(effects
				(font
					(size 1 1)
					(thickness 0.15)
				)
			)
		)
		(property "MPN" "CR0402-FX-1002GLF"
			(at 0 0 0)
			(layer "F.Fab")
			(hide yes)
			(effects
				(font
					(size 1 1)
					(thickness 0.15)
				)
			)
		)
		(property "Manufacturer" "Bourns"
			(at 0 0 0)
			(layer "F.Fab")
			(hide yes)
			(effects
				(font
					(size 1 1)
					(thickness 0.15)
				)
			)
		)
		(property "Tolerance" "1%"
			(at 0 0 0)
			(layer "F.Fab")
			(hide yes)
			(effects
				(font
					(size 1 1)
					(thickness 0.15)
				)
			)
		)
		(property "Val" "10k"
			(at 0 0 0)
			(layer "F.Fab")
			(hide yes)
			(effects
				(font
					(size 1 1)
					(thickness 0.15)
				)
			)
		)
		(sheetname "USB3")
		(sheetfile "usb3.kicad_sch")
		(attr smd)
		(fp_rect
			(start -0.925 -0.47)
			(end 0.925 0.47)
			(stroke
				(width 0.05)
				(type default)
			)
			(fill none)
			(layer "F.CrtYd")
		)
		(fp_rect
			(start -0.5 -0.25)
			(end 0.5 0.25)
			(stroke
				(width 0.15)
				(type solid)
			)
			(fill none)
			(layer "F.Fab")
		)
		(fp_text user "${REFERENCE}"
			(at -0.95 3.168 0)
			(layer "F.Fab")
			(hide yes)
			(effects
				(font
					(size 0.7 0.7)
					(thickness 0.15)
				)
				(justify left bottom)
			)
		)
		(fp_text user "Author: Antmicro"
			(at -0.95 4.169 0)
			(layer "F.Fab")
			(hide yes)
			(effects
				(font
					(size 0.7 0.7)
					(thickness 0.15)
				)
				(justify left bottom)
			)
		)
		(fp_text user "License: Apache-2.0"
			(at -0.95 5.169 0)
			(layer "F.Fab")
			(hide yes)
			(effects
				(font
					(size 0.7 0.7)
					(thickness 0.15)
				)
				(justify left bottom)
			)
		)
		(pad "1" smd roundrect
			(at -0.48 0)
			(size 0.59 0.64)
			(layers "F.Cu" "F.Paste" "F.Mask")
			(roundrect_rratio 0.25)
			(net 508 "USBC1_FLG")
			(pintype "passive")
		)
		(pad "2" smd roundrect
			(at 0.48 0)
			(size 0.59 0.64)
			(layers "F.Cu" "F.Paste" "F.Mask")
			(roundrect_rratio 0.25)
			(net 87 "+3V3")
			(pintype "passive")
		)
	)
	(footprint "antmicro-footprints:R_0402_1005Metric"
		(layer "F.Cu")
		(at 42.115 103.541 180)
		(descr "Resistor SMD 0402")
		(tags "resistor SMD 0402")
		(property "Reference" "R229"
			(at 1.315 0.441 180)
			(layer "F.SilkS")
			(effects
				(font
					(size 0.7 0.7)
					(thickness 0.15)
				)
				(justify left bottom)
			)
		)
		(property "Value" "R_100k_0402"
			(at 0 1.4 180)
			(layer "F.Fab")
			(effects
				(font
					(size 0.7 0.7)
					(thickness 0.15)
				)
				(justify left bottom)
			)
		)
		(property "Footprint" "antmicro-footprints:R_0402_1005Metric"
			(at 0 0 180)
			(layer "F.Fab")
			(hide yes)
			(effects
				(font
					(size 1.27 1.27)
					(thickness 0.15)
				)
			)
		)
		(property "Datasheet" "https://www.bourns.com/docs/product-datasheets/cr.pdf"
			(at 0 0 180)
			(layer "F.Fab")
			(hide yes)
			(effects
				(font
					(size 1.27 1.27)
					(thickness 0.15)
				)
			)
		)
		(property "Author" "Antmicro"
			(at 84.23 207.082 0)
			(layer "F.Fab")
			(hide yes)
			(effects
				(font
					(size 1 1)
					(thickness 0.15)
				)
			)
		)
		(property "License" "Apache-2.0"
			(at 84.23 207.082 0)
			(layer "F.Fab")
			(hide yes)
			(effects
				(font
					(size 1 1)
					(thickness 0.15)
				)
			)
		)
		(property "MPN" "CR0402-FX-1003GLF"
			(at 84.23 207.082 0)
			(layer "F.Fab")
			(hide yes)
			(effects
				(font
					(size 1 1)
					(thickness 0.15)
				)
			)
		)
		(property "Manufacturer" "Bourns"
			(at 84.23 207.082 0)
			(layer "F.Fab")
			(hide yes)
			(effects
				(font
					(size 1 1)
					(thickness 0.15)
				)
			)
		)
		(property "Tolerance" "1%"
			(at 84.23 207.082 0)
			(layer "F.Fab")
			(hide yes)
			(effects
				(font
					(size 1 1)
					(thickness 0.15)
				)
			)
		)
		(property "Val" "100k"
			(at 84.23 207.082 0)
			(layer "F.Fab")
			(hide yes)
			(effects
				(font
					(size 1 1)
					(thickness 0.15)
				)
			)
		)
		(sheetname "Ethernet")
		(sheetfile "ethernet.kicad_sch")
		(attr smd exclude_from_pos_files exclude_from_bom dnp)
		(fp_rect
			(start -0.925 -0.47)
			(end 0.925 0.47)
			(stroke
				(width 0.05)
				(type default)
			)
			(fill none)
			(layer "F.CrtYd")
		)
		(fp_rect
			(start -0.5 -0.25)
			(end 0.5 0.25)
			(stroke
				(width 0.15)
				(type solid)
			)
			(fill none)
			(layer "F.Fab")
		)
		(fp_text user "License: Apache-2.0"
			(at -0.95 5.169 180)
			(layer "F.Fab")
			(hide yes)
			(effects
				(font
					(size 0.7 0.7)
					(thickness 0.15)
				)
				(justify left bottom)
			)
		)
		(fp_text user "${REFERENCE}"
			(at -0.95 3.168 180)
			(layer "F.Fab")
			(hide yes)
			(effects
				(font
					(size 0.7 0.7)
					(thickness 0.15)
				)
				(justify left bottom)
			)
		)
		(fp_text user "Author: Antmicro"
			(at -0.95 4.169 180)
			(layer "F.Fab")
			(hide yes)
			(effects
				(font
					(size 0.7 0.7)
					(thickness 0.15)
				)
				(justify left bottom)
			)
		)
		(pad "1" smd roundrect
			(at -0.48 0 180)
			(size 0.59 0.64)
			(layers "F.Cu" "F.Paste" "F.Mask")
			(roundrect_rratio 0.25)
			(net 106 "GNDD")
			(pintype "passive")
		)
		(pad "2" smd roundrect
			(at 0.48 0 180)
			(size 0.59 0.64)
			(layers "F.Cu" "F.Paste" "F.Mask")
			(roundrect_rratio 0.25)
			(net 650 "/Ethernet/ULS-12_CTRL")
			(pintype "passive")
		)
	)
	(footprint "antmicro-footprints:R_0402_1005Metric"
		(layer "F.Cu")
		(at 114.4 97 180)
		(descr "Resistor SMD 0402")
		(tags "resistor SMD 0402")
		(property "Reference" "R29"
			(at 3.95 1.05 180)
			(layer "F.SilkS")
			(effects
				(font
					(size 0.7 0.7)
					(thickness 0.15)
				)
				(justify left bottom)
			)
		)
		(property "Value" "R_0R_0402"
			(at 0 1.4 180)
			(layer "F.Fab")
			(effects
				(font
					(size 0.7 0.7)
					(thickness 0.15)
				)
				(justify left bottom)
			)
		)
		(property "Footprint" "antmicro-footprints:R_0402_1005Metric"
			(at 0 0 180)
			(layer "F.Fab")
			(hide yes)
			(effects
				(font
					(size 1.27 1.27)
					(thickness 0.15)
				)
			)
		)
		(property "Datasheet" "https://industrial.panasonic.com/cdbs/www-data/pdf/RDA0000/AOA0000C301.pdf"
			(at 0 0 180)
			(layer "F.Fab")
			(hide yes)
			(effects
				(font
					(size 1.27 1.27)
					(thickness 0.15)
				)
			)
		)
		(property "Author" "Antmicro"
			(at 228.8 194 0)
			(layer "F.Fab")
			(hide yes)
			(effects
				(font
					(size 1 1)
					(thickness 0.15)
				)
			)
		)
		(property "Current" "1A"
			(at 228.8 194 0)
			(layer "F.Fab")
			(hide yes)
			(effects
				(font
					(size 1 1)
					(thickness 0.15)
				)
			)
		)
		(property "License" "Apache-2.0"
			(at 228.8 194 0)
			(layer "F.Fab")
			(hide yes)
			(effects
				(font
					(size 1 1)
					(thickness 0.15)
				)
			)
		)
		(property "MPN" "ERJ2GE0R00X"
			(at 228.8 194 0)
			(layer "F.Fab")
			(hide yes)
			(effects
				(font
					(size 1 1)
					(thickness 0.15)
				)
			)
		)
		(property "Manufacturer" "Panasonic"
			(at 228.8 194 0)
			(layer "F.Fab")
			(hide yes)
			(effects
				(font
					(size 1 1)
					(thickness 0.15)
				)
			)
		)
		(property "Tolerance" ""
			(at 228.8 194 0)
			(layer "F.Fab")
			(hide yes)
			(effects
				(font
					(size 1 1)
					(thickness 0.15)
				)
			)
		)
		(property "Val" "0R"
			(at 228.8 194 0)
			(layer "F.Fab")
			(hide yes)
			(effects
				(font
					(size 1 1)
					(thickness 0.15)
				)
			)
		)
		(sheetname "M.2")
		(sheetfile "m-2.kicad_sch")
		(attr smd)
		(fp_rect
			(start -0.925 -0.47)
			(end 0.925 0.47)
			(stroke
				(width 0.05)
				(type default)
			)
			(fill none)
			(layer "F.CrtYd")
		)
		(fp_rect
			(start -0.5 -0.25)
			(end 0.5 0.25)
			(stroke
				(width 0.15)
				(type solid)
			)
			(fill none)
			(layer "F.Fab")
		)
		(fp_text user "${REFERENCE}"
			(at -0.95 3.168 180)
			(layer "F.Fab")
			(hide yes)
			(effects
				(font
					(size 0.7 0.7)
					(thickness 0.15)
				)
				(justify left bottom)
			)
		)
		(fp_text user "License: Apache-2.0"
			(at -0.95 5.169 180)
			(layer "F.Fab")
			(hide yes)
			(effects
				(font
					(size 0.7 0.7)
					(thickness 0.15)
				)
				(justify left bottom)
			)
		)
		(fp_text user "Author: Antmicro"
			(at -0.95 4.169 180)
			(layer "F.Fab")
			(hide yes)
			(effects
				(font
					(size 0.7 0.7)
					(thickness 0.15)
				)
				(justify left bottom)
			)
		)
		(pad "1" smd roundrect
			(at -0.48 0 180)
			(size 0.59 0.64)
			(layers "F.Cu" "F.Paste" "F.Mask")
			(roundrect_rratio 0.25)
			(net 216 "/M.2/M2_E_SUSCLK")
			(pintype "passive")
		)
		(pad "2" smd roundrect
			(at 0.48 0 180)
			(size 0.59 0.64)
			(layers "F.Cu" "F.Paste" "F.Mask")
			(roundrect_rratio 0.25)
			(net 456 "/M.2/32.7KHZ_OUT")
			(pintype "passive")
		)
	)
	(footprint "antmicro-footprints:R_0402_1005Metric"
		(layer "F.Cu")
		(at 105.154938 109)
		(descr "Resistor SMD 0402")
		(tags "resistor SMD 0402")
		(property "Reference" "R201"
			(at -3.654938 0.45 0)
			(layer "F.SilkS")
			(effects
				(font
					(size 0.7 0.7)
					(thickness 0.15)
				)
				(justify left bottom)
			)
		)
		(property "Value" "R_0R_0402"
			(at 0 1.4 0)
			(layer "F.Fab")
			(effects
				(font
					(size 0.7 0.7)
					(thickness 0.15)
				)
				(justify left bottom)
			)
		)
		(property "Footprint" "antmicro-footprints:R_0402_1005Metric"
			(at 0 0 0)
			(layer "F.Fab")
			(hide yes)
			(effects
				(font
					(size 1.27 1.27)
					(thickness 0.15)
				)
			)
		)
		(property "Datasheet" "https://industrial.panasonic.com/cdbs/www-data/pdf/RDA0000/AOA0000C301.pdf"
			(at 0 0 0)
			(layer "F.Fab")
			(hide yes)
			(effects
				(font
					(size 1.27 1.27)
					(thickness 0.15)
				)
			)
		)
		(property "Author" "Antmicro"
			(at 0 0 0)
			(layer "F.Fab")
			(hide yes)
			(effects
				(font
					(size 1 1)
					(thickness 0.15)
				)
			)
		)
		(property "Current" "1A"
			(at 0 0 0)
			(layer "F.Fab")
			(hide yes)
			(effects
				(font
					(size 1 1)
					(thickness 0.15)
				)
			)
		)
		(property "License" "Apache-2.0"
			(at 0 0 0)
			(layer "F.Fab")
			(hide yes)
			(effects
				(font
					(size 1 1)
					(thickness 0.15)
				)
			)
		)
		(property "MPN" "ERJ2GE0R00X"
			(at 0 0 0)
			(layer "F.Fab")
			(hide yes)
			(effects
				(font
					(size 1 1)
					(thickness 0.15)
				)
			)
		)
		(property "Manufacturer" "Panasonic"
			(at 0 0 0)
			(layer "F.Fab")
			(hide yes)
			(effects
				(font
					(size 1 1)
					(thickness 0.15)
				)
			)
		)
		(property "Tolerance" ""
			(at 0 0 0)
			(layer "F.Fab")
			(hide yes)
			(effects
				(font
					(size 1 1)
					(thickness 0.15)
				)
			)
		)
		(property "Val" "0R"
			(at 0 0 0)
			(layer "F.Fab")
			(hide yes)
			(effects
				(font
					(size 1 1)
					(thickness 0.15)
				)
			)
		)
		(sheetname "USB3")
		(sheetfile "usb3.kicad_sch")
		(attr smd)
		(fp_rect
			(start -0.925 -0.47)
			(end 0.925 0.47)
			(stroke
				(width 0.05)
				(type default)
			)
			(fill none)
			(layer "F.CrtYd")
		)
		(fp_rect
			(start -0.5 -0.25)
			(end 0.5 0.25)
			(stroke
				(width 0.15)
				(type solid)
			)
			(fill none)
			(layer "F.Fab")
		)
		(fp_text user "${REFERENCE}"
			(at -0.95 3.168 0)
			(layer "F.Fab")
			(hide yes)
			(effects
				(font
					(size 0.7 0.7)
					(thickness 0.15)
				)
				(justify left bottom)
			)
		)
		(fp_text user "Author: Antmicro"
			(at -0.95 4.169 0)
			(layer "F.Fab")
			(hide yes)
			(effects
				(font
					(size 0.7 0.7)
					(thickness 0.15)
				)
				(justify left bottom)
			)
		)
		(fp_text user "License: Apache-2.0"
			(at -0.95 5.169 0)
			(layer "F.Fab")
			(hide yes)
			(effects
				(font
					(size 0.7 0.7)
					(thickness 0.15)
				)
				(justify left bottom)
			)
		)
		(pad "1" smd roundrect
			(at -0.48 0)
			(size 0.59 0.64)
			(layers "F.Cu" "F.Paste" "F.Mask")
			(roundrect_rratio 0.25)
			(net 159 "USBSS2_RX_N")
			(pintype "passive")
		)
		(pad "2" smd roundrect
			(at 0.48 0)
			(size 0.59 0.64)
			(layers "F.Cu" "F.Paste" "F.Mask")
			(roundrect_rratio 0.25)
			(net 611 "/USB3/USBSS1_C_RX_P")
			(pintype "passive")
		)
	)
	(footprint "antmicro-footprints:C_0402_1005Metric"
		(layer "F.Cu")
		(at 81.9 108 180)
		(descr "Capacitor SMD 0402")
		(tags "capacitor SMD 0402")
		(property "Reference" "C140"
			(at -0.85 -0.45 180)
			(layer "F.SilkS")
			(effects
				(font
					(size 0.7 0.7)
					(thickness 0.15)
				)
				(justify left bottom)
			)
		)
		(property "Value" "C_100n_0402"
			(at 0 1.4 180)
			(layer "F.Fab")
			(effects
				(font
					(size 0.7 0.7)
					(thickness 0.15)
				)
				(justify left bottom)
			)
		)
		(property "Footprint" "antmicro-footprints:C_0402_1005Metric"
			(at 0 0 180)
			(layer "F.Fab")
			(hide yes)
			(effects
				(font
					(size 1.27 1.27)
					(thickness 0.15)
				)
			)
		)
		(property "Datasheet" "https://www.murata.com/products/productdetail?partno=GRM155R61H104KE14%23"
			(at 0 0 180)
			(layer "F.Fab")
			(hide yes)
			(effects
				(font
					(size 1.27 1.27)
					(thickness 0.15)
				)
			)
		)
		(property "Author" "Antmicro"
			(at 163.8 216 0)
			(layer "F.Fab")
			(hide yes)
			(effects
				(font
					(size 1 1)
					(thickness 0.15)
				)
			)
		)
		(property "Dielectric" "X5R"
			(at 163.8 216 0)
			(layer "F.Fab")
			(hide yes)
			(effects
				(font
					(size 1 1)
					(thickness 0.15)
				)
			)
		)
		(property "License" "Apache-2.0"
			(at 163.8 216 0)
			(layer "F.Fab")
			(hide yes)
			(effects
				(font
					(size 1 1)
					(thickness 0.15)
				)
			)
		)
		(property "MPN" "GRM155R61H104KE14D"
			(at 163.8 216 0)
			(layer "F.Fab")
			(hide yes)
			(effects
				(font
					(size 1 1)
					(thickness 0.15)
				)
			)
		)
		(property "Manufacturer" "Murata"
			(at 163.8 216 0)
			(layer "F.Fab")
			(hide yes)
			(effects
				(font
					(size 1 1)
					(thickness 0.15)
				)
			)
		)
		(property "Val" "100n"
			(at 163.8 216 0)
			(layer "F.Fab")
			(hide yes)
			(effects
				(font
					(size 1 1)
					(thickness 0.15)
				)
			)
		)
		(property "Voltage" "50V"
			(at 163.8 216 0)
			(layer "F.Fab")
			(hide yes)
			(effects
				(font
					(size 1 1)
					(thickness 0.15)
				)
			)
		)
		(sheetname "USB Debug, DP")
		(sheetfile "usb.kicad_sch")
		(attr smd)
		(fp_rect
			(start -0.925 -0.47)
			(end 0.925 0.47)
			(stroke
				(width 0.05)
				(type default)
			)
			(fill none)
			(layer "F.CrtYd")
		)
		(fp_line
			(start 0.504 0.248)
			(end -0.494 0.248)
			(stroke
				(width 0.15)
				(type solid)
			)
			(layer "F.Fab")
		)
		(fp_line
			(start 0.504 -0.25)
			(end 0.504 0.248)
			(stroke
				(width 0.15)
				(type solid)
			)
			(layer "F.Fab")
		)
		(fp_line
			(start -0.494 0.248)
			(end -0.494 -0.25)
			(stroke
				(width 0.15)
				(type solid)
			)
			(layer "F.Fab")
		)
		(fp_line
			(start -0.494 -0.25)
			(end 0.504 -0.25)
			(stroke
				(width 0.15)
				(type solid)
			)
			(layer "F.Fab")
		)
		(fp_text user "${REFERENCE}"
			(at -0.932 3.168 180)
			(layer "F.Fab")
			(hide yes)
			(effects
				(font
					(size 0.7 0.7)
					(thickness 0.15)
				)
				(justify left bottom)
			)
		)
		(fp_text user "License: Apache-2.0"
			(at -0.932 5.17 180)
			(layer "F.Fab")
			(hide yes)
			(effects
				(font
					(size 0.7 0.7)
					(thickness 0.15)
				)
				(justify left bottom)
			)
		)
		(fp_text user "Author: Antmicro"
			(at -0.932 4.17 180)
			(layer "F.Fab")
			(hide yes)
			(effects
				(font
					(size 0.7 0.7)
					(thickness 0.15)
				)
				(justify left bottom)
			)
		)
		(pad "1" smd roundrect
			(at -0.48 0 180)
			(size 0.59 0.64)
			(layers "F.Cu" "F.Paste" "F.Mask")
			(roundrect_rratio 0.25)
			(net 58 "USBSS0_RX_P")
			(pintype "passive")
		)
		(pad "2" smd roundrect
			(at 0.48 0 180)
			(size 0.59 0.64)
			(layers "F.Cu" "F.Paste" "F.Mask")
			(roundrect_rratio 0.25)
			(net 186 "/USB Debug, DP/USBSS0_RX_C_N")
			(pintype "passive")
		)
	)
	(footprint "antmicro-footprints:XDFN-2_1x0.60mm"
		(layer "F.Cu")
		(at 137.8 86.07 90)
		(property "Reference" "D41"
			(at -0.3 0.4 0)
			(layer "F.SilkS")
			(effects
				(font
					(size 0.7 0.7)
					(thickness 0.15)
				)
				(justify left bottom)
			)
		)
		(property "Value" "TPD1E0B04_XDFN-2"
			(at 0 1.5 90)
			(layer "F.Fab")
			(effects
				(font
					(size 0.7 0.7)
					(thickness 0.15)
				)
				(justify left bottom)
			)
		)
		(property "Footprint" "antmicro-footprints:XDFN-2_1x0.60mm"
			(at 0 0 90)
			(layer "F.Fab")
			(hide yes)
			(effects
				(font
					(size 1.27 1.27)
					(thickness 0.15)
				)
			)
		)
		(property "Datasheet" "https://www.ti.com/general/docs/suppproductinfo.tsp?distId=26&gotoUrl=https://www.ti.com/lit/gpn/tpd1e0b04"
			(at 0 0 90)
			(layer "F.Fab")
			(hide yes)
			(effects
				(font
					(size 1.27 1.27)
					(thickness 0.15)
				)
			)
		)
		(property "MPN" "TPD1E0B04DPYR"
			(at 223.87 -51.73 0)
			(layer "F.Fab")
			(hide yes)
			(effects
				(font
					(size 1 1)
					(thickness 0.15)
				)
			)
		)
		(property "Manufacturer" "Texas Instruments"
			(at 223.87 -51.73 0)
			(layer "F.Fab")
			(hide yes)
			(effects
				(font
					(size 1 1)
					(thickness 0.15)
				)
			)
		)
		(property "Author" "Antmicro"
			(at 223.87 -51.73 0)
			(layer "F.Fab")
			(hide yes)
			(effects
				(font
					(size 1 1)
					(thickness 0.15)
				)
			)
		)
		(property "License" "Apache-2.0"
			(at 223.87 -51.73 0)
			(layer "F.Fab")
			(hide yes)
			(effects
				(font
					(size 1 1)
					(thickness 0.15)
				)
			)
		)
		(sheetname "Peripherals")
		(sheetfile "peripherals.kicad_sch")
		(attr smd)
		(fp_rect
			(start -0.725 -0.475)
			(end 0.725 0.475)
			(stroke
				(width 0.05)
				(type solid)
			)
			(fill none)
			(layer "F.CrtYd")
		)
		(fp_rect
			(start -0.55 -0.35)
			(end 0.55 0.35)
			(stroke
				(width 0.15)
				(type solid)
			)
			(fill none)
			(layer "F.Fab")
		)
		(fp_text user "License: Apache-2.0"
			(at -0.8 5.6 90)
			(layer "F.Fab")
			(hide yes)
			(effects
				(font
					(size 0.7 0.7)
					(thickness 0.15)
				)
				(justify left bottom)
			)
		)
		(fp_text user "Author: Antmicro"
			(at -0.8 4.4 90)
			(layer "F.Fab")
			(hide yes)
			(effects
				(font
					(size 0.7 0.7)
					(thickness 0.15)
				)
				(justify left bottom)
			)
		)
		(fp_text user "${REFERENCE}"
			(at -0.8 3.2 90)
			(layer "F.Fab")
			(hide yes)
			(effects
				(font
					(size 0.7 0.7)
					(thickness 0.15)
				)
				(justify left bottom)
			)
		)
		(pad "1" smd roundrect
			(at -0.351 0 90)
			(size 0.3 0.5)
			(layers "F.Cu" "F.Paste" "F.Mask")
			(roundrect_rratio 0.25)
			(net 411 "/Peripherals/PCIE2_TX0_CONN_N")
			(pinfunction "C")
			(pintype "passive")
		)
		(pad "2" smd roundrect
			(at 0.349 0 90)
			(size 0.3 0.5)
			(layers "F.Cu" "F.Paste" "F.Mask")
			(roundrect_rratio 0.25)
			(net 1 "GND")
			(pinfunction "A")
			(pintype "passive")
		)
	)
	(footprint "antmicro-footprints:LED_0603_1608Metric_G"
		(layer "F.Cu")
		(at 129.1 101.95 -90)
		(descr "LED SMD 0603 Green")
		(tags "LED SMD 0603 Green")
		(property "Reference" "D51"
			(at -3.4 -0.4 90)
			(layer "F.SilkS")
			(effects
				(font
					(size 0.7 0.7)
					(thickness 0.15)
				)
				(justify right bottom)
			)
		)
		(property "Value" "LED_G_0603_LTST-C190GKT"
			(at -0.001 1.599 90)
			(layer "F.Fab")
			(effects
				(font
					(size 0.7 0.7)
					(thickness 0.15)
				)
				(justify right bottom)
			)
		)
		(property "Footprint" "antmicro-footprints:LED_0603_1608Metric_G"
			(at 0 0 -90)
			(layer "F.Fab")
			(hide yes)
			(effects
				(font
					(size 1.27 1.27)
					(thickness 0.15)
				)
			)
		)
		(property "Datasheet" "https://media.digikey.com/pdf/Data%20Sheets/Lite-On%20PDFs/LTST-C190GKT.pdf"
			(at 0 0 -90)
			(layer "F.Fab")
			(hide yes)
			(effects
				(font
					(size 1.27 1.27)
					(thickness 0.15)
				)
			)
		)
		(property "Author" "Antmicro"
			(at 27.15 231.05 0)
			(layer "F.Fab")
			(hide yes)
			(effects
				(font
					(size 1 1)
					(thickness 0.15)
				)
			)
		)
		(property "Color" "Green"
			(at 27.15 231.05 0)
			(layer "F.Fab")
			(hide yes)
			(effects
				(font
					(size 1 1)
					(thickness 0.15)
				)
			)
		)
		(property "License" "Apache-2.0"
			(at 27.15 231.05 0)
			(layer "F.Fab")
			(hide yes)
			(effects
				(font
					(size 1 1)
					(thickness 0.15)
				)
			)
		)
		(property "MPN" "LTST-C190GKT"
			(at 27.15 231.05 0)
			(layer "F.Fab")
			(hide yes)
			(effects
				(font
					(size 1 1)
					(thickness 0.15)
				)
			)
		)
		(property "Manufacturer" "Lite-On"
			(at 27.15 231.05 0)
			(layer "F.Fab")
			(hide yes)
			(effects
				(font
					(size 1 1)
					(thickness 0.15)
				)
			)
		)
		(sheetname "M.2")
		(sheetfile "m-2.kicad_sch")
		(attr smd)
		(fp_line
			(start 0.22 0.35)
			(end -0.22 0.35)
			(stroke
				(width 0.15)
				(type solid)
			)
			(layer "F.SilkS")
		)
		(fp_line
			(start -0.094672 0.201008)
			(end -0.094672 -0.198992)
			(stroke
				(width 0.1)
				(type solid)
			)
			(layer "F.SilkS")
		)
		(fp_line
			(start 0.105328 0.201008)
			(end -0.094672 0.001008)
			(stroke
				(width 0.1)
				(type solid)
			)
			(layer "F.SilkS")
		)
		(fp_line
			(start 0.105328 0.201008)
			(end 0.105328 -0.198992)
			(stroke
				(width 0.1)
				(type solid)
			)
			(layer "F.SilkS")
		)
		(fp_line
			(start -0.094672 0.001008)
			(end -0.24 0.001008)
			(stroke
				(width 0.1)
				(type solid)
			)
			(layer "F.SilkS")
		)
		(fp_line
			(start -0.094672 0.001008)
			(end 0.105328 -0.198992)
			(stroke
				(width 0.1)
				(type solid)
			)
			(layer "F.SilkS")
		)
		(fp_line
			(start 0.105328 0.001008)
			(end 0.24 0.001)
			(stroke
				(width 0.1)
				(type solid)
			)
			(layer "F.SilkS")
		)
		(fp_line
			(start -1.18 -0.319)
			(end -1.18 0.321)
			(stroke
				(width 0.15)
				(type solid)
			)
			(layer "F.SilkS")
		)
		(fp_line
			(start 0.22 -0.35)
			(end -0.22 -0.35)
			(stroke
				(width 0.15)
				(type solid)
			)
			(layer "F.SilkS")
		)
		(fp_rect
			(start 1.25 0.65)
			(end -1.25 -0.65)
			(stroke
				(width 0.05)
				(type solid)
			)
			(fill none)
			(layer "F.CrtYd")
		)
		(fp_line
			(start -0.199 0.2)
			(end -0.199 0.1)
			(stroke
				(width 0.15)
				(type solid)
			)
			(layer "F.Fab")
		)
		(fp_line
			(start 0.201 0.2)
			(end 0.201 0)
			(stroke
				(width 0.15)
				(type solid)
			)
			(layer "F.Fab")
		)
		(fp_line
			(start -0.199 0)
			(end -0.597 0)
			(stroke
				(width 0.15)
				(type solid)
			)
			(layer "F.Fab")
		)
		(fp_line
			(start -0.101 0)
			(end 0.201 0.2)
			(stroke
				(width 0.15)
				(type solid)
			)
			(layer "F.Fab")
		)
		(fp_line
			(start 0.201 0)
			(end 0.201 -0.202)
			(stroke
				(width 0.15)
				(type solid)
			)
			(layer "F.Fab")
		)
		(fp_line
			(start 0.599 0)
			(end 0.201 0)
			(stroke
				(width 0.15)
				(type solid)
			)
			(layer "F.Fab")
		)
		(fp_line
			(start -0.199 -0.202)
			(end -0.199 0.1)
			(stroke
				(width 0.15)
				(type solid)
			)
			(layer "F.Fab")
		)
		(fp_line
			(start 0.201 -0.202)
			(end -0.101 0)
			(stroke
				(width 0.15)
				(type solid)
			)
			(layer "F.Fab")
		)
		(fp_rect
			(start 0.848 0.4)
			(end -0.85 -0.402)
			(stroke
				(width 0.15)
				(type solid)
			)
			(fill none)
			(layer "F.Fab")
		)
		(fp_text user "${REFERENCE}"
			(at -1.4224 5.999 90)
			(layer "F.Fab")
			(hide yes)
			(effects
				(font
					(size 0.7 0.7)
					(thickness 0.15)
				)
				(justify right bottom)
			)
		)
		(fp_text user "Author: Antmicro"
			(at -1.4224 4.799 90)
			(layer "F.Fab")
			(hide yes)
			(effects
				(font
					(size 0.7 0.7)
					(thickness 0.15)
				)
				(justify right bottom)
			)
		)
		(fp_text user "License: Apache-2.0"
			(at -1.4224 3.599 90)
			(layer "F.Fab")
			(hide yes)
			(effects
				(font
					(size 0.7 0.7)
					(thickness 0.15)
				)
				(justify right bottom)
			)
		)
		(pad "1" smd roundrect
			(at -0.7 0 90)
			(size 0.8 1)
			(layers "F.Cu" "F.Paste" "F.Mask")
			(roundrect_rratio 0.2)
			(net 169 "/M.2/~{LED1}")
			(pinfunction "C")
			(pintype "passive")
		)
		(pad "2" smd roundrect
			(at 0.7 0 90)
			(size 0.8 1)
			(layers "F.Cu" "F.Paste" "F.Mask")
			(roundrect_rratio 0.2)
			(net 184 "Net-(D51-A)")
			(pinfunction "A")
			(pintype "passive")
		)
	)
	(footprint "antmicro-footprints:C_0603_1608Metric_EIA"
		(layer "F.Cu")
		(at 55.28 94.63 90)
		(descr "Capacitor SMD 0603, IPC-7351 Density Level A")
		(tags "Capacitor 0603")
		(property "Reference" "C103"
			(at -2.32 28.32 90)
			(layer "F.SilkS")
			(effects
				(font
					(size 0.7 0.7)
					(thickness 0.15)
				)
				(justify left bottom)
			)
		)
		(property "Value" "C_22u_16V_0603"
			(at -1.42757 1.770288 90)
			(layer "F.Fab")
			(effects
				(font
					(size 0.7 0.7)
					(thickness 0.15)
				)
				(justify left bottom)
			)
		)
		(property "Footprint" "antmicro-footprints:C_0603_1608Metric_EIA"
			(at 0 0 90)
			(layer "F.Fab")
			(hide yes)
			(effects
				(font
					(size 1.27 1.27)
					(thickness 0.15)
				)
			)
		)
		(property "Datasheet" "https://product.samsungsem.com/mlcc/CL10A226MO7JZN.do"
			(at 0 0 90)
			(layer "F.Fab")
			(hide yes)
			(effects
				(font
					(size 1.27 1.27)
					(thickness 0.15)
				)
			)
		)
		(property "Description" "SMD Multilayer Ceramic Capacitor"
			(at 0 0 90)
			(layer "F.Fab")
			(hide yes)
			(effects
				(font
					(size 1.27 1.27)
					(thickness 0.15)
				)
			)
		)
		(property "Manufacturer" "Samsung Electro-Mechanics"
			(at 0 0 90)
			(unlocked yes)
			(layer "F.Fab")
			(hide yes)
			(effects
				(font
					(size 1 1)
					(thickness 0.15)
				)
			)
		)
		(property "MPN" "CL10A226MO7JZNC"
			(at 0 0 90)
			(unlocked yes)
			(layer "F.Fab")
			(hide yes)
			(effects
				(font
					(size 1 1)
					(thickness 0.15)
				)
			)
		)
		(property "Val" "22u"
			(at 0 0 90)
			(unlocked yes)
			(layer "F.Fab")
			(hide yes)
			(effects
				(font
					(size 1 1)
					(thickness 0.15)
				)
			)
		)
		(property "License" "Apache-2.0"
			(at 0 0 90)
			(unlocked yes)
			(layer "F.Fab")
			(hide yes)
			(effects
				(font
					(size 1 1)
					(thickness 0.15)
				)
			)
		)
		(property "Author" "Antmicro"
			(at 0 0 90)
			(unlocked yes)
			(layer "F.Fab")
			(hide yes)
			(effects
				(font
					(size 1 1)
					(thickness 0.15)
				)
			)
		)
		(property "Voltage" "16V"
			(at 0 0 90)
			(unlocked yes)
			(layer "F.Fab")
			(hide yes)
			(effects
				(font
					(size 1 1)
					(thickness 0.15)
				)
			)
		)
		(property "Dielectric" ""
			(at 0 0 90)
			(unlocked yes)
			(layer "F.Fab")
			(hide yes)
			(effects
				(font
					(size 1 1)
					(thickness 0.15)
				)
			)
		)
		(sheetname "Supply")
		(sheetfile "supply.kicad_sch")
		(attr smd)
		(fp_line
			(start -0.15 -0.55)
			(end 0.15 -0.55)
			(stroke
				(width 0.15)
				(type solid)
			)
			(layer "F.SilkS")
		)
		(fp_line
			(start -0.15 0.55)
			(end 0.15 0.55)
			(stroke
				(width 0.15)
				(type solid)
			)
			(layer "F.SilkS")
		)
		(fp_rect
			(start -1.25 -0.65)
			(end 1.25 0.65)
			(stroke
				(width 0.05)
				(type solid)
			)
			(fill none)
			(layer "F.CrtYd")
		)
		(fp_rect
			(start -0.8 -0.45)
			(end 0.8 0.45)
			(stroke
				(width 0.15)
				(type solid)
			)
			(fill none)
			(layer "F.Fab")
		)
		(fp_text user "License: Apache-2.0"
			(at -1.682 5.895 90)
			(layer "F.Fab")
			(hide yes)
			(effects
				(font
					(size 0.7 0.7)
					(thickness 0.15)
				)
				(justify left bottom)
			)
		)
		(fp_text user "Author: Antmicro"
			(at -1.682 4.894 90)
			(layer "F.Fab")
			(hide yes)
			(effects
				(font
					(size 0.7 0.7)
					(thickness 0.15)
				)
				(justify left bottom)
			)
		)
		(fp_text user "${REFERENCE}"
			(at -1.682 3.895 90)
			(layer "F.Fab")
			(hide yes)
			(effects
				(font
					(size 0.7 0.7)
					(thickness 0.15)
				)
				(justify left bottom)
			)
		)
		(pad "1" smd roundrect
			(at -0.7 0 90)
			(size 0.8 1.1)
			(layers "F.Cu" "F.Paste" "F.Mask")
			(roundrect_rratio 0.2)
			(net 1 "GND")
			(pintype "passive")
		)
		(pad "2" smd roundrect
			(at 0.7 0 90)
			(size 0.8 1.1)
			(layers "F.Cu" "F.Paste" "F.Mask")
			(roundrect_rratio 0.2)
			(net 761 "/Supply/5V_OUT")
			(pintype "passive")
		)
	)
	(footprint "antmicro-footprints:C_0402_1005Metric"
		(layer "F.Cu")
		(at 140 113.485 -90)
		(descr "Capacitor SMD 0402")
		(tags "capacitor SMD 0402")
		(property "Reference" "C107"
			(at 1.365 0.475 -90)
			(layer "F.SilkS")
			(effects
				(font
					(size 0.7 0.7)
					(thickness 0.15)
				)
				(justify left bottom)
			)
		)
		(property "Value" "C_1u_0402"
			(at 0 1.4 -90)
			(layer "F.Fab")
			(effects
				(font
					(size 0.7 0.7)
					(thickness 0.15)
				)
				(justify left bottom)
			)
		)
		(property "Footprint" "antmicro-footprints:C_0402_1005Metric"
			(at 0 0 -90)
			(layer "F.Fab")
			(hide yes)
			(effects
				(font
					(size 1.27 1.27)
					(thickness 0.15)
				)
			)
		)
		(property "Datasheet" "https://product.tdk.com/en/search/capacitor/ceramic/mlcc/info?part_no=C1005X6S1A105K050BC"
			(at 0 0 -90)
			(layer "F.Fab")
			(hide yes)
			(effects
				(font
					(size 1.27 1.27)
					(thickness 0.15)
				)
			)
		)
		(property "Author" "Antmicro"
			(at 26.515 253.485 0)
			(layer "F.Fab")
			(hide yes)
			(effects
				(font
					(size 1 1)
					(thickness 0.15)
				)
			)
		)
		(property "Dielectric" ""
			(at 26.515 253.485 0)
			(layer "F.Fab")
			(hide yes)
			(effects
				(font
					(size 1 1)
					(thickness 0.15)
				)
			)
		)
		(property "License" "Apache-2.0"
			(at 26.515 253.485 0)
			(layer "F.Fab")
			(hide yes)
			(effects
				(font
					(size 1 1)
					(thickness 0.15)
				)
			)
		)
		(property "MPN" "C1005X6S1A105K050BC"
			(at 26.515 253.485 0)
			(layer "F.Fab")
			(hide yes)
			(effects
				(font
					(size 1 1)
					(thickness 0.15)
				)
			)
		)
		(property "Manufacturer" "TDK"
			(at 26.515 253.485 0)
			(layer "F.Fab")
			(hide yes)
			(effects
				(font
					(size 1 1)
					(thickness 0.15)
				)
			)
		)
		(property "Val" "1u"
			(at 26.515 253.485 0)
			(layer "F.Fab")
			(hide yes)
			(effects
				(font
					(size 1 1)
					(thickness 0.15)
				)
			)
		)
		(property "Voltage" ""
			(at 26.515 253.485 0)
			(layer "F.Fab")
			(hide yes)
			(effects
				(font
					(size 1 1)
					(thickness 0.15)
				)
			)
		)
		(sheetname "Peripherals")
		(sheetfile "peripherals.kicad_sch")
		(attr smd)
		(fp_rect
			(start -0.925 -0.47)
			(end 0.925 0.47)
			(stroke
				(width 0.05)
				(type default)
			)
			(fill none)
			(layer "F.CrtYd")
		)
		(fp_line
			(start -0.494 0.248)
			(end -0.494 -0.25)
			(stroke
				(width 0.15)
				(type solid)
			)
			(layer "F.Fab")
		)
		(fp_line
			(start 0.504 0.248)
			(end -0.494 0.248)
			(stroke
				(width 0.15)
				(type solid)
			)
			(layer "F.Fab")
		)
		(fp_line
			(start -0.494 -0.25)
			(end 0.504 -0.25)
			(stroke
				(width 0.15)
				(type solid)
			)
			(layer "F.Fab")
		)
		(fp_line
			(start 0.504 -0.25)
			(end 0.504 0.248)
			(stroke
				(width 0.15)
				(type solid)
			)
			(layer "F.Fab")
		)
		(fp_text user "License: Apache-2.0"
			(at -0.932 5.17 -90)
			(layer "F.Fab")
			(hide yes)
			(effects
				(font
					(size 0.7 0.7)
					(thickness 0.15)
				)
				(justify left bottom)
			)
		)
		(fp_text user "${REFERENCE}"
			(at -0.932 3.168 -90)
			(layer "F.Fab")
			(hide yes)
			(effects
				(font
					(size 0.7 0.7)
					(thickness 0.15)
				)
				(justify left bottom)
			)
		)
		(fp_text user "Author: Antmicro"
			(at -0.932 4.17 -90)
			(layer "F.Fab")
			(hide yes)
			(effects
				(font
					(size 0.7 0.7)
					(thickness 0.15)
				)
				(justify left bottom)
			)
		)
		(pad "1" smd roundrect
			(at -0.48 0 270)
			(size 0.59 0.64)
			(layers "F.Cu" "F.Paste" "F.Mask")
			(roundrect_rratio 0.25)
			(net 1 "GND")
			(pintype "passive")
		)
		(pad "2" smd roundrect
			(at 0.48 0 270)
			(size 0.59 0.64)
			(layers "F.Cu" "F.Paste" "F.Mask")
			(roundrect_rratio 0.25)
			(net 479 "/Peripherals/5V_CONN")
			(pintype "passive")
		)
	)
	(footprint "antmicro-footprints:XDFN-2_1x0.60mm"
		(layer "F.Cu")
		(at 147.45 86.9 90)
		(property "Reference" "D39"
			(at 6.29 -0.15 0)
			(layer "F.SilkS")
			(effects
				(font
					(size 0.7 0.7)
					(thickness 0.15)
				)
				(justify left bottom)
			)
		)
		(property "Value" "TPD1E0B04_XDFN-2"
			(at 0 1.5 90)
			(layer "F.Fab")
			(effects
				(font
					(size 0.7 0.7)
					(thickness 0.15)
				)
				(justify left bottom)
			)
		)
		(property "Footprint" "antmicro-footprints:XDFN-2_1x0.60mm"
			(at 0 0 90)
			(layer "F.Fab")
			(hide yes)
			(effects
				(font
					(size 1.27 1.27)
					(thickness 0.15)
				)
			)
		)
		(property "Datasheet" "https://www.ti.com/general/docs/suppproductinfo.tsp?distId=26&gotoUrl=https://www.ti.com/lit/gpn/tpd1e0b04"
			(at 0 0 90)
			(layer "F.Fab")
			(hide yes)
			(effects
				(font
					(size 1.27 1.27)
					(thickness 0.15)
				)
			)
		)
		(property "MPN" "TPD1E0B04DPYR"
			(at 234.35 -60.55 0)
			(layer "F.Fab")
			(hide yes)
			(effects
				(font
					(size 1 1)
					(thickness 0.15)
				)
			)
		)
		(property "Manufacturer" "Texas Instruments"
			(at 234.35 -60.55 0)
			(layer "F.Fab")
			(hide yes)
			(effects
				(font
					(size 1 1)
					(thickness 0.15)
				)
			)
		)
		(property "Author" "Antmicro"
			(at 234.35 -60.55 0)
			(layer "F.Fab")
			(hide yes)
			(effects
				(font
					(size 1 1)
					(thickness 0.15)
				)
			)
		)
		(property "License" "Apache-2.0"
			(at 234.35 -60.55 0)
			(layer "F.Fab")
			(hide yes)
			(effects
				(font
					(size 1 1)
					(thickness 0.15)
				)
			)
		)
		(sheetname "Peripherals")
		(sheetfile "peripherals.kicad_sch")
		(attr smd)
		(fp_rect
			(start -0.725 -0.475)
			(end 0.725 0.475)
			(stroke
				(width 0.05)
				(type solid)
			)
			(fill none)
			(layer "F.CrtYd")
		)
		(fp_rect
			(start -0.55 -0.35)
			(end 0.55 0.35)
			(stroke
				(width 0.15)
				(type solid)
			)
			(fill none)
			(layer "F.Fab")
		)
		(fp_text user "${REFERENCE}"
			(at -0.8 3.2 90)
			(layer "F.Fab")
			(hide yes)
			(effects
				(font
					(size 0.7 0.7)
					(thickness 0.15)
				)
				(justify left bottom)
			)
		)
		(fp_text user "License: Apache-2.0"
			(at -0.8 5.6 90)
			(layer "F.Fab")
			(hide yes)
			(effects
				(font
					(size 0.7 0.7)
					(thickness 0.15)
				)
				(justify left bottom)
			)
		)
		(fp_text user "Author: Antmicro"
			(at -0.8 4.4 90)
			(layer "F.Fab")
			(hide yes)
			(effects
				(font
					(size 0.7 0.7)
					(thickness 0.15)
				)
				(justify left bottom)
			)
		)
		(pad "1" smd roundrect
			(at -0.351 0 90)
			(size 0.3 0.5)
			(layers "F.Cu" "F.Paste" "F.Mask")
			(roundrect_rratio 0.25)
			(net 113 "PCIE2_RX0_N")
			(pinfunction "C")
			(pintype "passive")
		)
		(pad "2" smd roundrect
			(at 0.349 0 90)
			(size 0.3 0.5)
			(layers "F.Cu" "F.Paste" "F.Mask")
			(roundrect_rratio 0.25)
			(net 1 "GND")
			(pinfunction "A")
			(pintype "passive")
		)
	)
	(footprint "antmicro-footprints:R_Array_4x0201_Panasonic_EXB18V"
		(layer "F.Cu")
		(at 96.675 118.3)
		(property "Reference" "R35"
			(at -1.05 -0.725 180)
			(layer "F.SilkS")
			(effects
				(font
					(size 0.7 0.7)
					(thickness 0.15)
				)
				(justify left bottom)
			)
		)
		(property "Value" "R_4x0R_0201_array"
			(at -1.1 1.8 0)
			(layer "F.Fab")
			(effects
				(font
					(size 0.7 0.7)
					(thickness 0.15)
				)
				(justify left bottom)
			)
		)
		(property "Footprint" "antmicro-footprints:R_Array_4x0201_Panasonic_EXB18V"
			(at 0 0 0)
			(layer "F.Fab")
			(hide yes)
			(effects
				(font
					(size 1.27 1.27)
					(thickness 0.15)
				)
			)
		)
		(property "Datasheet" "http://industrial.panasonic.com/cdbs/www-data/pdf/AOC0000/AOC0000C14.pdf"
			(at 0 0 0)
			(layer "F.Fab")
			(hide yes)
			(effects
				(font
					(size 1.27 1.27)
					(thickness 0.15)
				)
			)
		)
		(property "Author" "Antmicro"
			(at 0 0 0)
			(layer "F.Fab")
			(hide yes)
			(effects
				(font
					(size 1 1)
					(thickness 0.15)
				)
			)
		)
		(property "License" "Apache-2.0"
			(at 0 0 0)
			(layer "F.Fab")
			(hide yes)
			(effects
				(font
					(size 1 1)
					(thickness 0.15)
				)
			)
		)
		(property "MPN" "EXB-18VR000X"
			(at 0 0 0)
			(layer "F.Fab")
			(hide yes)
			(effects
				(font
					(size 1 1)
					(thickness 0.15)
				)
			)
		)
		(property "Manufacturer" "Panasonic"
			(at 0 0 0)
			(layer "F.Fab")
			(hide yes)
			(effects
				(font
					(size 1 1)
					(thickness 0.15)
				)
			)
		)
		(property "Val" "4x0R_0201"
			(at 0 0 0)
			(layer "F.Fab")
			(hide yes)
			(effects
				(font
					(size 1 1)
					(thickness 0.15)
				)
			)
		)
		(sheetname "HDMI")
		(sheetfile "hdmi.kicad_sch")
		(attr smd)
		(fp_line
			(start -0.8 -0.45)
			(end -0.8 0.45)
			(stroke
				(width 0.12)
				(type solid)
			)
			(layer "F.SilkS")
		)
		(fp_line
			(start 0.8 -0.45)
			(end 0.8 0.45)
			(stroke
				(width 0.12)
				(type solid)
			)
			(layer "F.SilkS")
		)
		(fp_rect
			(start -0.898 -0.66)
			(end 0.898 0.65)
			(stroke
				(width 0.05)
				(type solid)
			)
			(fill none)
			(layer "F.CrtYd")
		)
		(fp_text user "${REFERENCE}"
			(at -1.051 3.2 0)
			(layer "F.Fab")
			(hide yes)
			(effects
				(font
					(size 0.7 0.7)
					(thickness 0.15)
				)
				(justify left bottom)
			)
		)
		(fp_text user "Author: Antmicro"
			(at -1.051 4.599 0)
			(layer "F.Fab")
			(hide yes)
			(effects
				(font
					(size 0.7 0.7)
					(thickness 0.15)
				)
				(justify left bottom)
			)
		)
		(fp_text user "License: Apache-2.0"
			(at -1.051 6 0)
			(layer "F.Fab")
			(hide yes)
			(effects
				(font
					(size 0.7 0.7)
					(thickness 0.15)
				)
				(justify left bottom)
			)
		)
		(pad "1" smd roundrect
			(at -0.6 0.298)
			(size 0.2 0.4)
			(layers "F.Cu" "F.Paste" "F.Mask")
			(roundrect_rratio 0.25)
			(net 525 "/HDMI/HDMI_D1_CONN_N")
			(pinfunction "R1.1")
			(pintype "passive")
		)
		(pad "2" smd roundrect
			(at -0.202 0.298)
			(size 0.2 0.4)
			(layers "F.Cu" "F.Paste" "F.Mask")
			(roundrect_rratio 0.25)
			(net 526 "/HDMI/HDMI_D1_CONN_P")
			(pinfunction "R2.1")
			(pintype "passive")
		)
		(pad "3" smd roundrect
			(at 0.2 0.298)
			(size 0.2 0.4)
			(layers "F.Cu" "F.Paste" "F.Mask")
			(roundrect_rratio 0.25)
			(net 527 "/HDMI/HDMI_D2_CONN_N")
			(pinfunction "R3.1")
			(pintype "passive")
		)
		(pad "4" smd roundrect
			(at 0.598 0.298)
			(size 0.2 0.4)
			(layers "F.Cu" "F.Paste" "F.Mask")
			(roundrect_rratio 0.25)
			(net 528 "/HDMI/HDMI_D2_CONN_P")
			(pinfunction "R4.1")
			(pintype "passive")
		)
		(pad "5" smd roundrect
			(at 0.598 -0.3)
			(size 0.2 0.4)
			(layers "F.Cu" "F.Paste" "F.Mask")
			(roundrect_rratio 0.25)
			(net 492 "/HDMI/HDMI_D2_P")
			(pinfunction "R4.2")
			(pintype "passive")
		)
		(pad "6" smd roundrect
			(at 0.2 -0.3)
			(size 0.2 0.4)
			(layers "F.Cu" "F.Paste" "F.Mask")
			(roundrect_rratio 0.25)
			(net 486 "/HDMI/HDMI_D2_N")
			(pinfunction "R3.2")
			(pintype "passive")
		)
		(pad "7" smd roundrect
			(at -0.202 -0.3)
			(size 0.2 0.4)
			(layers "F.Cu" "F.Paste" "F.Mask")
			(roundrect_rratio 0.25)
			(net 493 "/HDMI/HDMI_D1_P")
			(pinfunction "R2.2")
			(pintype "passive")
		)
		(pad "8" smd roundrect
			(at -0.6 -0.3)
			(size 0.2 0.4)
			(layers "F.Cu" "F.Paste" "F.Mask")
			(roundrect_rratio 0.25)
			(net 487 "/HDMI/HDMI_D1_N")
			(pinfunction "R1.2")
			(pintype "passive")
		)
	)
	(footprint "antmicro-footprints:TSOT23-6"
		(layer "F.Cu")
		(at 102.35 119.25 90)
		(property "Reference" "U18"
			(at 1.4 -2.75 90)
			(layer "F.SilkS")
			(effects
				(font
					(size 0.7 0.7)
					(thickness 0.15)
				)
				(justify left bottom)
			)
		)
		(property "Value" "AP22615A_TSOT26"
			(at 0 2.6 90)
			(layer "F.Fab")
			(effects
				(font
					(size 0.7 0.7)
					(thickness 0.15)
				)
				(justify left bottom)
			)
		)
		(property "Footprint" "antmicro-footprints:TSOT23-6"
			(at 0 0 90)
			(layer "F.Fab")
			(hide yes)
			(effects
				(font
					(size 1.27 1.27)
					(thickness 0.15)
				)
			)
		)
		(property "Datasheet" "https://www.mouser.com/datasheet/2/115/DIOD_S_A0008958405_1-2543193.pdf"
			(at 0 0 90)
			(layer "F.Fab")
			(hide yes)
			(effects
				(font
					(size 1.27 1.27)
					(thickness 0.15)
				)
			)
		)
		(property "Author" "Antmicro"
			(at 221.6 16.9 0)
			(layer "F.Fab")
			(hide yes)
			(effects
				(font
					(size 1 1)
					(thickness 0.15)
				)
			)
		)
		(property "License" "Apache-2.0"
			(at 221.6 16.9 0)
			(layer "F.Fab")
			(hide yes)
			(effects
				(font
					(size 1 1)
					(thickness 0.15)
				)
			)
		)
		(property "MPN" "AP22615AWU-7"
			(at 221.6 16.9 0)
			(layer "F.Fab")
			(hide yes)
			(effects
				(font
					(size 1 1)
					(thickness 0.15)
				)
			)
		)
		(property "Manufacturer" "Diodes Incorporated"
			(at 221.6 16.9 0)
			(layer "F.Fab")
			(hide yes)
			(effects
				(font
					(size 1 1)
					(thickness 0.15)
				)
			)
		)
		(sheetname "USB3")
		(sheetfile "usb3.kicad_sch")
		(attr smd)
		(fp_line
			(start -1 -1.5)
			(end -1 -1.375)
			(stroke
				(width 0.15)
				(type solid)
			)
			(layer "F.SilkS")
		)
		(fp_line
			(start 1 -1.497)
			(end -1 -1.5)
			(stroke
				(width 0.15)
				(type solid)
			)
			(layer "F.SilkS")
		)
		(fp_line
			(start 1 -1.497)
			(end 1 -1.375)
			(stroke
				(width 0.15)
				(type solid)
			)
			(layer "F.SilkS")
		)
		(fp_line
			(start 1 1.55)
			(end 1 1.4)
			(stroke
				(width 0.15)
				(type solid)
			)
			(layer "F.SilkS")
		)
		(fp_line
			(start 1 1.55)
			(end -1 1.55)
			(stroke
				(width 0.15)
				(type solid)
			)
			(layer "F.SilkS")
		)
		(fp_line
			(start -1 1.55)
			(end -1 1.4)
			(stroke
				(width 0.15)
				(type solid)
			)
			(layer "F.SilkS")
		)
		(fp_circle
			(center -1.44 -1.5)
			(end -1.39 -1.5)
			(stroke
				(width 0.15)
				(type solid)
			)
			(fill solid)
			(layer "F.SilkS")
		)
		(fp_rect
			(start 1.93 -1.7)
			(end -1.93 1.7)
			(stroke
				(width 0.05)
				(type solid)
			)
			(fill none)
			(layer "F.CrtYd")
		)
		(fp_line
			(start -0.45 -1.521)
			(end -0.876 -1.096)
			(stroke
				(width 0.15)
				(type solid)
			)
			(layer "F.Fab")
		)
		(fp_rect
			(start 0.875 1.528)
			(end -0.875 -1.525)
			(stroke
				(width 0.15)
				(type solid)
			)
			(fill none)
			(layer "F.Fab")
		)
		(fp_text user "${REFERENCE}"
			(at -1.93 3.8 90)
			(layer "F.Fab")
			(hide yes)
			(effects
				(font
					(size 0.7 0.7)
					(thickness 0.15)
				)
				(justify left bottom)
			)
		)
		(fp_text user "Author: Antmicro"
			(at -1.93 5 90)
			(layer "F.Fab")
			(hide yes)
			(effects
				(font
					(size 0.7 0.7)
					(thickness 0.15)
				)
				(justify left bottom)
			)
		)
		(fp_text user "License: Apache-2.0"
			(at -1.93 6.199 90)
			(layer "F.Fab")
			(hide yes)
			(effects
				(font
					(size 0.7 0.7)
					(thickness 0.15)
				)
				(justify left bottom)
			)
		)
		(pad "1" smd rect
			(at -1.301 -0.947)
			(size 0.7 1.2)
			(layers "F.Cu" "F.Paste" "F.Mask")
			(net 270 "/USB3/USBC1_VBUS")
			(pinfunction "OUT")
			(pintype "power_out")
		)
		(pad "2" smd rect
			(at -1.301 0.004)
			(size 0.7 1.2)
			(layers "F.Cu" "F.Paste" "F.Mask")
			(net 1 "GND")
			(pinfunction "GND")
			(pintype "power_in")
		)
		(pad "3" smd rect
			(at -1.301 0.954)
			(size 0.7 1.2)
			(layers "F.Cu" "F.Paste" "F.Mask")
			(net 508 "USBC1_FLG")
			(pinfunction "FLG")
			(pintype "output")
		)
		(pad "4" smd rect
			(at 1.299 0.954)
			(size 0.7 1.2)
			(layers "F.Cu" "F.Paste" "F.Mask")
			(net 625 "Net-(Q4-D)")
			(pinfunction "EN")
			(pintype "input")
		)
		(pad "5" smd rect
			(at 1.299 0.004)
			(size 0.7 1.2)
			(layers "F.Cu" "F.Paste" "F.Mask")
			(net 564 "/USB3/USBC1_ISET")
			(pinfunction "ISET")
			(pintype "passive")
		)
		(pad "6" smd rect
			(at 1.299 -0.947)
			(size 0.7 1.2)
			(layers "F.Cu" "F.Paste" "F.Mask")
			(net 99 "+5V")
			(pinfunction "IN")
			(pintype "power_in")
		)
	)
	(footprint "antmicro-footprints:R_0402_1005Metric"
		(layer "F.Cu")
		(at 61.6 107)
		(descr "Resistor SMD 0402")
		(tags "resistor SMD 0402")
		(property "Reference" "R78"
			(at 0.75 0.45 0)
			(layer "F.SilkS")
			(effects
				(font
					(size 0.7 0.7)
					(thickness 0.15)
				)
				(justify left bottom)
			)
		)
		(property "Value" "R_2k2_0402"
			(at 0 1.4 0)
			(layer "F.Fab")
			(effects
				(font
					(size 0.7 0.7)
					(thickness 0.15)
				)
				(justify left bottom)
			)
		)
		(property "Footprint" "antmicro-footprints:R_0402_1005Metric"
			(at 0 0 0)
			(layer "F.Fab")
			(hide yes)
			(effects
				(font
					(size 1.27 1.27)
					(thickness 0.15)
				)
			)
		)
		(property "Datasheet" "https://www.bourns.com/docs/product-datasheets/cr.pdf"
			(at 0 0 0)
			(layer "F.Fab")
			(hide yes)
			(effects
				(font
					(size 1.27 1.27)
					(thickness 0.15)
				)
			)
		)
		(property "Author" "Antmicro"
			(at 0 0 0)
			(layer "F.Fab")
			(hide yes)
			(effects
				(font
					(size 1 1)
					(thickness 0.15)
				)
			)
		)
		(property "License" "Apache-2.0"
			(at 0 0 0)
			(layer "F.Fab")
			(hide yes)
			(effects
				(font
					(size 1 1)
					(thickness 0.15)
				)
			)
		)
		(property "MPN" "CR0402-FX-2201GLF"
			(at 0 0 0)
			(layer "F.Fab")
			(hide yes)
			(effects
				(font
					(size 1 1)
					(thickness 0.15)
				)
			)
		)
		(property "Manufacturer" "Bourns"
			(at 0 0 0)
			(layer "F.Fab")
			(hide yes)
			(effects
				(font
					(size 1 1)
					(thickness 0.15)
				)
			)
		)
		(property "Tolerance" "1%"
			(at 0 0 0)
			(layer "F.Fab")
			(hide yes)
			(effects
				(font
					(size 1 1)
					(thickness 0.15)
				)
			)
		)
		(property "Val" "2k2"
			(at 0 0 0)
			(layer "F.Fab")
			(hide yes)
			(effects
				(font
					(size 1 1)
					(thickness 0.15)
				)
			)
		)
		(sheetname "USB Debug, DP")
		(sheetfile "usb.kicad_sch")
		(attr smd)
		(fp_rect
			(start -0.925 -0.47)
			(end 0.925 0.47)
			(stroke
				(width 0.05)
				(type default)
			)
			(fill none)
			(layer "F.CrtYd")
		)
		(fp_rect
			(start -0.5 -0.25)
			(end 0.5 0.25)
			(stroke
				(width 0.15)
				(type solid)
			)
			(fill none)
			(layer "F.Fab")
		)
		(fp_text user "License: Apache-2.0"
			(at -0.95 5.169 0)
			(layer "F.Fab")
			(hide yes)
			(effects
				(font
					(size 0.7 0.7)
					(thickness 0.15)
				)
				(justify left bottom)
			)
		)
		(fp_text user "${REFERENCE}"
			(at -0.95 3.168 0)
			(layer "F.Fab")
			(hide yes)
			(effects
				(font
					(size 0.7 0.7)
					(thickness 0.15)
				)
				(justify left bottom)
			)
		)
		(fp_text user "Author: Antmicro"
			(at -0.95 4.169 0)
			(layer "F.Fab")
			(hide yes)
			(effects
				(font
					(size 0.7 0.7)
					(thickness 0.15)
				)
				(justify left bottom)
			)
		)
		(pad "1" smd roundrect
			(at -0.48 0)
			(size 0.59 0.64)
			(layers "F.Cu" "F.Paste" "F.Mask")
			(roundrect_rratio 0.25)
			(net 1 "GND")
			(pintype "passive")
		)
		(pad "2" smd roundrect
			(at 0.48 0)
			(size 0.59 0.64)
			(layers "F.Cu" "F.Paste" "F.Mask")
			(roundrect_rratio 0.25)
			(net 672 "Net-(U9-ISET)")
			(pintype "passive")
		)
	)
	(footprint "antmicro-footprints:R_0603_1608Metric"
		(layer "F.Cu")
		(at 59.09 91.2 -90)
		(descr "Resistor SMD 0603")
		(tags "resistor SMD 0603")
		(property "Reference" "R182"
			(at -0.8 -28.389999 90)
			(layer "F.SilkS")
			(effects
				(font
					(size 0.7 0.7)
					(thickness 0.15)
				)
				(justify right bottom)
			)
		)
		(property "Value" "R_0R_22.4A_0603"
			(at 0 1.6 90)
			(layer "F.Fab")
			(effects
				(font
					(size 0.7 0.7)
					(thickness 0.15)
				)
				(justify right bottom)
			)
		)
		(property "Footprint" "antmicro-footprints:R_0603_1608Metric"
			(at 0 0 90)
			(layer "F.Fab")
			(hide yes)
			(effects
				(font
					(size 1.27 1.27)
					(thickness 0.15)
				)
			)
		)
		(property "Datasheet" "https://fscdn.rohm.com/en/products/databook/datasheet/passive/resistor/chip_resistor/pmr-jpw-e.pdf"
			(at 0 0 90)
			(layer "F.Fab")
			(hide yes)
			(effects
				(font
					(size 1.27 1.27)
					(thickness 0.15)
				)
			)
		)
		(property "Author" "Antmicro"
			(at -34.77 148.11 0)
			(layer "F.Fab")
			(hide yes)
			(effects
				(font
					(size 1 1)
					(thickness 0.15)
				)
			)
		)
		(property "License" "Apache-2.0"
			(at -34.77 148.11 0)
			(layer "F.Fab")
			(hide yes)
			(effects
				(font
					(size 1 1)
					(thickness 0.15)
				)
			)
		)
		(property "MPN" "PMR03EZPJ000"
			(at -34.77 148.11 0)
			(layer "F.Fab")
			(hide yes)
			(effects
				(font
					(size 1 1)
					(thickness 0.15)
				)
			)
		)
		(property "Manufacturer" "ROHM Semiconductor"
			(at -34.77 148.11 0)
			(layer "F.Fab")
			(hide yes)
			(effects
				(font
					(size 1 1)
					(thickness 0.15)
				)
			)
		)
		(property "Max. Curr." "22.4A"
			(at -34.77 148.11 0)
			(layer "F.Fab")
			(hide yes)
			(effects
				(font
					(size 1 1)
					(thickness 0.15)
				)
			)
		)
		(property "Tolerance" "template_tolerance"
			(at -34.77 148.11 0)
			(layer "F.Fab")
			(hide yes)
			(effects
				(font
					(size 1 1)
					(thickness 0.15)
				)
			)
		)
		(property "Val" "0R"
			(at -34.77 148.11 0)
			(layer "F.Fab")
			(hide yes)
			(effects
				(font
					(size 1 1)
					(thickness 0.15)
				)
			)
		)
		(sheetname "Supply")
		(sheetfile "supply.kicad_sch")
		(attr smd exclude_from_pos_files exclude_from_bom dnp)
		(fp_line
			(start -0.15 0.4)
			(end 0.15 0.4)
			(stroke
				(width 0.15)
				(type solid)
			)
			(layer "F.SilkS")
		)
		(fp_line
			(start -0.15 -0.4)
			(end 0.15 -0.4)
			(stroke
				(width 0.15)
				(type solid)
			)
			(layer "F.SilkS")
		)
		(fp_rect
			(start -1.25 -0.65)
			(end 1.25 0.65)
			(stroke
				(width 0.05)
				(type solid)
			)
			(fill none)
			(layer "F.CrtYd")
		)
		(fp_rect
			(start -0.8 -0.4)
			(end 0.8 0.4)
			(stroke
				(width 0.15)
				(type solid)
			)
			(fill none)
			(layer "F.Fab")
		)
		(fp_text user "${REFERENCE}"
			(at -1.25 3.898 90)
			(layer "F.Fab")
			(hide yes)
			(effects
				(font
					(size 0.7 0.7)
					(thickness 0.15)
				)
				(justify right bottom)
			)
		)
		(fp_text user "Author: Antmicro"
			(at -1.25 4.9 90)
			(layer "F.Fab")
			(hide yes)
			(effects
				(font
					(size 0.7 0.7)
					(thickness 0.15)
				)
				(justify right bottom)
			)
		)
		(fp_text user "License: Apache-2.0"
			(at -1.25 5.9 90)
			(layer "F.Fab")
			(hide yes)
			(effects
				(font
					(size 0.7 0.7)
					(thickness 0.15)
				)
				(justify right bottom)
			)
		)
		(pad "1" smd roundrect
			(at -0.7 0 270)
			(size 0.8 1)
			(layers "F.Cu" "F.Paste" "F.Mask")
			(roundrect_rratio 0.2)
			(net 787 "+5V_SoM")
			(pintype "passive")
		)
		(pad "2" smd roundrect
			(at 0.7 0 270)
			(size 0.8 1)
			(layers "F.Cu" "F.Paste" "F.Mask")
			(roundrect_rratio 0.2)
			(net 99 "+5V")
			(pintype "passive")
		)
	)
	(footprint "antmicro-footprints:SOD-923"
		(layer "F.Cu")
		(at 68.9 87.925 90)
		(property "Reference" "D33"
			(at -2.775 0.49 90)
			(unlocked yes)
			(layer "F.SilkS")
			(effects
				(font
					(size 0.7 0.7)
					(thickness 0.15)
				)
				(justify left bottom)
			)
		)
		(property "Value" "ESD9X5.0ST5G"
			(at 0 1.3 90)
			(unlocked yes)
			(layer "F.Fab")
			(effects
				(font
					(size 0.7 0.7)
					(thickness 0.15)
				)
				(justify left bottom)
			)
		)
		(property "Footprint" "antmicro-footprints:SOD-923"
			(at 0 0 90)
			(layer "F.Fab")
			(hide yes)
			(effects
				(font
					(size 1.27 1.27)
					(thickness 0.15)
				)
			)
		)
		(property "Datasheet" "https://www.onsemi.com/pdf/datasheet/esd9x3.3st5g-d.pdf"
			(at 0 0 90)
			(layer "F.Fab")
			(hide yes)
			(effects
				(font
					(size 1.27 1.27)
					(thickness 0.15)
				)
			)
		)
		(property "Author" "Antmicro"
			(at 0 0 90)
			(layer "F.Fab")
			(hide yes)
			(effects
				(font
					(size 1 1)
					(thickness 0.15)
				)
			)
		)
		(property "License" "Apache-2.0"
			(at 0 0 90)
			(layer "F.Fab")
			(hide yes)
			(effects
				(font
					(size 1 1)
					(thickness 0.15)
				)
			)
		)
		(property "MPN" "ESD9X5.0ST5G"
			(at 0 0 90)
			(layer "F.Fab")
			(hide yes)
			(effects
				(font
					(size 1 1)
					(thickness 0.15)
				)
			)
		)
		(property "Manufacturer" "ON Semiconductor"
			(at 0 0 90)
			(layer "F.Fab")
			(hide yes)
			(effects
				(font
					(size 1 1)
					(thickness 0.15)
				)
			)
		)
		(sheetname "Supply")
		(sheetfile "supply.kicad_sch")
		(attr smd)
		(fp_line
			(start 0.5 -0.4)
			(end 0.5 -0.3)
			(stroke
				(width 0.15)
				(type solid)
			)
			(layer "F.SilkS")
		)
		(fp_line
			(start -0.16 -0.4)
			(end -0.16 0.4)
			(stroke
				(width 0.15)
				(type solid)
			)
			(layer "F.SilkS")
		)
		(fp_line
			(start -0.5 -0.4)
			(end 0.5 -0.4)
			(stroke
				(width 0.15)
				(type solid)
			)
			(layer "F.SilkS")
		)
		(fp_line
			(start -0.5 -0.3)
			(end -0.5 -0.4)
			(stroke
				(width 0.15)
				(type solid)
			)
			(layer "F.SilkS")
		)
		(fp_line
			(start 0.5 0.4)
			(end 0.5 0.3)
			(stroke
				(width 0.15)
				(type solid)
			)
			(layer "F.SilkS")
		)
		(fp_line
			(start -0.5 0.4)
			(end -0.5 0.3)
			(stroke
				(width 0.15)
				(type solid)
			)
			(layer "F.SilkS")
		)
		(fp_line
			(start -0.5 0.4)
			(end 0.5 0.4)
			(stroke
				(width 0.15)
				(type solid)
			)
			(layer "F.SilkS")
		)
		(fp_rect
			(start -0.68 -0.41)
			(end 0.68 0.41)
			(stroke
				(width 0.05)
				(type solid)
			)
			(fill none)
			(layer "F.CrtYd")
		)
		(fp_line
			(start -0.202 -0.3)
			(end -0.202 0.298)
			(stroke
				(width 0.15)
				(type solid)
			)
			(layer "F.Fab")
		)
		(fp_rect
			(start -0.402 -0.3)
			(end 0.4 0.298)
			(stroke
				(width 0.15)
				(type solid)
			)
			(fill none)
			(layer "F.Fab")
		)
		(fp_text user "Author: Antmicro"
			(at -0.68 5.7 90)
			(layer "F.Fab")
			(hide yes)
			(effects
				(font
					(size 0.7 0.7)
					(thickness 0.15)
				)
				(justify left bottom)
			)
		)
		(fp_text user "License: Apache-2.0"
			(at -0.68 4.5 90)
			(layer "F.Fab")
			(hide yes)
			(effects
				(font
					(size 0.7 0.7)
					(thickness 0.15)
				)
				(justify left bottom)
			)
		)
		(fp_text user "${REFERENCE}"
			(at -0.68 3.3 90)
			(unlocked yes)
			(layer "F.Fab")
			(hide yes)
			(effects
				(font
					(size 0.7 0.7)
					(thickness 0.15)
				)
				(justify left bottom)
			)
		)
		(pad "1" smd roundrect
			(at -0.438 0 90)
			(size 0.4 0.325)
			(layers "F.Cu" "F.Paste" "F.Mask")
			(roundrect_rratio 0.25)
			(net 87 "+3V3")
			(pinfunction "C")
			(pintype "passive")
		)
		(pad "2" smd roundrect
			(at 0.436 0 90)
			(size 0.4 0.325)
			(layers "F.Cu" "F.Paste" "F.Mask")
			(roundrect_rratio 0.25)
			(net 1 "GND")
			(pinfunction "A")
			(pintype "passive")
		)
	)
	(footprint "antmicro-footprints:RJ45_X-2337992-8_Horizontal"
		(layer "F.Cu")
		(at 33.435 108.616397)
		(property "Reference" "J6"
			(at 14.965 1.583603 90)
			(layer "F.SilkS")
			(effects
				(font
					(size 0.7 0.7)
					(thickness 0.15)
				)
				(justify left bottom)
			)
		)
		(property "Value" "Bus_RJ45_5-2337992-8"
			(at -2.6 22 0)
			(layer "F.Fab")
			(effects
				(font
					(size 0.7 0.7)
					(thickness 0.15)
				)
				(justify left bottom)
			)
		)
		(property "Footprint" "antmicro-footprints:RJ45_X-2337992-8_Horizontal"
			(at 0 0 0)
			(layer "F.Fab")
			(hide yes)
			(effects
				(font
					(size 1.27 1.27)
					(thickness 0.15)
				)
			)
		)
		(property "Datasheet" "https://www.te.com/commerce/DocumentDelivery/DDEController?Action=showdoc&DocId=Customer+Drawing%7F5-2337992-8%7FA%7Fpdf%7FEnglish%7FENG_CD_5-2337992-8_A.pdf%7F5-2337992-8"
			(at 0 0 0)
			(layer "F.Fab")
			(hide yes)
			(effects
				(font
					(size 1.27 1.27)
					(thickness 0.15)
				)
			)
		)
		(property "Author" "Antmicro"
			(at 0 0 0)
			(layer "F.Fab")
			(hide yes)
			(effects
				(font
					(size 1 1)
					(thickness 0.15)
				)
			)
		)
		(property "License" "Apache-2.0"
			(at 0 0 0)
			(layer "F.Fab")
			(hide yes)
			(effects
				(font
					(size 1 1)
					(thickness 0.15)
				)
			)
		)
		(property "MPN" "5-2337992-8"
			(at 0 0 0)
			(layer "F.Fab")
			(hide yes)
			(effects
				(font
					(size 1 1)
					(thickness 0.15)
				)
			)
		)
		(property "Manufacturer" "TE Connectivity"
			(at 0 0 0)
			(layer "F.Fab")
			(hide yes)
			(effects
				(font
					(size 1 1)
					(thickness 0.15)
				)
			)
		)
		(property ki_fp_filters "CONN18_5-2337992-8_TEC")
		(sheetname "Ethernet")
		(sheetfile "ethernet.kicad_sch")
		(attr through_hole)
		(fp_line
			(start -2.363 -1.845)
			(end -2.363 4.48)
			(stroke
				(width 0.15)
				(type solid)
			)
			(layer "F.SilkS")
		)
		(fp_line
			(start -2.363 7.217)
			(end -2.363 19.771)
			(stroke
				(width 0.15)
				(type solid)
			)
			(layer "F.SilkS")
		)
		(fp_line
			(start -2.363 19.771)
			(end 13.791 19.771)
			(stroke
				(width 0.15)
				(type solid)
			)
			(layer "F.SilkS")
		)
		(fp_line
			(start 13.791 -1.845)
			(end -2.363 -1.845)
			(stroke
				(width 0.15)
				(type solid)
			)
			(layer "F.SilkS")
		)
		(fp_line
			(start 13.791 4.48)
			(end 13.791 -1.845)
			(stroke
				(width 0.15)
				(type solid)
			)
			(layer "F.SilkS")
		)
		(fp_line
			(start 13.791 19.771)
			(end 13.791 7.217)
			(stroke
				(width 0.15)
				(type solid)
			)
			(layer "F.SilkS")
		)
		(fp_rect
			(start -2.4 -1.8)
			(end 13.9 19.999)
			(stroke
				(width 0.05)
				(type solid)
			)
			(fill none)
			(layer "F.CrtYd")
		)
		(fp_line
			(start -2.237 -1.718)
			(end -2.237 19.644)
			(stroke
				(width 0.15)
				(type solid)
			)
			(layer "F.Fab")
		)
		(fp_line
			(start -2.237 19.644)
			(end 13.665 19.644)
			(stroke
				(width 0.15)
				(type solid)
			)
			(layer "F.Fab")
		)
		(fp_line
			(start 13.665 -1.718)
			(end -2.237 -1.718)
			(stroke
				(width 0.15)
				(type solid)
			)
			(layer "F.Fab")
		)
		(fp_line
			(start 13.665 19.644)
			(end 13.665 -1.718)
			(stroke
				(width 0.15)
				(type solid)
			)
			(layer "F.Fab")
		)
		(fp_text user "Author: Antmicro"
			(at -2.644 24.8 0)
			(layer "F.Fab")
			(hide yes)
			(effects
				(font
					(size 0.7 0.7)
					(thickness 0.15)
				)
				(justify left bottom)
			)
		)
		(fp_text user "${REFERENCE}"
			(at -2.644 23.4 0)
			(layer "F.Fab")
			(hide yes)
			(effects
				(font
					(size 0.7 0.7)
					(thickness 0.15)
				)
				(justify left bottom)
			)
		)
		(fp_text user "License: Apache-2.0"
			(at -2.644 26.2 0)
			(layer "F.Fab")
			(hide yes)
			(effects
				(font
					(size 0.7 0.7)
					(thickness 0.15)
				)
				(justify left bottom)
			)
		)
		(pad "" np_thru_hole circle
			(at 0 8.9)
			(size 3.25 3.25)
			(drill 3.25)
			(layers "*.Cu" "*.Mask")
		)
		(pad "" np_thru_hole circle
			(at 11.429 8.9)
			(size 3.25 3.25)
			(drill 3.25)
			(layers "*.Cu" "*.Mask")
		)
		(pad "1" thru_hole circle
			(at 0 0)
			(size 1.397 1.397)
			(drill 0.889)
			(layers "*.Cu" "*.Mask")
			(remove_unused_layers no)
			(net 67 "GBE_MDI0_P")
			(pinfunction "P1")
			(pintype "bidirectional")
		)
		(pad "2" thru_hole circle
			(at 1.269 2.539)
			(size 1.397 1.397)
			(drill 0.889)
			(layers "*.Cu" "*.Mask")
			(remove_unused_layers no)
			(net 66 "GBE_MDI0_N")
			(pinfunction "P2")
			(pintype "bidirectional")
		)
		(pad "3" thru_hole circle
			(at 2.539 0)
			(size 1.397 1.397)
			(drill 0.889)
			(layers "*.Cu" "*.Mask")
			(remove_unused_layers no)
			(net 69 "GBE_MDI1_P")
			(pinfunction "P3")
			(pintype "bidirectional")
		)
		(pad "4" thru_hole circle
			(at 3.809 2.539)
			(size 1.397 1.397)
			(drill 0.889)
			(layers "*.Cu" "*.Mask")
			(remove_unused_layers no)
			(net 136 "Net-(J6-P4)")
			(pinfunction "P4")
			(pintype "bidirectional")
		)
		(pad "5" thru_hole circle
			(at 5.078 0)
			(size 1.397 1.397)
			(drill 0.889)
			(layers "*.Cu" "*.Mask")
			(remove_unused_layers no)
			(net 136 "Net-(J6-P4)")
			(pinfunction "P5")
			(pintype "bidirectional")
		)
		(pad "6" thru_hole circle
			(at 6.349 2.539)
			(size 1.397 1.397)
			(drill 0.889)
			(layers "*.Cu" "*.Mask")
			(remove_unused_layers no)
			(net 68 "GBE_MDI1_N")
			(pinfunction "P6")
			(pintype "bidirectional")
		)
		(pad "7" thru_hole circle
			(at 7.618 0)
			(size 1.397 1.397)
			(drill 0.889)
			(layers "*.Cu" "*.Mask")
			(remove_unused_layers no)
			(net 74 "GBE_MDI2_P")
			(pinfunction "P7")
			(pintype "bidirectional")
		)
		(pad "8" thru_hole circle
			(at 8.89 2.539)
			(size 1.397 1.397)
			(drill 0.889)
			(layers "*.Cu" "*.Mask")
			(remove_unused_layers no)
			(net 72 "GBE_MDI2_N")
			(pinfunction "P8")
			(pintype "bidirectional")
		)
		(pad "9" thru_hole circle
			(at 10.159 0)
			(size 1.397 1.397)
			(drill 0.889)
			(layers "*.Cu" "*.Mask")
			(remove_unused_layers no)
			(net 77 "GBE_MDI3_P")
			(pinfunction "P9")
			(pintype "bidirectional")
		)
		(pad "10" thru_hole circle
			(at 11.429 2.539)
			(size 1.397 1.397)
			(drill 0.889)
			(layers "*.Cu" "*.Mask")
			(remove_unused_layers no)
			(net 76 "GBE_MDI3_N")
			(pinfunction "P10")
			(pintype "bidirectional")
		)
		(pad "11" thru_hole circle
			(at 0 5.078)
			(size 1.397 1.397)
			(drill 0.889)
			(layers "*.Cu" "*.Mask")
			(remove_unused_layers no)
			(net 121 "/Ethernet/PAIR_12")
			(pinfunction "VC1")
			(pintype "bidirectional")
		)
		(pad "12" thru_hole circle
			(at 2.539 6.339)
			(size 1.397 1.397)
			(drill 0.889)
			(layers "*.Cu" "*.Mask")
			(remove_unused_layers no)
			(net 122 "/Ethernet/PAIR_36")
			(pinfunction "VC2")
			(pintype "bidirectional")
		)
		(pad "13" thru_hole circle
			(at 8.89 6.339)
			(size 1.397 1.397)
			(drill 0.889)
			(layers "*.Cu" "*.Mask")
			(remove_unused_layers no)
			(net 123 "/Ethernet/PAIR_78")
			(pinfunction "VC3")
			(pintype "bidirectional")
		)
		(pad "14" thru_hole circle
			(at 11.429 5.07)
			(size 1.397 1.397)
			(drill 0.889)
			(layers "*.Cu" "*.Mask")
			(remove_unused_layers no)
			(net 124 "/Ethernet/PAIR_910")
			(pinfunction "VC4")
			(pintype "bidirectional")
		)
		(pad "15" thru_hole circle
			(at -0.927 12.958)
			(size 1.524 1.524)
			(drill 1.016)
			(layers "*.Cu" "*.Mask")
			(remove_unused_layers no)
			(net 87 "+3V3")
			(pinfunction "LED_GRN+")
			(pintype "passive")
		)
		(pad "16" thru_hole circle
			(at 1.614 12.958)
			(size 1.524 1.524)
			(drill 1.016)
			(layers "*.Cu" "*.Mask")
			(remove_unused_layers no)
			(net 551 "Net-(J6-LED_GRN-)")
			(pinfunction "LED_GRN-")
			(pintype "passive")
		)
		(pad "17" thru_hole circle
			(at 9.814 12.958)
			(size 1.524 1.524)
			(drill 1.016)
			(layers "*.Cu" "*.Mask")
			(remove_unused_layers no)
			(net 87 "+3V3")
			(pinfunction "LED_YEL+")
			(pintype "passive")
		)
		(pad "18" thru_hole circle
			(at 12.355 12.958)
			(size 1.524 1.524)
			(drill 1.016)
			(layers "*.Cu" "*.Mask")
			(remove_unused_layers no)
			(net 552 "Net-(J6-LED_YEL-)")
			(pinfunction "LED_YEL-")
			(pintype "passive")
		)
		(pad "19" thru_hole circle
			(at -2.136 5.85)
			(size 2.1 2.1)
			(drill 1.6)
			(layers "*.Cu" "*.Mask")
			(remove_unused_layers no)
			(net 715 "Net-(C78-Pad1)")
			(pinfunction "SHIELD")
			(pintype "passive")
		)
		(pad "20" thru_hole circle
			(at 13.563 5.85)
			(size 2.1082 2.1082)
			(drill 1.6002)
			(layers "*.Cu" "*.Mask")
			(remove_unused_layers no)
			(net 715 "Net-(C78-Pad1)")
			(pinfunction "SHIELD")
			(pintype "passive")
		)
	)
	(footprint "antmicro-footprints:R_0603_1608Metric"
		(layer "F.Cu")
		(at 137.2 115.9 180)
		(descr "Resistor SMD 0603")
		(tags "resistor SMD 0603")
		(property "Reference" "R247"
			(at 4.05 -0.4 180)
			(layer "F.SilkS")
			(effects
				(font
					(size 0.7 0.7)
					(thickness 0.15)
				)
				(justify left bottom)
			)
		)
		(property "Value" "R_0R_0603"
			(at 0 1.6 180)
			(layer "F.Fab")
			(effects
				(font
					(size 0.7 0.7)
					(thickness 0.15)
				)
				(justify left bottom)
			)
		)
		(property "Footprint" "antmicro-footprints:R_0603_1608Metric"
			(at 0 0 180)
			(layer "F.Fab")
			(hide yes)
			(effects
				(font
					(size 1.27 1.27)
					(thickness 0.15)
				)
			)
		)
		(property "Datasheet" "https://www.bourns.com/docs/product-datasheets/cr.pdf?sfvrsn=574d41f6_14"
			(at 0 0 180)
			(layer "F.Fab")
			(hide yes)
			(effects
				(font
					(size 1.27 1.27)
					(thickness 0.15)
				)
			)
		)
		(property "Author" "Antmicro"
			(at 274.4 231.8 0)
			(layer "F.Fab")
			(hide yes)
			(effects
				(font
					(size 1 1)
					(thickness 0.15)
				)
			)
		)
		(property "Current" "1A"
			(at 274.4 231.8 0)
			(layer "F.Fab")
			(hide yes)
			(effects
				(font
					(size 1 1)
					(thickness 0.15)
				)
			)
		)
		(property "License" "Apache-2.0"
			(at 274.4 231.8 0)
			(layer "F.Fab")
			(hide yes)
			(effects
				(font
					(size 1 1)
					(thickness 0.15)
				)
			)
		)
		(property "MPN" "CR0603-J/-000ELF"
			(at 274.4 231.8 0)
			(layer "F.Fab")
			(hide yes)
			(effects
				(font
					(size 1 1)
					(thickness 0.15)
				)
			)
		)
		(property "Manufacturer" "Bourns"
			(at 274.4 231.8 0)
			(layer "F.Fab")
			(hide yes)
			(effects
				(font
					(size 1 1)
					(thickness 0.15)
				)
			)
		)
		(property "Tolerance" ""
			(at 274.4 231.8 0)
			(layer "F.Fab")
			(hide yes)
			(effects
				(font
					(size 1 1)
					(thickness 0.15)
				)
			)
		)
		(property "Val" "0R"
			(at 274.4 231.8 0)
			(layer "F.Fab")
			(hide yes)
			(effects
				(font
					(size 1 1)
					(thickness 0.15)
				)
			)
		)
		(sheetname "Peripherals")
		(sheetfile "peripherals.kicad_sch")
		(attr smd)
		(fp_line
			(start -0.15 0.4)
			(end 0.15 0.4)
			(stroke
				(width 0.15)
				(type solid)
			)
			(layer "F.SilkS")
		)
		(fp_line
			(start -0.15 -0.4)
			(end 0.15 -0.4)
			(stroke
				(width 0.15)
				(type solid)
			)
			(layer "F.SilkS")
		)
		(fp_rect
			(start -1.25 -0.65)
			(end 1.25 0.65)
			(stroke
				(width 0.05)
				(type solid)
			)
			(fill none)
			(layer "F.CrtYd")
		)
		(fp_rect
			(start -0.8 -0.4)
			(end 0.8 0.4)
			(stroke
				(width 0.15)
				(type solid)
			)
			(fill none)
			(layer "F.Fab")
		)
		(fp_text user "Author: Antmicro"
			(at -1.25 4.9 180)
			(layer "F.Fab")
			(hide yes)
			(effects
				(font
					(size 0.7 0.7)
					(thickness 0.15)
				)
				(justify left bottom)
			)
		)
		(fp_text user "License: Apache-2.0"
			(at -1.25 5.9 180)
			(layer "F.Fab")
			(hide yes)
			(effects
				(font
					(size 0.7 0.7)
					(thickness 0.15)
				)
				(justify left bottom)
			)
		)
		(fp_text user "${REFERENCE}"
			(at -1.25 3.898 180)
			(layer "F.Fab")
			(hide yes)
			(effects
				(font
					(size 0.7 0.7)
					(thickness 0.15)
				)
				(justify left bottom)
			)
		)
		(pad "1" smd roundrect
			(at -0.7 0 180)
			(size 0.8 1)
			(layers "F.Cu" "F.Paste" "F.Mask")
			(roundrect_rratio 0.2)
			(net 484 "/Peripherals/3V3_STDB_CONN")
			(pintype "passive")
		)
		(pad "2" smd roundrect
			(at 0.7 0 180)
			(size 0.8 1)
			(layers "F.Cu" "F.Paste" "F.Mask")
			(roundrect_rratio 0.2)
			(net 117 "3V3_STDB")
			(pintype "passive")
		)
	)
	(footprint "antmicro-footprints:R_0402_1005Metric"
		(layer "F.Cu")
		(at 69.69 82.31 -90)
		(descr "Resistor SMD 0402")
		(tags "resistor SMD 0402")
		(property "Reference" "R4"
			(at 0.84 0.33 90)
			(layer "F.SilkS")
			(effects
				(font
					(size 0.7 0.7)
					(thickness 0.15)
				)
				(justify right top)
			)
		)
		(property "Value" "R_0R_0402"
			(at 0 1.4 90)
			(layer "F.Fab")
			(effects
				(font
					(size 0.7 0.7)
					(thickness 0.15)
				)
				(justify right top)
			)
		)
		(property "Footprint" "antmicro-footprints:R_0402_1005Metric"
			(at 0 0 90)
			(layer "F.Fab")
			(hide yes)
			(effects
				(font
					(size 1.27 1.27)
					(thickness 0.15)
				)
			)
		)
		(property "Datasheet" "https://industrial.panasonic.com/cdbs/www-data/pdf/RDA0000/AOA0000C301.pdf"
			(at 0 0 90)
			(layer "F.Fab")
			(hide yes)
			(effects
				(font
					(size 1.27 1.27)
					(thickness 0.15)
				)
			)
		)
		(property "Author" "Antmicro"
			(at -13.14905 151.95095 0)
			(layer "F.Fab")
			(hide yes)
			(effects
				(font
					(size 1 1)
					(thickness 0.15)
				)
			)
		)
		(property "Current" "1A"
			(at -13.14905 151.95095 0)
			(layer "F.Fab")
			(hide yes)
			(effects
				(font
					(size 1 1)
					(thickness 0.15)
				)
			)
		)
		(property "License" "Apache-2.0"
			(at -13.14905 151.95095 0)
			(layer "F.Fab")
			(hide yes)
			(effects
				(font
					(size 1 1)
					(thickness 0.15)
				)
			)
		)
		(property "MPN" "ERJ2GE0R00X"
			(at -13.14905 151.95095 0)
			(layer "F.Fab")
			(hide yes)
			(effects
				(font
					(size 1 1)
					(thickness 0.15)
				)
			)
		)
		(property "Manufacturer" "Panasonic"
			(at -13.14905 151.95095 0)
			(layer "F.Fab")
			(hide yes)
			(effects
				(font
					(size 1 1)
					(thickness 0.15)
				)
			)
		)
		(property "Tolerance" ""
			(at -13.14905 151.95095 0)
			(layer "F.Fab")
			(hide yes)
			(effects
				(font
					(size 1 1)
					(thickness 0.15)
				)
			)
		)
		(property "Val" "0R"
			(at -13.14905 151.95095 0)
			(layer "F.Fab")
			(hide yes)
			(effects
				(font
					(size 1 1)
					(thickness 0.15)
				)
			)
		)
		(sheetname "SoM")
		(sheetfile "som.kicad_sch")
		(attr smd exclude_from_pos_files exclude_from_bom dnp)
		(fp_rect
			(start -0.925 -0.47)
			(end 0.925 0.47)
			(stroke
				(width 0.05)
				(type default)
			)
			(fill none)
			(layer "F.CrtYd")
		)
		(fp_rect
			(start -0.5 -0.25)
			(end 0.5 0.25)
			(stroke
				(width 0.15)
				(type solid)
			)
			(fill none)
			(layer "F.Fab")
		)
		(fp_text user "${REFERENCE}"
			(at -0.95 3.168 90)
			(layer "F.Fab")
			(hide yes)
			(effects
				(font
					(size 0.7 0.7)
					(thickness 0.15)
				)
				(justify right top)
			)
		)
		(fp_text user "Author: Antmicro"
			(at -0.95 4.169 90)
			(layer "F.Fab")
			(hide yes)
			(effects
				(font
					(size 0.7 0.7)
					(thickness 0.15)
				)
				(justify right top)
			)
		)
		(fp_text user "License: Apache-2.0"
			(at -0.95 5.169 90)
			(layer "F.Fab")
			(hide yes)
			(effects
				(font
					(size 0.7 0.7)
					(thickness 0.15)
				)
				(justify right top)
			)
		)
		(pad "1" smd roundrect
			(at -0.48 0 270)
			(size 0.59 0.64)
			(layers "F.Cu" "F.Paste" "F.Mask")
			(roundrect_rratio 0.25)
			(net 752 "Net-(J15H-GPIO12{slash}PWM)")
			(pintype "passive")
		)
		(pad "2" smd roundrect
			(at 0.48 0 270)
			(size 0.59 0.64)
			(layers "F.Cu" "F.Paste" "F.Mask")
			(roundrect_rratio 0.25)
			(net 242 "VSYNC_CAM2")
			(pintype "passive")
		)
	)
	(footprint "antmicro-footprints:C_0805_2012Metric"
		(layer "F.Cu")
		(at 71.58 86.82)
		(descr "Capacitor SMD 0805")
		(tags "capacitor SMD 0805")
		(property "Reference" "C122"
			(at -1.4 -0.91 0)
			(layer "F.SilkS")
			(effects
				(font
					(size 0.7 0.7)
					(thickness 0.15)
				)
				(justify left bottom)
			)
		)
		(property "Value" "C_22u_25V_0805"
			(at -2.055717 1.963152 0)
			(layer "F.Fab")
			(effects
				(font
					(size 0.7 0.7)
					(thickness 0.15)
				)
				(justify left bottom)
			)
		)
		(property "Footprint" "antmicro-footprints:C_0805_2012Metric"
			(at 0 0 0)
			(layer "F.Fab")
			(hide yes)
			(effects
				(font
					(size 1.27 1.27)
					(thickness 0.15)
				)
			)
		)
		(property "Datasheet" "https://product.samsungsem.com/mlcc/CL21A226MAYNNN.do"
			(at 0 0 0)
			(layer "F.Fab")
			(hide yes)
			(effects
				(font
					(size 1.27 1.27)
					(thickness 0.15)
				)
			)
		)
		(property "Author" "Antmicro"
			(at 0 0 0)
			(layer "F.Fab")
			(hide yes)
			(effects
				(font
					(size 1 1)
					(thickness 0.15)
				)
			)
		)
		(property "Dielectric" "X5R"
			(at 0 0 0)
			(layer "F.Fab")
			(hide yes)
			(effects
				(font
					(size 1 1)
					(thickness 0.15)
				)
			)
		)
		(property "License" "Apache-2.0"
			(at 0 0 0)
			(layer "F.Fab")
			(hide yes)
			(effects
				(font
					(size 1 1)
					(thickness 0.15)
				)
			)
		)
		(property "MPN" "CL21A226MAYNNNE"
			(at 0 0 0)
			(layer "F.Fab")
			(hide yes)
			(effects
				(font
					(size 1 1)
					(thickness 0.15)
				)
			)
		)
		(property "Manufacturer" "Samsung Electro-Mechanics"
			(at 0 0 0)
			(layer "F.Fab")
			(hide yes)
			(effects
				(font
					(size 1 1)
					(thickness 0.15)
				)
			)
		)
		(property "Public" "False"
			(at 0 0 0)
			(layer "F.Fab")
			(hide yes)
			(effects
				(font
					(size 1 1)
					(thickness 0.15)
				)
			)
		)
		(property "Val" "22u"
			(at 0 0 0)
			(layer "F.Fab")
			(hide yes)
			(effects
				(font
					(size 1 1)
					(thickness 0.15)
				)
			)
		)
		(property "Voltage" "25V"
			(at 0 0 0)
			(layer "F.Fab")
			(hide yes)
			(effects
				(font
					(size 1 1)
					(thickness 0.15)
				)
			)
		)
		(sheetname "Supply")
		(sheetfile "supply.kicad_sch")
		(attr smd)
		(fp_line
			(start -0.3 -0.7)
			(end 0.3 -0.7)
			(stroke
				(width 0.15)
				(type solid)
			)
			(layer "F.SilkS")
		)
		(fp_line
			(start -0.3 0.7)
			(end 0.3 0.7)
			(stroke
				(width 0.15)
				(type solid)
			)
			(layer "F.SilkS")
		)
		(fp_rect
			(start 1.95 -0.9)
			(end -1.95 0.9)
			(stroke
				(width 0.05)
				(type default)
			)
			(fill none)
			(layer "F.CrtYd")
		)
		(fp_rect
			(start -0.95 -0.675)
			(end 0.95 0.675)
			(stroke
				(width 0.15)
				(type solid)
			)
			(fill none)
			(layer "F.Fab")
		)
		(fp_text user "License: Apache-2.0"
			(at -1.9 4.947 0)
			(layer "F.Fab")
			(hide yes)
			(effects
				(font
					(size 0.7 0.7)
					(thickness 0.15)
				)
				(justify left bottom)
			)
		)
		(fp_text user "${REFERENCE}"
			(at -1.9 3.947 0)
			(layer "F.Fab")
			(hide yes)
			(effects
				(font
					(size 0.7 0.7)
					(thickness 0.15)
				)
				(justify left bottom)
			)
		)
		(fp_text user "Author: Antmicro"
			(at -1.9 5.947 0)
			(layer "F.Fab")
			(hide yes)
			(effects
				(font
					(size 0.7 0.7)
					(thickness 0.15)
				)
				(justify left bottom)
			)
		)
		(pad "1" smd roundrect
			(at -1.1 0)
			(size 1.2 1.3)
			(layers "F.Cu" "F.Paste" "F.Mask")
			(roundrect_rratio 0.25)
			(net 1 "GND")
			(pintype "passive")
		)
		(pad "2" smd roundrect
			(at 1.1 0)
			(size 1.2 1.3)
			(layers "F.Cu" "F.Paste" "F.Mask")
			(roundrect_rratio 0.25)
			(net 115 "VCC")
			(pintype "passive")
		)
	)
	(footprint "antmicro-footprints:R_0402_1005Metric"
		(layer "F.Cu")
		(at 148 110.5 180)
		(descr "Resistor SMD 0402")
		(tags "resistor SMD 0402")
		(property "Reference" "R335"
			(at 1.21 -5.91 180)
			(layer "F.SilkS")
			(effects
				(font
					(size 0.7 0.7)
					(thickness 0.15)
				)
				(justify left bottom)
			)
		)
		(property "Value" "R_470R_0402"
			(at 0 1.4 180)
			(layer "F.Fab")
			(effects
				(font
					(size 0.7 0.7)
					(thickness 0.15)
				)
				(justify left bottom)
			)
		)
		(property "Footprint" "antmicro-footprints:R_0402_1005Metric"
			(at 0 0 180)
			(layer "F.Fab")
			(hide yes)
			(effects
				(font
					(size 1.27 1.27)
					(thickness 0.15)
				)
			)
		)
		(property "Datasheet" "https://www.bourns.com/docs/product-datasheets/cr.pdf"
			(at 0 0 180)
			(layer "F.Fab")
			(hide yes)
			(effects
				(font
					(size 1.27 1.27)
					(thickness 0.15)
				)
			)
		)
		(property "Author" "Antmicro"
			(at 296 221 0)
			(layer "F.Fab")
			(hide yes)
			(effects
				(font
					(size 1 1)
					(thickness 0.15)
				)
			)
		)
		(property "License" "Apache-2.0"
			(at 296 221 0)
			(layer "F.Fab")
			(hide yes)
			(effects
				(font
					(size 1 1)
					(thickness 0.15)
				)
			)
		)
		(property "MPN" "CR0402-FX-4700GLF"
			(at 296 221 0)
			(layer "F.Fab")
			(hide yes)
			(effects
				(font
					(size 1 1)
					(thickness 0.15)
				)
			)
		)
		(property "Manufacturer" "Bourns"
			(at 296 221 0)
			(layer "F.Fab")
			(hide yes)
			(effects
				(font
					(size 1 1)
					(thickness 0.15)
				)
			)
		)
		(property "Tolerance" "1%"
			(at 296 221 0)
			(layer "F.Fab")
			(hide yes)
			(effects
				(font
					(size 1 1)
					(thickness 0.15)
				)
			)
		)
		(property "Val" "470R"
			(at 296 221 0)
			(layer "F.Fab")
			(hide yes)
			(effects
				(font
					(size 1 1)
					(thickness 0.15)
				)
			)
		)
		(sheetname "Peripherals")
		(sheetfile "peripherals.kicad_sch")
		(attr smd)
		(fp_rect
			(start -0.925 -0.47)
			(end 0.925 0.47)
			(stroke
				(width 0.05)
				(type default)
			)
			(fill none)
			(layer "F.CrtYd")
		)
		(fp_rect
			(start -0.5 -0.25)
			(end 0.5 0.25)
			(stroke
				(width 0.15)
				(type solid)
			)
			(fill none)
			(layer "F.Fab")
		)
		(fp_text user "Author: Antmicro"
			(at -0.95 4.169 180)
			(layer "F.Fab")
			(hide yes)
			(effects
				(font
					(size 0.7 0.7)
					(thickness 0.15)
				)
				(justify left bottom)
			)
		)
		(fp_text user "License: Apache-2.0"
			(at -0.95 5.169 180)
			(layer "F.Fab")
			(hide yes)
			(effects
				(font
					(size 0.7 0.7)
					(thickness 0.15)
				)
				(justify left bottom)
			)
		)
		(fp_text user "${REFERENCE}"
			(at -0.95 3.168 180)
			(layer "F.Fab")
			(hide yes)
			(effects
				(font
					(size 0.7 0.7)
					(thickness 0.15)
				)
				(justify left bottom)
			)
		)
		(pad "1" smd roundrect
			(at -0.48 0 180)
			(size 0.59 0.64)
			(layers "F.Cu" "F.Paste" "F.Mask")
			(roundrect_rratio 0.25)
			(net 100 "CAN_RX")
			(pintype "passive")
		)
		(pad "2" smd roundrect
			(at 0.48 0 180)
			(size 0.59 0.64)
			(layers "F.Cu" "F.Paste" "F.Mask")
			(roundrect_rratio 0.25)
			(net 600 "Net-(J11-Pad68)")
			(pintype "passive")
		)
	)
	(footprint "antmicro-footprints:C_0402_1005Metric"
		(layer "F.Cu")
		(at 81.9 104.6 180)
		(descr "Capacitor SMD 0402")
		(tags "capacitor SMD 0402")
		(property "Reference" "C144"
			(at -0.8 -0.45 180)
			(layer "F.SilkS")
			(effects
				(font
					(size 0.7 0.7)
					(thickness 0.15)
				)
				(justify left bottom)
			)
		)
		(property "Value" "C_100n_0402"
			(at 0 1.4 180)
			(layer "F.Fab")
			(effects
				(font
					(size 0.7 0.7)
					(thickness 0.15)
				)
				(justify left bottom)
			)
		)
		(property "Footprint" "antmicro-footprints:C_0402_1005Metric"
			(at 0 0 180)
			(layer "F.Fab")
			(hide yes)
			(effects
				(font
					(size 1.27 1.27)
					(thickness 0.15)
				)
			)
		)
		(property "Datasheet" "https://www.murata.com/products/productdetail?partno=GRM155R61H104KE14%23"
			(at 0 0 180)
			(layer "F.Fab")
			(hide yes)
			(effects
				(font
					(size 1.27 1.27)
					(thickness 0.15)
				)
			)
		)
		(property "Author" "Antmicro"
			(at 163.8 209.2 0)
			(layer "F.Fab")
			(hide yes)
			(effects
				(font
					(size 1 1)
					(thickness 0.15)
				)
			)
		)
		(property "Dielectric" "X5R"
			(at 163.8 209.2 0)
			(layer "F.Fab")
			(hide yes)
			(effects
				(font
					(size 1 1)
					(thickness 0.15)
				)
			)
		)
		(property "License" "Apache-2.0"
			(at 163.8 209.2 0)
			(layer "F.Fab")
			(hide yes)
			(effects
				(font
					(size 1 1)
					(thickness 0.15)
				)
			)
		)
		(property "MPN" "GRM155R61H104KE14D"
			(at 163.8 209.2 0)
			(layer "F.Fab")
			(hide yes)
			(effects
				(font
					(size 1 1)
					(thickness 0.15)
				)
			)
		)
		(property "Manufacturer" "Murata"
			(at 163.8 209.2 0)
			(layer "F.Fab")
			(hide yes)
			(effects
				(font
					(size 1 1)
					(thickness 0.15)
				)
			)
		)
		(property "Val" "100n"
			(at 163.8 209.2 0)
			(layer "F.Fab")
			(hide yes)
			(effects
				(font
					(size 1 1)
					(thickness 0.15)
				)
			)
		)
		(property "Voltage" "50V"
			(at 163.8 209.2 0)
			(layer "F.Fab")
			(hide yes)
			(effects
				(font
					(size 1 1)
					(thickness 0.15)
				)
			)
		)
		(sheetname "USB Debug, DP")
		(sheetfile "usb.kicad_sch")
		(attr smd)
		(fp_rect
			(start -0.925 -0.47)
			(end 0.925 0.47)
			(stroke
				(width 0.05)
				(type default)
			)
			(fill none)
			(layer "F.CrtYd")
		)
		(fp_line
			(start 0.504 0.248)
			(end -0.494 0.248)
			(stroke
				(width 0.15)
				(type solid)
			)
			(layer "F.Fab")
		)
		(fp_line
			(start 0.504 -0.25)
			(end 0.504 0.248)
			(stroke
				(width 0.15)
				(type solid)
			)
			(layer "F.Fab")
		)
		(fp_line
			(start -0.494 0.248)
			(end -0.494 -0.25)
			(stroke
				(width 0.15)
				(type solid)
			)
			(layer "F.Fab")
		)
		(fp_line
			(start -0.494 -0.25)
			(end 0.504 -0.25)
			(stroke
				(width 0.15)
				(type solid)
			)
			(layer "F.Fab")
		)
		(fp_text user "Author: Antmicro"
			(at -0.932 4.17 180)
			(layer "F.Fab")
			(hide yes)
			(effects
				(font
					(size 0.7 0.7)
					(thickness 0.15)
				)
				(justify left bottom)
			)
		)
		(fp_text user "License: Apache-2.0"
			(at -0.932 5.17 180)
			(layer "F.Fab")
			(hide yes)
			(effects
				(font
					(size 0.7 0.7)
					(thickness 0.15)
				)
				(justify left bottom)
			)
		)
		(fp_text user "${REFERENCE}"
			(at -0.932 3.168 180)
			(layer "F.Fab")
			(hide yes)
			(effects
				(font
					(size 0.7 0.7)
					(thickness 0.15)
				)
				(justify left bottom)
			)
		)
		(pad "1" smd roundrect
			(at -0.48 0 180)
			(size 0.59 0.64)
			(layers "F.Cu" "F.Paste" "F.Mask")
			(roundrect_rratio 0.25)
			(net 59 "USBSS0_TX_N")
			(pintype "passive")
		)
		(pad "2" smd roundrect
			(at 0.48 0 180)
			(size 0.59 0.64)
			(layers "F.Cu" "F.Paste" "F.Mask")
			(roundrect_rratio 0.25)
			(net 194 "/USB Debug, DP/USBSS0_TX_C_P")
			(pintype "passive")
		)
	)
	(footprint "antmicro-footprints:C_0402_1005Metric"
		(layer "F.Cu")
		(at 137.4 113.1)
		(descr "Capacitor SMD 0402")
		(tags "capacitor SMD 0402")
		(property "Reference" "C106"
			(at -5.84 0.27 0)
			(layer "F.SilkS")
			(effects
				(font
					(size 0.7 0.7)
					(thickness 0.15)
				)
				(justify left bottom)
			)
		)
		(property "Value" "C_1u_0402"
			(at 0 1.4 0)
			(layer "F.Fab")
			(effects
				(font
					(size 0.7 0.7)
					(thickness 0.15)
				)
				(justify left bottom)
			)
		)
		(property "Footprint" "antmicro-footprints:C_0402_1005Metric"
			(at 0 0 0)
			(layer "F.Fab")
			(hide yes)
			(effects
				(font
					(size 1.27 1.27)
					(thickness 0.15)
				)
			)
		)
		(property "Datasheet" "https://product.tdk.com/en/search/capacitor/ceramic/mlcc/info?part_no=C1005X6S1A105K050BC"
			(at 0 0 0)
			(layer "F.Fab")
			(hide yes)
			(effects
				(font
					(size 1.27 1.27)
					(thickness 0.15)
				)
			)
		)
		(property "Author" "Antmicro"
			(at 0 0 0)
			(layer "F.Fab")
			(hide yes)
			(effects
				(font
					(size 1 1)
					(thickness 0.15)
				)
			)
		)
		(property "Dielectric" ""
			(at 0 0 0)
			(layer "F.Fab")
			(hide yes)
			(effects
				(font
					(size 1 1)
					(thickness 0.15)
				)
			)
		)
		(property "License" "Apache-2.0"
			(at 0 0 0)
			(layer "F.Fab")
			(hide yes)
			(effects
				(font
					(size 1 1)
					(thickness 0.15)
				)
			)
		)
		(property "MPN" "C1005X6S1A105K050BC"
			(at 0 0 0)
			(layer "F.Fab")
			(hide yes)
			(effects
				(font
					(size 1 1)
					(thickness 0.15)
				)
			)
		)
		(property "Manufacturer" "TDK"
			(at 0 0 0)
			(layer "F.Fab")
			(hide yes)
			(effects
				(font
					(size 1 1)
					(thickness 0.15)
				)
			)
		)
		(property "Val" "1u"
			(at 0 0 0)
			(layer "F.Fab")
			(hide yes)
			(effects
				(font
					(size 1 1)
					(thickness 0.15)
				)
			)
		)
		(property "Voltage" ""
			(at 0 0 0)
			(layer "F.Fab")
			(hide yes)
			(effects
				(font
					(size 1 1)
					(thickness 0.15)
				)
			)
		)
		(sheetname "Peripherals")
		(sheetfile "peripherals.kicad_sch")
		(attr smd)
		(fp_rect
			(start -0.925 -0.47)
			(end 0.925 0.47)
			(stroke
				(width 0.05)
				(type default)
			)
			(fill none)
			(layer "F.CrtYd")
		)
		(fp_line
			(start -0.494 -0.25)
			(end 0.504 -0.25)
			(stroke
				(width 0.15)
				(type solid)
			)
			(layer "F.Fab")
		)
		(fp_line
			(start -0.494 0.248)
			(end -0.494 -0.25)
			(stroke
				(width 0.15)
				(type solid)
			)
			(layer "F.Fab")
		)
		(fp_line
			(start 0.504 -0.25)
			(end 0.504 0.248)
			(stroke
				(width 0.15)
				(type solid)
			)
			(layer "F.Fab")
		)
		(fp_line
			(start 0.504 0.248)
			(end -0.494 0.248)
			(stroke
				(width 0.15)
				(type solid)
			)
			(layer "F.Fab")
		)
		(fp_text user "License: Apache-2.0"
			(at -0.932 5.17 0)
			(layer "F.Fab")
			(hide yes)
			(effects
				(font
					(size 0.7 0.7)
					(thickness 0.15)
				)
				(justify left bottom)
			)
		)
		(fp_text user "Author: Antmicro"
			(at -0.932 4.17 0)
			(layer "F.Fab")
			(hide yes)
			(effects
				(font
					(size 0.7 0.7)
					(thickness 0.15)
				)
				(justify left bottom)
			)
		)
		(fp_text user "${REFERENCE}"
			(at -0.932 3.168 0)
			(layer "F.Fab")
			(hide yes)
			(effects
				(font
					(size 0.7 0.7)
					(thickness 0.15)
				)
				(justify left bottom)
			)
		)
		(pad "1" smd roundrect
			(at -0.48 0)
			(size 0.59 0.64)
			(layers "F.Cu" "F.Paste" "F.Mask")
			(roundrect_rratio 0.25)
			(net 1 "GND")
			(pintype "passive")
		)
		(pad "2" smd roundrect
			(at 0.48 0)
			(size 0.59 0.64)
			(layers "F.Cu" "F.Paste" "F.Mask")
			(roundrect_rratio 0.25)
			(net 483 "/Peripherals/1V8_CONN")
			(pintype "passive")
		)
	)
	(footprint "antmicro-footprints:SOT-523"
		(layer "F.Cu")
		(at 105.4 118.85 90)
		(property "Reference" "Q4"
			(at 1.125 -0.65 0)
			(layer "F.SilkS")
			(effects
				(font
					(size 0.7 0.7)
					(thickness 0.15)
				)
				(justify left bottom)
			)
		)
		(property "Value" "PJE138K"
			(at 0.1 1.824 90)
			(layer "F.Fab")
			(effects
				(font
					(size 0.7 0.7)
					(thickness 0.15)
				)
				(justify left bottom)
			)
		)
		(property "Footprint" "antmicro-footprints:SOT-523"
			(at 0 0 90)
			(layer "F.Fab")
			(hide yes)
			(effects
				(font
					(size 1.27 1.27)
					(thickness 0.15)
				)
			)
		)
		(property "Datasheet" "https://www.mouser.com/datasheet/2/1057/PJE138K-1876698.pdf"
			(at 0 0 90)
			(layer "F.Fab")
			(hide yes)
			(effects
				(font
					(size 1.27 1.27)
					(thickness 0.15)
				)
			)
		)
		(property "Author" "Antmicro"
			(at 224.25 13.45 0)
			(layer "F.Fab")
			(hide yes)
			(effects
				(font
					(size 1 1)
					(thickness 0.15)
				)
			)
		)
		(property "License" "Apache-2.0"
			(at 224.25 13.45 0)
			(layer "F.Fab")
			(hide yes)
			(effects
				(font
					(size 1 1)
					(thickness 0.15)
				)
			)
		)
		(property "MPN" "PJE138K_R1_00001"
			(at 224.25 13.45 0)
			(layer "F.Fab")
			(hide yes)
			(effects
				(font
					(size 1 1)
					(thickness 0.15)
				)
			)
		)
		(property "Manufacturer" "PANJIT"
			(at 224.25 13.45 0)
			(layer "F.Fab")
			(hide yes)
			(effects
				(font
					(size 1 1)
					(thickness 0.15)
				)
			)
		)
		(sheetname "USB3")
		(sheetfile "usb3.kicad_sch")
		(attr smd)
		(fp_line
			(start -0.277 -0.551)
			(end -0.277 -0.75)
			(stroke
				(width 0.15)
				(type solid)
			)
			(layer "F.SilkS")
		)
		(fp_line
			(start -0.725 -0.551)
			(end -0.277 -0.551)
			(stroke
				(width 0.15)
				(type solid)
			)
			(layer "F.SilkS")
		)
		(fp_line
			(start -0.927 -0.351)
			(end -0.725 -0.551)
			(stroke
				(width 0.15)
				(type solid)
			)
			(layer "F.SilkS")
		)
		(fp_line
			(start -0.927 -0.051)
			(end -0.927 -0.351)
			(stroke
				(width 0.15)
				(type solid)
			)
			(layer "F.SilkS")
		)
		(fp_circle
			(center -0.9652 0.9652)
			(end -0.9152 0.9652)
			(stroke
				(width 0.15)
				(type solid)
			)
			(fill solid)
			(layer "F.SilkS")
		)
		(fp_line
			(start 1.1 -1.16)
			(end 1.1 1.15)
			(stroke
				(width 0.05)
				(type solid)
			)
			(layer "F.CrtYd")
		)
		(fp_line
			(start -1.12 -1.16)
			(end 1.1 -1.16)
			(stroke
				(width 0.05)
				(type solid)
			)
			(layer "F.CrtYd")
		)
		(fp_line
			(start -1.12 -1.16)
			(end -1.12 1.15)
			(stroke
				(width 0.05)
				(type solid)
			)
			(layer "F.CrtYd")
		)
		(fp_line
			(start -1.12 1.15)
			(end 1.1 1.15)
			(stroke
				(width 0.05)
				(type solid)
			)
			(layer "F.CrtYd")
		)
		(fp_line
			(start 0.8 -0.425)
			(end -0.652 -0.425)
			(stroke
				(width 0.15)
				(type solid)
			)
			(layer "F.Fab")
		)
		(fp_line
			(start 0.8 -0.425)
			(end 0.8 0.424)
			(stroke
				(width 0.15)
				(type solid)
			)
			(layer "F.Fab")
		)
		(fp_line
			(start -0.652 -0.425)
			(end -0.802 -0.276)
			(stroke
				(width 0.15)
				(type solid)
			)
			(layer "F.Fab")
		)
		(fp_line
			(start -0.802 -0.276)
			(end -0.802 0.424)
			(stroke
				(width 0.15)
				(type solid)
			)
			(layer "F.Fab")
		)
		(fp_line
			(start 0.8 0.424)
			(end -0.802 0.424)
			(stroke
				(width 0.15)
				(type solid)
			)
			(layer "F.Fab")
		)
		(fp_circle
			(center -0.9652 0.9652)
			(end -0.9144 0.9652)
			(stroke
				(width 0.15)
				(type solid)
			)
			(fill none)
			(layer "F.Fab")
		)
		(fp_text user "Author: Antmicro"
			(at -1.12 6.224 90)
			(layer "F.Fab")
			(hide yes)
			(effects
				(font
					(size 0.7 0.7)
					(thickness 0.15)
				)
				(justify left bottom)
			)
		)
		(fp_text user "${REFERENCE}"
			(at -1.12 3.824 90)
			(layer "F.Fab")
			(hide yes)
			(effects
				(font
					(size 0.7 0.7)
					(thickness 0.15)
				)
				(justify left bottom)
			)
		)
		(fp_text user "License: Apache-2.0"
			(at -1.12 5.024 90)
			(layer "F.Fab")
			(hide yes)
			(effects
				(font
					(size 0.7 0.7)
					(thickness 0.15)
				)
				(justify left bottom)
			)
		)
		(pad "1" smd rect
			(at -0.5 0.65 90)
			(size 0.4 0.51)
			(layers "F.Cu" "F.Paste" "F.Mask")
			(net 284 "/USB3/USBC1_ID")
			(pinfunction "G")
			(pintype "passive")
		)
		(pad "2" smd rect
			(at 0.498 0.65 90)
			(size 0.4 0.51)
			(layers "F.Cu" "F.Paste" "F.Mask")
			(net 1 "GND")
			(pinfunction "S")
			(pintype "passive")
		)
		(pad "3" smd rect
			(at 0 -0.652 90)
			(size 0.4 0.51)
			(layers "F.Cu" "F.Paste" "F.Mask")
			(net 625 "Net-(Q4-D)")
			(pinfunction "D")
			(pintype "passive")
		)
	)
	(footprint "antmicro-footprints:LED_0603_1608Metric_G"
		(layer "F.Cu")
		(at 30.775 105.025 -90)
		(descr "LED SMD 0603 Green")
		(tags "LED SMD 0603 Green")
		(property "Reference" "D15"
			(at 1.075 -0.025 -90)
			(layer "F.SilkS")
			(effects
				(font
					(size 0.7 0.7)
					(thickness 0.15)
				)
				(justify right bottom)
			)
		)
		(property "Value" "LED_G_0603_LTST-C190GKT"
			(at -0.001 1.599 90)
			(layer "F.Fab")
			(effects
				(font
					(size 0.7 0.7)
					(thickness 0.15)
				)
				(justify right bottom)
			)
		)
		(property "Footprint" "antmicro-footprints:LED_0603_1608Metric_G"
			(at 0 0 -90)
			(layer "F.Fab")
			(hide yes)
			(effects
				(font
					(size 1.27 1.27)
					(thickness 0.15)
				)
			)
		)
		(property "Datasheet" "https://media.digikey.com/pdf/Data%20Sheets/Lite-On%20PDFs/LTST-C190GKT.pdf"
			(at 0 0 -90)
			(layer "F.Fab")
			(hide yes)
			(effects
				(font
					(size 1.27 1.27)
					(thickness 0.15)
				)
			)
		)
		(property "Author" "Antmicro"
			(at -74.25 135.8 0)
			(layer "F.Fab")
			(hide yes)
			(effects
				(font
					(size 1 1)
					(thickness 0.15)
				)
			)
		)
		(property "Color" "Green"
			(at -74.25 135.8 0)
			(layer "F.Fab")
			(hide yes)
			(effects
				(font
					(size 1 1)
					(thickness 0.15)
				)
			)
		)
		(property "License" "Apache-2.0"
			(at -74.25 135.8 0)
			(layer "F.Fab")
			(hide yes)
			(effects
				(font
					(size 1 1)
					(thickness 0.15)
				)
			)
		)
		(property "MPN" "LTST-C190GKT"
			(at -74.25 135.8 0)
			(layer "F.Fab")
			(hide yes)
			(effects
				(font
					(size 1 1)
					(thickness 0.15)
				)
			)
		)
		(property "Manufacturer" "Lite-On"
			(at -74.25 135.8 0)
			(layer "F.Fab")
			(hide yes)
			(effects
				(font
					(size 1 1)
					(thickness 0.15)
				)
			)
		)
		(sheetname "Ethernet")
		(sheetfile "ethernet.kicad_sch")
		(attr smd)
		(fp_line
			(start 0.22 0.35)
			(end -0.22 0.35)
			(stroke
				(width 0.15)
				(type solid)
			)
			(layer "F.SilkS")
		)
		(fp_line
			(start -0.094672 0.201008)
			(end -0.094672 -0.198992)
			(stroke
				(width 0.1)
				(type solid)
			)
			(layer "F.SilkS")
		)
		(fp_line
			(start 0.105328 0.201008)
			(end -0.094672 0.001008)
			(stroke
				(width 0.1)
				(type solid)
			)
			(layer "F.SilkS")
		)
		(fp_line
			(start 0.105328 0.201008)
			(end 0.105328 -0.198992)
			(stroke
				(width 0.1)
				(type solid)
			)
			(layer "F.SilkS")
		)
		(fp_line
			(start -0.094672 0.001008)
			(end -0.24 0.001008)
			(stroke
				(width 0.1)
				(type solid)
			)
			(layer "F.SilkS")
		)
		(fp_line
			(start -0.094672 0.001008)
			(end 0.105328 -0.198992)
			(stroke
				(width 0.1)
				(type solid)
			)
			(layer "F.SilkS")
		)
		(fp_line
			(start 0.105328 0.001008)
			(end 0.24 0.001)
			(stroke
				(width 0.1)
				(type solid)
			)
			(layer "F.SilkS")
		)
		(fp_line
			(start -1.18 -0.319)
			(end -1.18 0.321)
			(stroke
				(width 0.15)
				(type solid)
			)
			(layer "F.SilkS")
		)
		(fp_line
			(start 0.22 -0.35)
			(end -0.22 -0.35)
			(stroke
				(width 0.15)
				(type solid)
			)
			(layer "F.SilkS")
		)
		(fp_rect
			(start 1.25 0.65)
			(end -1.25 -0.65)
			(stroke
				(width 0.05)
				(type solid)
			)
			(fill none)
			(layer "F.CrtYd")
		)
		(fp_line
			(start -0.199 0.2)
			(end -0.199 0.1)
			(stroke
				(width 0.15)
				(type solid)
			)
			(layer "F.Fab")
		)
		(fp_line
			(start 0.201 0.2)
			(end 0.201 0)
			(stroke
				(width 0.15)
				(type solid)
			)
			(layer "F.Fab")
		)
		(fp_line
			(start -0.199 0)
			(end -0.597 0)
			(stroke
				(width 0.15)
				(type solid)
			)
			(layer "F.Fab")
		)
		(fp_line
			(start -0.101 0)
			(end 0.201 0.2)
			(stroke
				(width 0.15)
				(type solid)
			)
			(layer "F.Fab")
		)
		(fp_line
			(start 0.201 0)
			(end 0.201 -0.202)
			(stroke
				(width 0.15)
				(type solid)
			)
			(layer "F.Fab")
		)
		(fp_line
			(start 0.599 0)
			(end 0.201 0)
			(stroke
				(width 0.15)
				(type solid)
			)
			(layer "F.Fab")
		)
		(fp_line
			(start -0.199 -0.202)
			(end -0.199 0.1)
			(stroke
				(width 0.15)
				(type solid)
			)
			(layer "F.Fab")
		)
		(fp_line
			(start 0.201 -0.202)
			(end -0.101 0)
			(stroke
				(width 0.15)
				(type solid)
			)
			(layer "F.Fab")
		)
		(fp_rect
			(start 0.848 0.4)
			(end -0.85 -0.402)
			(stroke
				(width 0.15)
				(type solid)
			)
			(fill none)
			(layer "F.Fab")
		)
		(fp_text user "${REFERENCE}"
			(at -1.4224 5.999 90)
			(layer "F.Fab")
			(hide yes)
			(effects
				(font
					(size 0.7 0.7)
					(thickness 0.15)
				)
				(justify right bottom)
			)
		)
		(fp_text user "License: Apache-2.0"
			(at -1.4224 3.599 90)
			(layer "F.Fab")
			(hide yes)
			(effects
				(font
					(size 0.7 0.7)
					(thickness 0.15)
				)
				(justify right bottom)
			)
		)
		(fp_text user "Author: Antmicro"
			(at -1.4224 4.799 90)
			(layer "F.Fab")
			(hide yes)
			(effects
				(font
					(size 0.7 0.7)
					(thickness 0.15)
				)
				(justify right bottom)
			)
		)
		(pad "1" smd roundrect
			(at -0.7 0 90)
			(size 0.8 1)
			(layers "F.Cu" "F.Paste" "F.Mask")
			(roundrect_rratio 0.2)
			(net 106 "GNDD")
			(pinfunction "C")
			(pintype "passive")
		)
		(pad "2" smd roundrect
			(at 0.7 0 90)
			(size 0.8 1)
			(layers "F.Cu" "F.Paste" "F.Mask")
			(roundrect_rratio 0.2)
			(net 153 "Net-(D15-A)")
			(pinfunction "A")
			(pintype "passive")
		)
	)
	(footprint "antmicro-footprints:R_0402_1005Metric"
		(layer "F.Cu")
		(at 75.42 85.34)
		(descr "Resistor SMD 0402")
		(tags "resistor SMD 0402")
		(property "Reference" "R176"
			(at -2.12 -2.3 0)
			(layer "F.SilkS")
			(effects
				(font
					(size 0.7 0.7)
					(thickness 0.15)
				)
				(justify left bottom)
			)
		)
		(property "Value" "R_499k_0402"
			(at -1.011843 1.772047 0)
			(layer "F.Fab")
			(effects
				(font
					(size 0.7 0.7)
					(thickness 0.15)
				)
				(justify left bottom)
			)
		)
		(property "Footprint" "antmicro-footprints:R_0402_1005Metric"
			(at 0 0 0)
			(layer "F.Fab")
			(hide yes)
			(effects
				(font
					(size 1.27 1.27)
					(thickness 0.15)
				)
			)
		)
		(property "Datasheet" "https://www.mouser.com/datasheet/2/54/cr-1858361.pdf"
			(at 0 0 0)
			(layer "F.Fab")
			(hide yes)
			(effects
				(font
					(size 1.27 1.27)
					(thickness 0.15)
				)
			)
		)
		(property "Author" "Antmicro"
			(at 0 0 0)
			(layer "F.Fab")
			(hide yes)
			(effects
				(font
					(size 1 1)
					(thickness 0.15)
				)
			)
		)
		(property "License" "Apache-2.0"
			(at 0 0 0)
			(layer "F.Fab")
			(hide yes)
			(effects
				(font
					(size 1 1)
					(thickness 0.15)
				)
			)
		)
		(property "MPN" "CR0402-FX-4993GLF"
			(at 0 0 0)
			(layer "F.Fab")
			(hide yes)
			(effects
				(font
					(size 1 1)
					(thickness 0.15)
				)
			)
		)
		(property "Manufacturer" "Bourns"
			(at 0 0 0)
			(layer "F.Fab")
			(hide yes)
			(effects
				(font
					(size 1 1)
					(thickness 0.15)
				)
			)
		)
		(property "Tolerance" "1%"
			(at 0 0 0)
			(layer "F.Fab")
			(hide yes)
			(effects
				(font
					(size 1 1)
					(thickness 0.15)
				)
			)
		)
		(property "Val" "499k"
			(at 0 0 0)
			(layer "F.Fab")
			(hide yes)
			(effects
				(font
					(size 1 1)
					(thickness 0.15)
				)
			)
		)
		(sheetname "Supply")
		(sheetfile "supply.kicad_sch")
		(attr smd)
		(fp_rect
			(start -0.925 -0.47)
			(end 0.925 0.47)
			(stroke
				(width 0.05)
				(type default)
			)
			(fill none)
			(layer "F.CrtYd")
		)
		(fp_rect
			(start -0.5 -0.25)
			(end 0.5 0.25)
			(stroke
				(width 0.15)
				(type solid)
			)
			(fill none)
			(layer "F.Fab")
		)
		(fp_text user "${REFERENCE}"
			(at -0.95 3.168 0)
			(layer "F.Fab")
			(hide yes)
			(effects
				(font
					(size 0.7 0.7)
					(thickness 0.15)
				)
				(justify left bottom)
			)
		)
		(fp_text user "License: Apache-2.0"
			(at -0.95 5.169 0)
			(layer "F.Fab")
			(hide yes)
			(effects
				(font
					(size 0.7 0.7)
					(thickness 0.15)
				)
				(justify left bottom)
			)
		)
		(fp_text user "Author: Antmicro"
			(at -0.95 4.169 0)
			(layer "F.Fab")
			(hide yes)
			(effects
				(font
					(size 0.7 0.7)
					(thickness 0.15)
				)
				(justify left bottom)
			)
		)
		(pad "1" smd roundrect
			(at -0.48 0)
			(size 0.59 0.64)
			(layers "F.Cu" "F.Paste" "F.Mask")
			(roundrect_rratio 0.25)
			(net 1 "GND")
			(pintype "passive")
		)
		(pad "2" smd roundrect
			(at 0.48 0)
			(size 0.59 0.64)
			(layers "F.Cu" "F.Paste" "F.Mask")
			(roundrect_rratio 0.25)
			(net 687 "/Supply/3V3_MODE1")
			(pintype "passive")
		)
	)
	(footprint "antmicro-footprints:SOT-23-3"
		(layer "F.Cu")
		(at 58.2 112.6 -90)
		(property "Reference" "Q15"
			(at 1.825 2.725 0)
			(layer "F.SilkS")
			(effects
				(font
					(size 0.7 0.7)
					(thickness 0.15)
				)
				(justify left bottom)
			)
		)
		(property "Value" "SSM3J332R"
			(at -1.9 2.7 -90)
			(layer "F.Fab")
			(effects
				(font
					(size 0.7 0.7)
					(thickness 0.15)
				)
				(justify left bottom)
			)
		)
		(property "Footprint" "antmicro-footprints:SOT-23-3"
			(at 0 0 -90)
			(layer "F.Fab")
			(hide yes)
			(effects
				(font
					(size 1.27 1.27)
					(thickness 0.15)
				)
			)
		)
		(property "Datasheet" "https://www.mouser.com/datasheet/2/408/SSM3J332R_datasheet_en_20181015-1150575.pdf"
			(at 0 0 -90)
			(layer "F.Fab")
			(hide yes)
			(effects
				(font
					(size 1.27 1.27)
					(thickness 0.15)
				)
			)
		)
		(property "Author" "Antmicro"
			(at -54.4 170.8 0)
			(layer "F.Fab")
			(hide yes)
			(effects
				(font
					(size 1 1)
					(thickness 0.15)
				)
			)
		)
		(property "License" "Apache-2.0"
			(at -54.4 170.8 0)
			(layer "F.Fab")
			(hide yes)
			(effects
				(font
					(size 1 1)
					(thickness 0.15)
				)
			)
		)
		(property "MPN" "SSM3J332R,LF"
			(at -54.4 170.8 0)
			(layer "F.Fab")
			(hide yes)
			(effects
				(font
					(size 1 1)
					(thickness 0.15)
				)
			)
		)
		(property "Manufacturer" "Toshiba"
			(at -54.4 170.8 0)
			(layer "F.Fab")
			(hide yes)
			(effects
				(font
					(size 1 1)
					(thickness 0.15)
				)
			)
		)
		(sheetname "Supply")
		(sheetfile "supply.kicad_sch")
		(attr smd)
		(fp_line
			(start -0.7 1.5)
			(end -0.7 1.35)
			(stroke
				(width 0.15)
				(type solid)
			)
			(layer "F.SilkS")
		)
		(fp_line
			(start 0.7 1.5)
			(end -0.7 1.5)
			(stroke
				(width 0.15)
				(type solid)
			)
			(layer "F.SilkS")
		)
		(fp_line
			(start 0.7 0.4)
			(end 0.7 1.5)
			(stroke
				(width 0.15)
				(type solid)
			)
			(layer "F.SilkS")
		)
		(fp_line
			(start 0.7 -0.4)
			(end 0.7 -1.5)
			(stroke
				(width 0.15)
				(type solid)
			)
			(layer "F.SilkS")
		)
		(fp_line
			(start -1.45 -1.35)
			(end -0.85 -1.35)
			(stroke
				(width 0.15)
				(type solid)
			)
			(layer "F.SilkS")
		)
		(fp_line
			(start -0.85 -1.35)
			(end -0.7 -1.5)
			(stroke
				(width 0.15)
				(type solid)
			)
			(layer "F.SilkS")
		)
		(fp_line
			(start 0.7 -1.5)
			(end -0.7 -1.5)
			(stroke
				(width 0.15)
				(type solid)
			)
			(layer "F.SilkS")
		)
		(fp_line
			(start -0.85 1.65)
			(end -0.85 1.4)
			(stroke
				(width 0.05)
				(type solid)
			)
			(layer "F.CrtYd")
		)
		(fp_line
			(start 0.85 1.65)
			(end -0.85 1.65)
			(stroke
				(width 0.05)
				(type solid)
			)
			(layer "F.CrtYd")
		)
		(fp_line
			(start -1.75 1.4)
			(end -1.75 0.5)
			(stroke
				(width 0.05)
				(type solid)
			)
			(layer "F.CrtYd")
		)
		(fp_line
			(start -0.85 1.4)
			(end -1.75 1.4)
			(stroke
				(width 0.05)
				(type solid)
			)
			(layer "F.CrtYd")
		)
		(fp_line
			(start -1.75 0.5)
			(end -0.85 0.5)
			(stroke
				(width 0.05)
				(type solid)
			)
			(layer "F.CrtYd")
		)
		(fp_line
			(start -0.85 0.5)
			(end -0.85 -0.5)
			(stroke
				(width 0.05)
				(type solid)
			)
			(layer "F.CrtYd")
		)
		(fp_line
			(start 0.85 0.45)
			(end 0.85 1.65)
			(stroke
				(width 0.05)
				(type solid)
			)
			(layer "F.CrtYd")
		)
		(fp_line
			(start 1.75 0.45)
			(end 0.85 0.45)
			(stroke
				(width 0.05)
				(type solid)
			)
			(layer "F.CrtYd")
		)
		(fp_line
			(start 0.825 -0.45)
			(end 1.75 -0.45)
			(stroke
				(width 0.05)
				(type solid)
			)
			(layer "F.CrtYd")
		)
		(fp_line
			(start 1.75 -0.45)
			(end 1.75 0.45)
			(stroke
				(width 0.05)
				(type solid)
			)
			(layer "F.CrtYd")
		)
		(fp_line
			(start -1.75 -0.5)
			(end -1.75 -1.4)
			(stroke
				(width 0.05)
				(type solid)
			)
			(layer "F.CrtYd")
		)
		(fp_line
			(start -0.85 -0.5)
			(end -1.75 -0.5)
			(stroke
				(width 0.05)
				(type solid)
			)
			(layer "F.CrtYd")
		)
		(fp_line
			(start -0.9 -1.4)
			(end -1.75 -1.4)
			(stroke
				(width 0.05)
				(type solid)
			)
			(layer "F.CrtYd")
		)
		(fp_line
			(start -0.9 -1.6)
			(end -0.9 -1.4)
			(stroke
				(width 0.05)
				(type solid)
			)
			(layer "F.CrtYd")
		)
		(fp_line
			(start -0.9 -1.6)
			(end 0.825 -1.6)
			(stroke
				(width 0.05)
				(type solid)
			)
			(layer "F.CrtYd")
		)
		(fp_line
			(start 0.825 -1.6)
			(end 0.825 -0.45)
			(stroke
				(width 0.05)
				(type solid)
			)
			(layer "F.CrtYd")
		)
		(fp_line
			(start -0.712 1.519)
			(end 0.688 1.519)
			(stroke
				(width 0.15)
				(type solid)
			)
			(layer "F.Fab")
		)
		(fp_line
			(start 0.688 1.519)
			(end 0.688 -1.52)
			(stroke
				(width 0.15)
				(type solid)
			)
			(layer "F.Fab")
		)
		(fp_line
			(start -0.712 -1.325)
			(end -0.712 1.523)
			(stroke
				(width 0.15)
				(type solid)
			)
			(layer "F.Fab")
		)
		(fp_line
			(start -0.437 -1.526)
			(end -0.712 -1.325)
			(stroke
				(width 0.15)
				(type solid)
			)
			(layer "F.Fab")
		)
		(fp_line
			(start -0.437 -1.526)
			(end 0.688 -1.526)
			(stroke
				(width 0.15)
				(type solid)
			)
			(layer "F.Fab")
		)
		(fp_text user "Author: Antmicro"
			(at -1.837 5.3 -90)
			(layer "F.Fab")
			(hide yes)
			(effects
				(font
					(size 0.7 0.7)
					(thickness 0.15)
				)
				(justify left bottom)
			)
		)
		(fp_text user "License: Apache-2.0"
			(at -1.8 6.8 -90)
			(layer "F.Fab")
			(hide yes)
			(effects
				(font
					(size 0.7 0.7)
					(thickness 0.15)
				)
				(justify left bottom)
			)
		)
		(fp_text user "${REFERENCE}"
			(at -1.837 4 -90)
			(layer "F.Fab")
			(hide yes)
			(effects
				(font
					(size 0.7 0.7)
					(thickness 0.15)
				)
				(justify left bottom)
			)
		)
		(pad "1" smd roundrect
			(at -1.1 -0.951 270)
			(size 1 0.6)
			(layers "F.Cu" "F.Paste" "F.Mask")
			(roundrect_rratio 0.15)
			(net 630 "Net-(Q15-G)")
			(pinfunction "G")
			(pintype "bidirectional")
		)
		(pad "2" smd roundrect
			(at -1.1 0.949 270)
			(size 1 0.6)
			(layers "F.Cu" "F.Paste" "F.Mask")
			(roundrect_rratio 0.15)
			(net 328 "/Supply/VCC_IN")
			(pinfunction "S")
			(pintype "bidirectional")
		)
		(pad "3" smd roundrect
			(at 1.1 -0.0005 270)
			(size 1 0.6)
			(layers "F.Cu" "F.Paste" "F.Mask")
			(roundrect_rratio 0.15)
			(net 189 "Net-(D28-C)")
			(pinfunction "D")
			(pintype "bidirectional")
		)
	)
	(footprint "antmicro-footprints:R_Array_4x0402"
		(layer "F.Cu")
		(at 147.85 103.12 -90)
		(property "Reference" "R101"
			(at 1.44 -1.6 -90)
			(layer "F.SilkS")
			(effects
				(font
					(size 0.7 0.7)
					(thickness 0.15)
				)
				(justify left bottom)
			)
		)
		(property "Value" "R_4x330R_0402_array"
			(at -1.5 2 -90)
			(layer "F.Fab")
			(effects
				(font
					(size 0.7 0.7)
					(thickness 0.15)
				)
				(justify left bottom)
			)
		)
		(property "Footprint" "antmicro-footprints:R_Array_4x0402"
			(at 0 0 -90)
			(layer "F.Fab")
			(hide yes)
			(effects
				(font
					(size 1.27 1.27)
					(thickness 0.15)
				)
			)
		)
		(property "Datasheet" "http://industrial.panasonic.com/cdbs/www-data/pdf/AOC0000/AOC0000C14.pdf"
			(at 0 0 -90)
			(layer "F.Fab")
			(hide yes)
			(effects
				(font
					(size 1.27 1.27)
					(thickness 0.15)
				)
			)
		)
		(property "Author" "Antmicro"
			(at 44.73 250.97 0)
			(layer "F.Fab")
			(hide yes)
			(effects
				(font
					(size 1 1)
					(thickness 0.15)
				)
			)
		)
		(property "License" "Apache-2.0"
			(at 44.73 250.97 0)
			(layer "F.Fab")
			(hide yes)
			(effects
				(font
					(size 1 1)
					(thickness 0.15)
				)
			)
		)
		(property "MPN" "EXB-28V331JX"
			(at 44.73 250.97 0)
			(layer "F.Fab")
			(hide yes)
			(effects
				(font
					(size 1 1)
					(thickness 0.15)
				)
			)
		)
		(property "Manufacturer" "Panasonic"
			(at 44.73 250.97 0)
			(layer "F.Fab")
			(hide yes)
			(effects
				(font
					(size 1 1)
					(thickness 0.15)
				)
			)
		)
		(property "Val" "R_4x330R_0402"
			(at 44.73 250.97 0)
			(layer "F.Fab")
			(hide yes)
			(effects
				(font
					(size 1 1)
					(thickness 0.15)
				)
			)
		)
		(sheetname "Peripherals")
		(sheetfile "peripherals.kicad_sch")
		(attr smd)
		(fp_line
			(start 1.167 0.498)
			(end 1.167 -0.5)
			(stroke
				(width 0.15)
				(type solid)
			)
			(layer "F.SilkS")
		)
		(fp_line
			(start -1.17 -0.5)
			(end -1.17 0.498)
			(stroke
				(width 0.15)
				(type solid)
			)
			(layer "F.SilkS")
		)
		(fp_rect
			(start -1.2 -0.9)
			(end 1.2 0.9)
			(stroke
				(width 0.05)
				(type solid)
			)
			(fill none)
			(layer "F.CrtYd")
		)
		(fp_line
			(start -1 0.498)
			(end -1 -0.5)
			(stroke
				(width 0.15)
				(type solid)
			)
			(layer "F.Fab")
		)
		(fp_line
			(start 0.998 0.498)
			(end -1 0.498)
			(stroke
				(width 0.15)
				(type solid)
			)
			(layer "F.Fab")
		)
		(fp_line
			(start -1 -0.5)
			(end 0.998 -0.5)
			(stroke
				(width 0.15)
				(type solid)
			)
			(layer "F.Fab")
		)
		(fp_line
			(start 0.998 -0.5)
			(end 0.998 0.498)
			(stroke
				(width 0.15)
				(type solid)
			)
			(layer "F.Fab")
		)
		(fp_text user "License: Apache-2.0"
			(at -1.5 5.75 -90)
			(layer "F.Fab")
			(hide yes)
			(effects
				(font
					(size 0.7 0.7)
					(thickness 0.15)
				)
				(justify left bottom)
			)
		)
		(fp_text user "Author: Antmicro"
			(at -1.5 4.5 -90)
			(layer "F.Fab")
			(hide yes)
			(effects
				(font
					(size 0.7 0.7)
					(thickness 0.15)
				)
				(justify left bottom)
			)
		)
		(fp_text user "${REFERENCE}"
			(at -1.5 3.25 -90)
			(layer "F.Fab")
			(hide yes)
			(effects
				(font
					(size 0.7 0.7)
					(thickness 0.15)
				)
				(justify left bottom)
			)
		)
		(pad "1" smd roundrect
			(at -0.802 0.45 270)
			(size 0.4 0.5)
			(layers "F.Cu" "F.Paste" "F.Mask")
			(roundrect_rratio 0.25)
			(net 588 "/Peripherals/I2S0_SDOUT_CONN")
			(pinfunction "R1.1")
			(pintype "passive")
		)
		(pad "2" smd roundrect
			(at -0.272 0.45 270)
			(size 0.4 0.5)
			(layers "F.Cu" "F.Paste" "F.Mask")
			(roundrect_rratio 0.25)
			(net 590 "/Peripherals/SPI1_SCK_CONN")
			(pinfunction "R2.1")
			(pintype "passive")
		)
		(pad "3" smd roundrect
			(at 0.27 0.45 270)
			(size 0.4 0.5)
			(layers "F.Cu" "F.Paste" "F.Mask")
			(roundrect_rratio 0.25)
			(net 592 "/Peripherals/SPI1_MOSI_CONN")
			(pinfunction "R3.1")
			(pintype "passive")
		)
		(pad "4" smd roundrect
			(at 0.8 0.45 270)
			(size 0.4 0.5)
			(layers "F.Cu" "F.Paste" "F.Mask")
			(roundrect_rratio 0.25)
			(net 594 "/Peripherals/SPI1_MISO_CONN")
			(pinfunction "R4.1")
			(pintype "passive")
		)
		(pad "5" smd roundrect
			(at 0.8 -0.452 270)
			(size 0.4 0.5)
			(layers "F.Cu" "F.Paste" "F.Mask")
			(roundrect_rratio 0.25)
			(net 39 "SPI1_MISO")
			(pinfunction "R4.2")
			(pintype "passive")
		)
		(pad "6" smd roundrect
			(at 0.27 -0.452 270)
			(size 0.4 0.5)
			(layers "F.Cu" "F.Paste" "F.Mask")
			(roundrect_rratio 0.25)
			(net 37 "SPI1_MOSI")
			(pinfunction "R3.2")
			(pintype "passive")
		)
		(pad "7" smd roundrect
			(at -0.272 -0.452 270)
			(size 0.4 0.5)
			(layers "F.Cu" "F.Paste" "F.Mask")
			(roundrect_rratio 0.25)
			(net 38 "SPI1_SCK")
			(pinfunction "R2.2")
			(pintype "passive")
		)
		(pad "8" smd roundrect
			(at -0.802 -0.452 270)
			(size 0.4 0.5)
			(layers "F.Cu" "F.Paste" "F.Mask")
			(roundrect_rratio 0.25)
			(net 70 "I2S0_SDOUT")
			(pinfunction "R1.2")
			(pintype "passive")
		)
	)
	(footprint "antmicro-footprints:XDFN-2_1x0.60mm"
		(layer "F.Cu")
		(at 135.1 88.47 90)
		(property "Reference" "D43"
			(at -0.6 0.4 0)
			(layer "F.SilkS")
			(effects
				(font
					(size 0.7 0.7)
					(thickness 0.15)
				)
				(justify left bottom)
			)
		)
		(property "Value" "TPD1E0B04_XDFN-2"
			(at 0 1.5 90)
			(layer "F.Fab")
			(effects
				(font
					(size 0.7 0.7)
					(thickness 0.15)
				)
				(justify left bottom)
			)
		)
		(property "Footprint" "antmicro-footprints:XDFN-2_1x0.60mm"
			(at 0 0 90)
			(layer "F.Fab")
			(hide yes)
			(effects
				(font
					(size 1.27 1.27)
					(thickness 0.15)
				)
			)
		)
		(property "Datasheet" "https://www.ti.com/general/docs/suppproductinfo.tsp?distId=26&gotoUrl=https://www.ti.com/lit/gpn/tpd1e0b04"
			(at 0 0 90)
			(layer "F.Fab")
			(hide yes)
			(effects
				(font
					(size 1.27 1.27)
					(thickness 0.15)
				)
			)
		)
		(property "MPN" "TPD1E0B04DPYR"
			(at 223.57 -46.63 0)
			(layer "F.Fab")
			(hide yes)
			(effects
				(font
					(size 1 1)
					(thickness 0.15)
				)
			)
		)
		(property "Manufacturer" "Texas Instruments"
			(at 223.57 -46.63 0)
			(layer "F.Fab")
			(hide yes)
			(effects
				(font
					(size 1 1)
					(thickness 0.15)
				)
			)
		)
		(property "Author" "Antmicro"
			(at 223.57 -46.63 0)
			(layer "F.Fab")
			(hide yes)
			(effects
				(font
					(size 1 1)
					(thickness 0.15)
				)
			)
		)
		(property "License" "Apache-2.0"
			(at 223.57 -46.63 0)
			(layer "F.Fab")
			(hide yes)
			(effects
				(font
					(size 1 1)
					(thickness 0.15)
				)
			)
		)
		(sheetname "Peripherals")
		(sheetfile "peripherals.kicad_sch")
		(attr smd)
		(fp_rect
			(start -0.725 -0.475)
			(end 0.725 0.475)
			(stroke
				(width 0.05)
				(type solid)
			)
			(fill none)
			(layer "F.CrtYd")
		)
		(fp_rect
			(start -0.55 -0.35)
			(end 0.55 0.35)
			(stroke
				(width 0.15)
				(type solid)
			)
			(fill none)
			(layer "F.Fab")
		)
		(fp_text user "License: Apache-2.0"
			(at -0.8 5.6 90)
			(layer "F.Fab")
			(hide yes)
			(effects
				(font
					(size 0.7 0.7)
					(thickness 0.15)
				)
				(justify left bottom)
			)
		)
		(fp_text user "Author: Antmicro"
			(at -0.8 4.4 90)
			(layer "F.Fab")
			(hide yes)
			(effects
				(font
					(size 0.7 0.7)
					(thickness 0.15)
				)
				(justify left bottom)
			)
		)
		(fp_text user "${REFERENCE}"
			(at -0.8 3.2 90)
			(layer "F.Fab")
			(hide yes)
			(effects
				(font
					(size 0.7 0.7)
					(thickness 0.15)
				)
				(justify left bottom)
			)
		)
		(pad "1" smd roundrect
			(at -0.351 0 90)
			(size 0.3 0.5)
			(layers "F.Cu" "F.Paste" "F.Mask")
			(roundrect_rratio 0.25)
			(net 163 "PCIE2_CLK_N")
			(pinfunction "C")
			(pintype "passive")
		)
		(pad "2" smd roundrect
			(at 0.349 0 90)
			(size 0.3 0.5)
			(layers "F.Cu" "F.Paste" "F.Mask")
			(roundrect_rratio 0.25)
			(net 1 "GND")
			(pinfunction "A")
			(pintype "passive")
		)
	)
	(footprint "antmicro-footprints:USON-8_2x3mm_P0.5mm"
		(layer "F.Cu")
		(at 82.02 115.4 -90)
		(property "Reference" "U7"
			(at -1.79 -1.89 90)
			(layer "F.SilkS")
			(effects
				(font
					(size 0.7 0.7)
					(thickness 0.15)
				)
				(justify left bottom)
			)
		)
		(property "Value" "W25Q80DV_USON"
			(at 0 2.3 -90)
			(layer "F.Fab")
			(effects
				(font
					(size 0.7 0.7)
					(thickness 0.15)
				)
				(justify left bottom)
			)
		)
		(property "Footprint" "antmicro-footprints:USON-8_2x3mm_P0.5mm"
			(at 0 0 -90)
			(layer "F.Fab")
			(hide yes)
			(effects
				(font
					(size 1.27 1.27)
					(thickness 0.15)
				)
			)
		)
		(property "Datasheet" "https://www.mouser.com/datasheet/2/949/w25q80dv_dl_revh_10022015-1489677.pdf"
			(at 0 0 -90)
			(layer "F.Fab")
			(hide yes)
			(effects
				(font
					(size 1.27 1.27)
					(thickness 0.15)
				)
			)
		)
		(property "Author" "Antmicro"
			(at -33.38 197.42 0)
			(layer "F.Fab")
			(hide yes)
			(effects
				(font
					(size 1 1)
					(thickness 0.15)
				)
			)
		)
		(property "License" "Apache-2.0"
			(at -33.38 197.42 0)
			(layer "F.Fab")
			(hide yes)
			(effects
				(font
					(size 1 1)
					(thickness 0.15)
				)
			)
		)
		(property "MPN" "W25Q80DVUXIE TR"
			(at -33.38 197.42 0)
			(layer "F.Fab")
			(hide yes)
			(effects
				(font
					(size 1 1)
					(thickness 0.15)
				)
			)
		)
		(property "Manufacturer" "Winbond"
			(at -33.38 197.42 0)
			(layer "F.Fab")
			(hide yes)
			(effects
				(font
					(size 1 1)
					(thickness 0.15)
				)
			)
		)
		(sheetname "USB Debug, DP")
		(sheetfile "usb.kicad_sch")
		(attr smd)
		(fp_line
			(start 1.71 1.3005)
			(end -1.71 1.3)
			(stroke
				(width 0.15)
				(type solid)
			)
			(layer "F.SilkS")
		)
		(fp_line
			(start -1.71 1.3)
			(end -1.71 -0.89)
			(stroke
				(width 0.15)
				(type solid)
			)
			(layer "F.SilkS")
		)
		(fp_line
			(start -1.71 -0.89)
			(end -1.3 -1.301)
			(stroke
				(width 0.15)
				(type solid)
			)
			(layer "F.SilkS")
		)
		(fp_line
			(start 1.71 -1.3005)
			(end 1.71 1.3005)
			(stroke
				(width 0.15)
				(type solid)
			)
			(layer "F.SilkS")
		)
		(fp_line
			(start -1.3 -1.301)
			(end 1.71 -1.3005)
			(stroke
				(width 0.15)
				(type solid)
			)
			(layer "F.SilkS")
		)
		(fp_circle
			(center -1.75 -1.25)
			(end -1.7 -1.25)
			(stroke
				(width 0.15)
				(type solid)
			)
			(fill solid)
			(layer "F.SilkS")
		)
		(fp_rect
			(start 1.9 -1.4)
			(end -1.9 1.4)
			(stroke
				(width 0.05)
				(type solid)
			)
			(fill none)
			(layer "F.CrtYd")
		)
		(fp_line
			(start -1.499 -0.5)
			(end -0.998 -1)
			(stroke
				(width 0.15)
				(type solid)
			)
			(layer "F.Fab")
		)
		(fp_rect
			(start 1.5 1)
			(end -1.5 -1)
			(stroke
				(width 0.15)
				(type solid)
			)
			(fill none)
			(layer "F.Fab")
		)
		(fp_text user "License: Apache-2.0"
			(at -1.9 7.099 -90)
			(layer "F.Fab")
			(hide yes)
			(effects
				(font
					(size 0.7 0.7)
					(thickness 0.15)
				)
				(justify left bottom)
			)
		)
		(fp_text user "Author: Antmicro"
			(at -1.9 6.099 -90)
			(layer "F.Fab")
			(hide yes)
			(effects
				(font
					(size 0.7 0.7)
					(thickness 0.15)
				)
				(justify left bottom)
			)
		)
		(fp_text user "${REFERENCE}"
			(at -1.9 5.099 -90)
			(layer "F.Fab")
			(hide yes)
			(effects
				(font
					(size 0.7 0.7)
					(thickness 0.15)
				)
				(justify left bottom)
			)
		)
		(pad "1" smd roundrect
			(at -1.273 -0.75 180)
			(size 0.3 0.7)
			(layers "F.Cu" "F.Paste" "F.Mask")
			(roundrect_rratio 0.25)
			(net 253 "~{PDC_CS}")
			(pinfunction "~{CS}")
			(pintype "input")
		)
		(pad "2" smd roundrect
			(at -1.273 -0.25 180)
			(size 0.3 0.7)
			(layers "F.Cu" "F.Paste" "F.Mask")
			(roundrect_rratio 0.25)
			(net 255 "PDC_MISO")
			(pinfunction "SO/IO1")
			(pintype "input")
		)
		(pad "3" smd roundrect
			(at -1.273 0.248 180)
			(size 0.3 0.7)
			(layers "F.Cu" "F.Paste" "F.Mask")
			(roundrect_rratio 0.25)
			(net 98 "EEPROM_PWR")
			(pinfunction "~{WP}/IO2")
			(pintype "input")
		)
		(pad "4" smd roundrect
			(at -1.273 0.748 180)
			(size 0.3 0.7)
			(layers "F.Cu" "F.Paste" "F.Mask")
			(roundrect_rratio 0.25)
			(net 1 "GND")
			(pinfunction "VSS")
			(pintype "power_in")
		)
		(pad "5" smd roundrect
			(at 1.276 0.748 180)
			(size 0.3 0.7)
			(layers "F.Cu" "F.Paste" "F.Mask")
			(roundrect_rratio 0.25)
			(net 256 "PDC_MOSI")
			(pinfunction "SI/IO0")
			(pintype "input")
		)
		(pad "6" smd roundrect
			(at 1.276 0.248 180)
			(size 0.3 0.7)
			(layers "F.Cu" "F.Paste" "F.Mask")
			(roundrect_rratio 0.25)
			(net 254 "PDC_SCLK")
			(pinfunction "SCLK")
			(pintype "input")
		)
		(pad "7" smd roundrect
			(at 1.276 -0.25 180)
			(size 0.3 0.7)
			(layers "F.Cu" "F.Paste" "F.Mask")
			(roundrect_rratio 0.25)
			(net 98 "EEPROM_PWR")
			(pinfunction "~{HOLD}/IO3")
			(pintype "input")
		)
		(pad "8" smd roundrect
			(at 1.276 -0.75 180)
			(size 0.3 0.7)
			(layers "F.Cu" "F.Paste" "F.Mask")
			(roundrect_rratio 0.25)
			(net 98 "EEPROM_PWR")
			(pinfunction "VCC")
			(pintype "power_in")
		)
		(pad "EP" smd roundrect
			(at 0 0 270)
			(size 0.2 1.6)
			(layers "F.Cu" "F.Paste" "F.Mask")
			(roundrect_rratio 0.25)
			(net 728 "unconnected-(U7-PadEP)")
			(pinfunction "EP")
			(pintype "power_in+no_connect")
		)
	)
	(footprint "antmicro-footprints:TP_SMD_0.75mm"
		(layer "F.Cu")
		(at 64.475 122.485 180)
		(property "Reference" "TP27"
			(at -0.45 0.42 -90)
			(layer "F.SilkS")
			(effects
				(font
					(size 0.7 0.7)
					(thickness 0.15)
				)
				(justify left bottom)
			)
		)
		(property "Value" "TP_0.75mm_SMD"
			(at 0 1.2 180)
			(layer "F.Fab")
			(effects
				(font
					(size 0.7 0.7)
					(thickness 0.15)
				)
				(justify left bottom)
			)
		)
		(property "Footprint" "antmicro-footprints:TP_SMD_0.75mm"
			(at 0 0 180)
			(layer "F.Fab")
			(hide yes)
			(effects
				(font
					(size 1.27 1.27)
					(thickness 0.15)
				)
			)
		)
		(property "Author" "Antmicro"
			(at 128.95 244.97 0)
			(layer "F.Fab")
			(hide yes)
			(effects
				(font
					(size 1 1)
					(thickness 0.15)
				)
			)
		)
		(property "License" "Apache-2.0"
			(at 128.95 244.97 0)
			(layer "F.Fab")
			(hide yes)
			(effects
				(font
					(size 1 1)
					(thickness 0.15)
				)
			)
		)
		(property "MPN" ""
			(at 128.95 244.97 0)
			(layer "F.Fab")
			(hide yes)
			(effects
				(font
					(size 1 1)
					(thickness 0.15)
				)
			)
		)
		(property "Manufacturer" ""
			(at 128.95 244.97 0)
			(layer "F.Fab")
			(hide yes)
			(effects
				(font
					(size 1 1)
					(thickness 0.15)
				)
			)
		)
		(sheetname "USB Debug, DP")
		(sheetfile "usb.kicad_sch")
		(attr exclude_from_pos_files exclude_from_bom)
		(fp_circle
			(center 0 0)
			(end 0.475 0)
			(stroke
				(width 0.05)
				(type default)
			)
			(fill none)
			(layer "F.CrtYd")
		)
		(fp_text user "Author: Antmicro"
			(at -0.4 3.901 180)
			(layer "F.Fab")
			(hide yes)
			(effects
				(font
					(size 0.7 0.7)
					(thickness 0.15)
				)
				(justify left bottom)
			)
		)
		(fp_text user "${REFERENCE}"
			(at -0.4 2.7 180)
			(layer "F.Fab")
			(hide yes)
			(effects
				(font
					(size 0.7 0.7)
					(thickness 0.15)
				)
				(justify left bottom)
			)
		)
		(fp_text user "License: Apache-2.0"
			(at -0.4 5.101 180)
			(layer "F.Fab")
			(hide yes)
			(effects
				(font
					(size 0.7 0.7)
					(thickness 0.15)
				)
				(justify left bottom)
			)
		)
		(pad "1" smd circle
			(at 0 0 180)
			(size 0.75 0.75)
			(layers "F.Cu" "F.Mask")
			(net 501 "/USB Debug, DP/USBC3_FLG")
			(pinfunction "1")
			(pintype "passive")
		)
	)
	(footprint "antmicro-footprints:LED_0603_1608Metric_G"
		(layer "F.Cu")
		(at 47 105.025 -90)
		(descr "LED SMD 0603 Green")
		(tags "LED SMD 0603 Green")
		(property "Reference" "D62"
			(at 11.075 -1.4 -90)
			(layer "F.SilkS")
			(effects
				(font
					(size 0.7 0.7)
					(thickness 0.15)
				)
				(justify right top)
			)
		)
		(property "Value" "LED_G_0603_LTST-C190GKT"
			(at -0.001 1.599 90)
			(layer "F.Fab")
			(effects
				(font
					(size 0.7 0.7)
					(thickness 0.15)
				)
				(justify right top)
			)
		)
		(property "Footprint" "antmicro-footprints:LED_0603_1608Metric_G"
			(at 0 0 90)
			(layer "F.Fab")
			(hide yes)
			(effects
				(font
					(size 1.27 1.27)
					(thickness 0.15)
				)
			)
		)
		(property "Datasheet" "https://media.digikey.com/pdf/Data%20Sheets/Lite-On%20PDFs/LTST-C190GKT.pdf"
			(at 0 0 90)
			(layer "F.Fab")
			(hide yes)
			(effects
				(font
					(size 1.27 1.27)
					(thickness 0.15)
				)
			)
		)
		(property "MPN" "LTST-C190GKT"
			(at 0 0 -90)
			(unlocked yes)
			(layer "F.Fab")
			(hide yes)
			(effects
				(font
					(size 1 1)
					(thickness 0.15)
				)
			)
		)
		(property "Manufacturer" "Lite-On"
			(at 0 0 -90)
			(unlocked yes)
			(layer "F.Fab")
			(hide yes)
			(effects
				(font
					(size 1 1)
					(thickness 0.15)
				)
			)
		)
		(property "Author" "Antmicro"
			(at 0 0 -90)
			(unlocked yes)
			(layer "F.Fab")
			(hide yes)
			(effects
				(font
					(size 1 1)
					(thickness 0.15)
				)
			)
		)
		(property "License" "Apache-2.0"
			(at 0 0 -90)
			(unlocked yes)
			(layer "F.Fab")
			(hide yes)
			(effects
				(font
					(size 1 1)
					(thickness 0.15)
				)
			)
		)
		(property "Color" "Green"
			(at 0 0 -90)
			(unlocked yes)
			(layer "F.Fab")
			(hide yes)
			(effects
				(font
					(size 1 1)
					(thickness 0.15)
				)
			)
		)
		(sheetname "Supply")
		(sheetfile "supply.kicad_sch")
		(attr smd)
		(fp_line
			(start 0.22 0.35)
			(end -0.22 0.35)
			(stroke
				(width 0.15)
				(type solid)
			)
			(layer "F.SilkS")
		)
		(fp_line
			(start -0.094672 0.201008)
			(end -0.094672 -0.198992)
			(stroke
				(width 0.1)
				(type solid)
			)
			(layer "F.SilkS")
		)
		(fp_line
			(start 0.105328 0.201008)
			(end -0.094672 0.001008)
			(stroke
				(width 0.1)
				(type solid)
			)
			(layer "F.SilkS")
		)
		(fp_line
			(start 0.105328 0.201008)
			(end 0.105328 -0.198992)
			(stroke
				(width 0.1)
				(type solid)
			)
			(layer "F.SilkS")
		)
		(fp_line
			(start -0.094672 0.001008)
			(end -0.24 0.001008)
			(stroke
				(width 0.1)
				(type solid)
			)
			(layer "F.SilkS")
		)
		(fp_line
			(start -0.094672 0.001008)
			(end 0.105328 -0.198992)
			(stroke
				(width 0.1)
				(type solid)
			)
			(layer "F.SilkS")
		)
		(fp_line
			(start 0.105328 0.001008)
			(end 0.24 0.001)
			(stroke
				(width 0.1)
				(type solid)
			)
			(layer "F.SilkS")
		)
		(fp_line
			(start -1.18 -0.319)
			(end -1.18 0.321)
			(stroke
				(width 0.15)
				(type solid)
			)
			(layer "F.SilkS")
		)
		(fp_line
			(start 0.22 -0.35)
			(end -0.22 -0.35)
			(stroke
				(width 0.15)
				(type solid)
			)
			(layer "F.SilkS")
		)
		(fp_rect
			(start 1.25 0.65)
			(end -1.25 -0.65)
			(stroke
				(width 0.05)
				(type solid)
			)
			(fill none)
			(layer "F.CrtYd")
		)
		(fp_line
			(start -0.199 0.2)
			(end -0.199 0.1)
			(stroke
				(width 0.15)
				(type solid)
			)
			(layer "F.Fab")
		)
		(fp_line
			(start 0.201 0.2)
			(end 0.201 0)
			(stroke
				(width 0.15)
				(type solid)
			)
			(layer "F.Fab")
		)
		(fp_line
			(start -0.199 0)
			(end -0.597 0)
			(stroke
				(width 0.15)
				(type solid)
			)
			(layer "F.Fab")
		)
		(fp_line
			(start -0.101 0)
			(end 0.201 0.2)
			(stroke
				(width 0.15)
				(type solid)
			)
			(layer "F.Fab")
		)
		(fp_line
			(start 0.201 0)
			(end 0.201 -0.202)
			(stroke
				(width 0.15)
				(type solid)
			)
			(layer "F.Fab")
		)
		(fp_line
			(start 0.599 0)
			(end 0.201 0)
			(stroke
				(width 0.15)
				(type solid)
			)
			(layer "F.Fab")
		)
		(fp_line
			(start -0.199 -0.202)
			(end -0.199 0.1)
			(stroke
				(width 0.15)
				(type solid)
			)
			(layer "F.Fab")
		)
		(fp_line
			(start 0.201 -0.202)
			(end -0.101 0)
			(stroke
				(width 0.15)
				(type solid)
			)
			(layer "F.Fab")
		)
		(fp_rect
			(start 0.848 0.4)
			(end -0.85 -0.402)
			(stroke
				(width 0.15)
				(type solid)
			)
			(fill none)
			(layer "F.Fab")
		)
		(fp_text user "License: Apache-2.0"
			(at -1.4224 3.599 90)
			(layer "F.Fab")
			(hide yes)
			(effects
				(font
					(size 0.7 0.7)
					(thickness 0.15)
				)
				(justify right top)
			)
		)
		(fp_text user "Author: Antmicro"
			(at -1.4224 4.799 90)
			(layer "F.Fab")
			(hide yes)
			(effects
				(font
					(size 0.7 0.7)
					(thickness 0.15)
				)
				(justify right top)
			)
		)
		(fp_text user "${REFERENCE}"
			(at -1.4224 5.999 90)
			(layer "F.Fab")
			(hide yes)
			(effects
				(font
					(size 0.7 0.7)
					(thickness 0.15)
				)
				(justify right top)
			)
		)
		(pad "1" smd roundrect
			(at -0.7 0 90)
			(size 0.8 1)
			(layers "F.Cu" "F.Paste" "F.Mask")
			(roundrect_rratio 0.2)
			(net 793 "Net-(D62-C)")
			(pinfunction "C")
			(pintype "passive")
		)
		(pad "2" smd roundrect
			(at 0.7 0 90)
			(size 0.8 1)
			(layers "F.Cu" "F.Paste" "F.Mask")
			(roundrect_rratio 0.2)
			(net 798 "Net-(D62-A)")
			(pinfunction "A")
			(pintype "passive")
		)
	)
	(footprint "antmicro-footprints:TP_SMD_0.75mm"
		(layer "F.Cu")
		(at 127.905 115.235 180)
		(property "Reference" "TP6"
			(at -0.46 -0.445 0)
			(layer "F.SilkS")
			(effects
				(font
					(size 0.7 0.7)
					(thickness 0.15)
				)
				(justify left bottom)
			)
		)
		(property "Value" "TP_0.75mm_SMD"
			(at 0 1.2 180)
			(layer "F.Fab")
			(effects
				(font
					(size 0.7 0.7)
					(thickness 0.15)
				)
				(justify left bottom)
			)
		)
		(property "Footprint" "antmicro-footprints:TP_SMD_0.75mm"
			(at 0 0 180)
			(layer "F.Fab")
			(hide yes)
			(effects
				(font
					(size 1.27 1.27)
					(thickness 0.15)
				)
			)
		)
		(property "Author" "Antmicro"
			(at 255.81 230.47 0)
			(layer "F.Fab")
			(hide yes)
			(effects
				(font
					(size 1 1)
					(thickness 0.15)
				)
			)
		)
		(property "License" "Apache-2.0"
			(at 255.81 230.47 0)
			(layer "F.Fab")
			(hide yes)
			(effects
				(font
					(size 1 1)
					(thickness 0.15)
				)
			)
		)
		(property "MPN" ""
			(at 255.81 230.47 0)
			(layer "F.Fab")
			(hide yes)
			(effects
				(font
					(size 1 1)
					(thickness 0.15)
				)
			)
		)
		(property "Manufacturer" ""
			(at 255.81 230.47 0)
			(layer "F.Fab")
			(hide yes)
			(effects
				(font
					(size 1 1)
					(thickness 0.15)
				)
			)
		)
		(sheetname "M.2")
		(sheetfile "m-2.kicad_sch")
		(attr exclude_from_pos_files exclude_from_bom)
		(fp_circle
			(center 0 0)
			(end 0.475 0)
			(stroke
				(width 0.05)
				(type default)
			)
			(fill none)
			(layer "F.CrtYd")
		)
		(fp_text user "Author: Antmicro"
			(at -0.4 3.901 180)
			(layer "F.Fab")
			(hide yes)
			(effects
				(font
					(size 0.7 0.7)
					(thickness 0.15)
				)
				(justify left bottom)
			)
		)
		(fp_text user "${REFERENCE}"
			(at -0.4 2.7 180)
			(layer "F.Fab")
			(hide yes)
			(effects
				(font
					(size 0.7 0.7)
					(thickness 0.15)
				)
				(justify left bottom)
			)
		)
		(fp_text user "License: Apache-2.0"
			(at -0.4 5.101 180)
			(layer "F.Fab")
			(hide yes)
			(effects
				(font
					(size 0.7 0.7)
					(thickness 0.15)
				)
				(justify left bottom)
			)
		)
		(pad "1" smd circle
			(at 0 0 180)
			(size 0.75 0.75)
			(layers "F.Cu" "F.Mask")
			(net 225 "/M.2/~{M2_E_ALERT}")
			(pinfunction "1")
			(pintype "passive")
		)
	)
	(footprint "antmicro-footprints:R_0402_1005Metric"
		(layer "F.Cu")
		(at 107.3 102.65 -90)
		(descr "Resistor SMD 0402")
		(tags "resistor SMD 0402")
		(property "Reference" "R119"
			(at -0.725 -0.45 -90)
			(layer "F.SilkS")
			(effects
				(font
					(size 0.7 0.7)
					(thickness 0.15)
				)
				(justify left bottom)
			)
		)
		(property "Value" "R_0R_0402"
			(at 0 1.4 -90)
			(layer "F.Fab")
			(effects
				(font
					(size 0.7 0.7)
					(thickness 0.15)
				)
				(justify left bottom)
			)
		)
		(property "Footprint" "antmicro-footprints:R_0402_1005Metric"
			(at 0 0 -90)
			(layer "F.Fab")
			(hide yes)
			(effects
				(font
					(size 1.27 1.27)
					(thickness 0.15)
				)
			)
		)
		(property "Datasheet" "https://industrial.panasonic.com/cdbs/www-data/pdf/RDA0000/AOA0000C301.pdf"
			(at 0 0 -90)
			(layer "F.Fab")
			(hide yes)
			(effects
				(font
					(size 1.27 1.27)
					(thickness 0.15)
				)
			)
		)
		(property "Author" "Antmicro"
			(at 4.65 209.95 0)
			(layer "F.Fab")
			(hide yes)
			(effects
				(font
					(size 1 1)
					(thickness 0.15)
				)
			)
		)
		(property "Current" "1A"
			(at 4.65 209.95 0)
			(layer "F.Fab")
			(hide yes)
			(effects
				(font
					(size 1 1)
					(thickness 0.15)
				)
			)
		)
		(property "License" "Apache-2.0"
			(at 4.65 209.95 0)
			(layer "F.Fab")
			(hide yes)
			(effects
				(font
					(size 1 1)
					(thickness 0.15)
				)
			)
		)
		(property "MPN" "ERJ2GE0R00X"
			(at 4.65 209.95 0)
			(layer "F.Fab")
			(hide yes)
			(effects
				(font
					(size 1 1)
					(thickness 0.15)
				)
			)
		)
		(property "Manufacturer" "Panasonic"
			(at 4.65 209.95 0)
			(layer "F.Fab")
			(hide yes)
			(effects
				(font
					(size 1 1)
					(thickness 0.15)
				)
			)
		)
		(property "Tolerance" ""
			(at 4.65 209.95 0)
			(layer "F.Fab")
			(hide yes)
			(effects
				(font
					(size 1 1)
					(thickness 0.15)
				)
			)
		)
		(property "Val" "0R"
			(at 4.65 209.95 0)
			(layer "F.Fab")
			(hide yes)
			(effects
				(font
					(size 1 1)
					(thickness 0.15)
				)
			)
		)
		(sheetname "USB3")
		(sheetfile "usb3.kicad_sch")
		(attr smd)
		(fp_rect
			(start -0.925 -0.47)
			(end 0.925 0.47)
			(stroke
				(width 0.05)
				(type default)
			)
			(fill none)
			(layer "F.CrtYd")
		)
		(fp_rect
			(start -0.5 -0.25)
			(end 0.5 0.25)
			(stroke
				(width 0.15)
				(type solid)
			)
			(fill none)
			(layer "F.Fab")
		)
		(fp_text user "License: Apache-2.0"
			(at -0.95 5.169 -90)
			(layer "F.Fab")
			(hide yes)
			(effects
				(font
					(size 0.7 0.7)
					(thickness 0.15)
				)
				(justify left bottom)
			)
		)
		(fp_text user "Author: Antmicro"
			(at -0.95 4.169 -90)
			(layer "F.Fab")
			(hide yes)
			(effects
				(font
					(size 0.7 0.7)
					(thickness 0.15)
				)
				(justify left bottom)
			)
		)
		(fp_text user "${REFERENCE}"
			(at -0.95 3.168 -90)
			(layer "F.Fab")
			(hide yes)
			(effects
				(font
					(size 0.7 0.7)
					(thickness 0.15)
				)
				(justify left bottom)
			)
		)
		(pad "1" smd roundrect
			(at -0.48 0 270)
			(size 0.59 0.64)
			(layers "F.Cu" "F.Paste" "F.Mask")
			(roundrect_rratio 0.25)
			(net 1 "GND")
			(pintype "passive")
		)
		(pad "2" smd roundrect
			(at 0.48 0 270)
			(size 0.59 0.64)
			(layers "F.Cu" "F.Paste" "F.Mask")
			(roundrect_rratio 0.25)
			(net 319 "/USB3/~{USBC1_EN_CC}")
			(pintype "passive")
		)
	)
	(footprint "antmicro-footprints:R_0402_1005Metric"
		(layer "F.Cu")
		(at 87.05 114.2 -90)
		(descr "Resistor SMD 0402")
		(tags "resistor SMD 0402")
		(property "Reference" "R293"
			(at -0.84 -0.41 -90)
			(layer "F.SilkS")
			(effects
				(font
					(size 0.7 0.7)
					(thickness 0.15)
				)
				(justify left bottom)
			)
		)
		(property "Value" "R_0R_0402"
			(at 0 1.4 -90)
			(layer "F.Fab")
			(effects
				(font
					(size 0.7 0.7)
					(thickness 0.15)
				)
				(justify left bottom)
			)
		)
		(property "Footprint" "antmicro-footprints:R_0402_1005Metric"
			(at 0 0 -90)
			(layer "F.Fab")
			(hide yes)
			(effects
				(font
					(size 1.27 1.27)
					(thickness 0.15)
				)
			)
		)
		(property "Datasheet" "https://industrial.panasonic.com/cdbs/www-data/pdf/RDA0000/AOA0000C301.pdf"
			(at 0 0 -90)
			(layer "F.Fab")
			(hide yes)
			(effects
				(font
					(size 1.27 1.27)
					(thickness 0.15)
				)
			)
		)
		(property "Author" "Antmicro"
			(at -27.15 201.25 0)
			(layer "F.Fab")
			(hide yes)
			(effects
				(font
					(size 1 1)
					(thickness 0.15)
				)
			)
		)
		(property "Current" "1A"
			(at -27.15 201.25 0)
			(layer "F.Fab")
			(hide yes)
			(effects
				(font
					(size 1 1)
					(thickness 0.15)
				)
			)
		)
		(property "License" "Apache-2.0"
			(at -27.15 201.25 0)
			(layer "F.Fab")
			(hide yes)
			(effects
				(font
					(size 1 1)
					(thickness 0.15)
				)
			)
		)
		(property "MPN" "ERJ2GE0R00X"
			(at -27.15 201.25 0)
			(layer "F.Fab")
			(hide yes)
			(effects
				(font
					(size 1 1)
					(thickness 0.15)
				)
			)
		)
		(property "Manufacturer" "Panasonic"
			(at -27.15 201.25 0)
			(layer "F.Fab")
			(hide yes)
			(effects
				(font
					(size 1 1)
					(thickness 0.15)
				)
			)
		)
		(property "Tolerance" ""
			(at -27.15 201.25 0)
			(layer "F.Fab")
			(hide yes)
			(effects
				(font
					(size 1 1)
					(thickness 0.15)
				)
			)
		)
		(property "Val" "0R"
			(at -27.15 201.25 0)
			(layer "F.Fab")
			(hide yes)
			(effects
				(font
					(size 1 1)
					(thickness 0.15)
				)
			)
		)
		(sheetname "HDMI")
		(sheetfile "hdmi.kicad_sch")
		(attr smd exclude_from_pos_files exclude_from_bom dnp)
		(fp_rect
			(start -0.925 -0.47)
			(end 0.925 0.47)
			(stroke
				(width 0.05)
				(type default)
			)
			(fill none)
			(layer "F.CrtYd")
		)
		(fp_rect
			(start -0.5 -0.25)
			(end 0.5 0.25)
			(stroke
				(width 0.15)
				(type solid)
			)
			(fill none)
			(layer "F.Fab")
		)
		(fp_text user "License: Apache-2.0"
			(at -0.95 5.169 -90)
			(layer "F.Fab")
			(hide yes)
			(effects
				(font
					(size 0.7 0.7)
					(thickness 0.15)
				)
				(justify left bottom)
			)
		)
		(fp_text user "Author: Antmicro"
			(at -0.95 4.169 -90)
			(layer "F.Fab")
			(hide yes)
			(effects
				(font
					(size 0.7 0.7)
					(thickness 0.15)
				)
				(justify left bottom)
			)
		)
		(fp_text user "${REFERENCE}"
			(at -0.95 3.168 -90)
			(layer "F.Fab")
			(hide yes)
			(effects
				(font
					(size 0.7 0.7)
					(thickness 0.15)
				)
				(justify left bottom)
			)
		)
		(pad "1" smd roundrect
			(at -0.48 0 270)
			(size 0.59 0.64)
			(layers "F.Cu" "F.Paste" "F.Mask")
			(roundrect_rratio 0.25)
			(net 576 "/HDMI/HDMI_HPD_5V_R")
			(pintype "passive")
		)
		(pad "2" smd roundrect
			(at 0.48 0 270)
			(size 0.59 0.64)
			(layers "F.Cu" "F.Paste" "F.Mask")
			(roundrect_rratio 0.25)
			(net 529 "/HDMI/HDMI_HPD_5V")
			(pintype "passive")
		)
	)
	(footprint "antmicro-footprints:C_0402_1005Metric"
		(layer "F.Cu")
		(at 137.115 109.05)
		(descr "Capacitor SMD 0402")
		(tags "capacitor SMD 0402")
		(property "Reference" "C105"
			(at -3.615 0.45 0)
			(layer "F.SilkS")
			(effects
				(font
					(size 0.7 0.7)
					(thickness 0.15)
				)
				(justify left bottom)
			)
		)
		(property "Value" "C_1u_0402"
			(at 0 1.4 0)
			(layer "F.Fab")
			(effects
				(font
					(size 0.7 0.7)
					(thickness 0.15)
				)
				(justify left bottom)
			)
		)
		(property "Footprint" "antmicro-footprints:C_0402_1005Metric"
			(at 0 0 0)
			(layer "F.Fab")
			(hide yes)
			(effects
				(font
					(size 1.27 1.27)
					(thickness 0.15)
				)
			)
		)
		(property "Datasheet" "https://product.tdk.com/en/search/capacitor/ceramic/mlcc/info?part_no=C1005X6S1A105K050BC"
			(at 0 0 0)
			(layer "F.Fab")
			(hide yes)
			(effects
				(font
					(size 1.27 1.27)
					(thickness 0.15)
				)
			)
		)
		(property "Author" "Antmicro"
			(at 0 0 0)
			(layer "F.Fab")
			(hide yes)
			(effects
				(font
					(size 1 1)
					(thickness 0.15)
				)
			)
		)
		(property "Dielectric" ""
			(at 0 0 0)
			(layer "F.Fab")
			(hide yes)
			(effects
				(font
					(size 1 1)
					(thickness 0.15)
				)
			)
		)
		(property "License" "Apache-2.0"
			(at 0 0 0)
			(layer "F.Fab")
			(hide yes)
			(effects
				(font
					(size 1 1)
					(thickness 0.15)
				)
			)
		)
		(property "MPN" "C1005X6S1A105K050BC"
			(at 0 0 0)
			(layer "F.Fab")
			(hide yes)
			(effects
				(font
					(size 1 1)
					(thickness 0.15)
				)
			)
		)
		(property "Manufacturer" "TDK"
			(at 0 0 0)
			(layer "F.Fab")
			(hide yes)
			(effects
				(font
					(size 1 1)
					(thickness 0.15)
				)
			)
		)
		(property "Val" "1u"
			(at 0 0 0)
			(layer "F.Fab")
			(hide yes)
			(effects
				(font
					(size 1 1)
					(thickness 0.15)
				)
			)
		)
		(property "Voltage" ""
			(at 0 0 0)
			(layer "F.Fab")
			(hide yes)
			(effects
				(font
					(size 1 1)
					(thickness 0.15)
				)
			)
		)
		(sheetname "Peripherals")
		(sheetfile "peripherals.kicad_sch")
		(attr smd)
		(fp_rect
			(start -0.925 -0.47)
			(end 0.925 0.47)
			(stroke
				(width 0.05)
				(type default)
			)
			(fill none)
			(layer "F.CrtYd")
		)
		(fp_line
			(start -0.494 -0.25)
			(end 0.504 -0.25)
			(stroke
				(width 0.15)
				(type solid)
			)
			(layer "F.Fab")
		)
		(fp_line
			(start -0.494 0.248)
			(end -0.494 -0.25)
			(stroke
				(width 0.15)
				(type solid)
			)
			(layer "F.Fab")
		)
		(fp_line
			(start 0.504 -0.25)
			(end 0.504 0.248)
			(stroke
				(width 0.15)
				(type solid)
			)
			(layer "F.Fab")
		)
		(fp_line
			(start 0.504 0.248)
			(end -0.494 0.248)
			(stroke
				(width 0.15)
				(type solid)
			)
			(layer "F.Fab")
		)
		(fp_text user "License: Apache-2.0"
			(at -0.932 5.17 0)
			(layer "F.Fab")
			(hide yes)
			(effects
				(font
					(size 0.7 0.7)
					(thickness 0.15)
				)
				(justify left bottom)
			)
		)
		(fp_text user "${REFERENCE}"
			(at -0.932 3.168 0)
			(layer "F.Fab")
			(hide yes)
			(effects
				(font
					(size 0.7 0.7)
					(thickness 0.15)
				)
				(justify left bottom)
			)
		)
		(fp_text user "Author: Antmicro"
			(at -0.932 4.17 0)
			(layer "F.Fab")
			(hide yes)
			(effects
				(font
					(size 0.7 0.7)
					(thickness 0.15)
				)
				(justify left bottom)
			)
		)
		(pad "1" smd roundrect
			(at -0.48 0)
			(size 0.59 0.64)
			(layers "F.Cu" "F.Paste" "F.Mask")
			(roundrect_rratio 0.25)
			(net 1 "GND")
			(pintype "passive")
		)
		(pad "2" smd roundrect
			(at 0.48 0)
			(size 0.59 0.64)
			(layers "F.Cu" "F.Paste" "F.Mask")
			(roundrect_rratio 0.25)
			(net 482 "/Peripherals/3V3_CONN")
			(pintype "passive")
		)
	)
	(footprint "antmicro-footprints:R_0402_1005Metric"
		(layer "F.Cu")
		(at 67.67 99.42 90)
		(descr "Resistor SMD 0402")
		(tags "resistor SMD 0402")
		(property "Reference" "R169"
			(at -3.605 0.555 90)
			(layer "F.SilkS")
			(effects
				(font
					(size 0.7 0.7)
					(thickness 0.15)
				)
				(justify left bottom)
			)
		)
		(property "Value" "R_2k7_0402"
			(at -1.011843 1.772047 90)
			(layer "F.Fab")
			(effects
				(font
					(size 0.7 0.7)
					(thickness 0.15)
				)
				(justify left bottom)
			)
		)
		(property "Footprint" "antmicro-footprints:R_0402_1005Metric"
			(at 0 0 90)
			(layer "F.Fab")
			(hide yes)
			(effects
				(font
					(size 1.27 1.27)
					(thickness 0.15)
				)
			)
		)
		(property "Datasheet" "https://www.bourns.com/docs/product-datasheets/cr.pdf"
			(at 0 0 90)
			(layer "F.Fab")
			(hide yes)
			(effects
				(font
					(size 1.27 1.27)
					(thickness 0.15)
				)
			)
		)
		(property "Description" "SMD Chip Resistor, 2.7 kohm, ± 1%, 63 mW, 0402 [1005 Metric], Thick Film, General Purpose"
			(at 0 0 90)
			(layer "F.Fab")
			(hide yes)
			(effects
				(font
					(size 1.27 1.27)
					(thickness 0.15)
				)
			)
		)
		(property "Author" "Antmicro"
			(at 167.09 31.75 0)
			(layer "F.Fab")
			(hide yes)
			(effects
				(font
					(size 1 1)
					(thickness 0.15)
				)
			)
		)
		(property "License" "Apache-2.0"
			(at 167.09 31.75 0)
			(layer "F.Fab")
			(hide yes)
			(effects
				(font
					(size 1 1)
					(thickness 0.15)
				)
			)
		)
		(property "MPN" "CR0402-FX-2701GLF"
			(at 167.09 31.75 0)
			(layer "F.Fab")
			(hide yes)
			(effects
				(font
					(size 1 1)
					(thickness 0.15)
				)
			)
		)
		(property "Manufacturer" "Bourns"
			(at 167.09 31.75 0)
			(layer "F.Fab")
			(hide yes)
			(effects
				(font
					(size 1 1)
					(thickness 0.15)
				)
			)
		)
		(property "Tolerance" "1%"
			(at 167.09 31.75 0)
			(layer "F.Fab")
			(hide yes)
			(effects
				(font
					(size 1 1)
					(thickness 0.15)
				)
			)
		)
		(property "Val" "2k7"
			(at 167.09 31.75 0)
			(layer "F.Fab")
			(hide yes)
			(effects
				(font
					(size 1 1)
					(thickness 0.15)
				)
			)
		)
		(sheetname "Supply")
		(sheetfile "supply.kicad_sch")
		(attr smd)
		(fp_rect
			(start -0.925 -0.47)
			(end 0.925 0.47)
			(stroke
				(width 0.05)
				(type default)
			)
			(fill none)
			(layer "F.CrtYd")
		)
		(fp_rect
			(start -0.5 -0.25)
			(end 0.5 0.25)
			(stroke
				(width 0.15)
				(type solid)
			)
			(fill none)
			(layer "F.Fab")
		)
		(fp_text user "${REFERENCE}"
			(at -0.95 3.168 90)
			(layer "F.Fab")
			(hide yes)
			(effects
				(font
					(size 0.7 0.7)
					(thickness 0.15)
				)
				(justify left bottom)
			)
		)
		(fp_text user "Author: Antmicro"
			(at -0.95 4.169 90)
			(layer "F.Fab")
			(hide yes)
			(effects
				(font
					(size 0.7 0.7)
					(thickness 0.15)
				)
				(justify left bottom)
			)
		)
		(fp_text user "License: Apache-2.0"
			(at -0.95 5.169 90)
			(layer "F.Fab")
			(hide yes)
			(effects
				(font
					(size 0.7 0.7)
					(thickness 0.15)
				)
				(justify left bottom)
			)
		)
		(pad "1" smd roundrect
			(at -0.48 0 90)
			(size 0.59 0.64)
			(layers "F.Cu" "F.Paste" "F.Mask")
			(roundrect_rratio 0.25)
			(net 1 "GND")
			(pintype "passive")
		)
		(pad "2" smd roundrect
			(at 0.48 0 90)
			(size 0.59 0.64)
			(layers "F.Cu" "F.Paste" "F.Mask")
			(roundrect_rratio 0.25)
			(net 712 "/Supply/5V_EN")
			(pintype "passive")
		)
	)
	(footprint "antmicro-footprints:USON-10_2.5x1mm_P0.5mm"
		(layer "F.Cu")
		(at 113.55 116.178749 90)
		(descr "USON-10 2.5x1mm_ Pitch 0.5mm")
		(tags "USON-10 2.5x1mm Pitch 0.5mm")
		(property "Reference" "U21"
			(at 0.878749 -1.05 180)
			(layer "F.SilkS")
			(effects
				(font
					(size 0.7 0.7)
					(thickness 0.15)
				)
				(justify left bottom)
			)
		)
		(property "Value" "TPD4E05U06QDQARQ1"
			(at 0.018 2.499 90)
			(layer "F.Fab")
			(effects
				(font
					(size 0.7 0.7)
					(thickness 0.15)
				)
				(justify left bottom)
			)
		)
		(property "Footprint" "antmicro-footprints:USON-10_2.5x1mm_P0.5mm"
			(at 0 0 90)
			(layer "F.Fab")
			(hide yes)
			(effects
				(font
					(size 1.27 1.27)
					(thickness 0.15)
				)
			)
		)
		(property "Datasheet" "https://www.ti.com/lit/ds/symlink/tpd4e05u06-q1.pdf?HQS=dis-mous-null-mousermode-dsf-pf-null-wwe&ts=1663591265741&ref_url=https%253A%252F%252Fwww.mouser.com%252F"
			(at 0 0 90)
			(layer "F.Fab")
			(hide yes)
			(effects
				(font
					(size 1.27 1.27)
					(thickness 0.15)
				)
			)
		)
		(property "Author" "Antmicro"
			(at 229.728749 2.628749 0)
			(layer "F.Fab")
			(hide yes)
			(effects
				(font
					(size 1 1)
					(thickness 0.15)
				)
			)
		)
		(property "License" "Apache-2.0"
			(at 229.728749 2.628749 0)
			(layer "F.Fab")
			(hide yes)
			(effects
				(font
					(size 1 1)
					(thickness 0.15)
				)
			)
		)
		(property "MPN" "TPD4E05U06QDQARQ1"
			(at 229.728749 2.628749 0)
			(layer "F.Fab")
			(hide yes)
			(effects
				(font
					(size 1 1)
					(thickness 0.15)
				)
			)
		)
		(property "Manufacturer" "Texas Instruments"
			(at 229.728749 2.628749 0)
			(layer "F.Fab")
			(hide yes)
			(effects
				(font
					(size 1 1)
					(thickness 0.15)
				)
			)
		)
		(sheetname "USB3")
		(sheetfile "usb3.kicad_sch")
		(attr smd)
		(fp_line
			(start 0.498 -1.401)
			(end -0.5 -1.401)
			(stroke
				(width 0.15)
				(type solid)
			)
			(layer "F.SilkS")
		)
		(fp_line
			(start 0.498 1.398)
			(end -0.5 1.398)
			(stroke
				(width 0.15)
				(type solid)
			)
			(layer "F.SilkS")
		)
		(fp_circle
			(center -0.68 -1.27)
			(end -0.63 -1.27)
			(stroke
				(width 0.15)
				(type solid)
			)
			(fill solid)
			(layer "F.SilkS")
		)
		(fp_rect
			(start -0.8 -1.5)
			(end 0.8 1.499)
			(stroke
				(width 0.05)
				(type solid)
			)
			(fill none)
			(layer "F.CrtYd")
		)
		(fp_line
			(start 0.498 -1.25)
			(end -0.25 -1.25)
			(stroke
				(width 0.15)
				(type solid)
			)
			(layer "F.Fab")
		)
		(fp_line
			(start 0.498 -1.25)
			(end 0.498 1.249)
			(stroke
				(width 0.15)
				(type solid)
			)
			(layer "F.Fab")
		)
		(fp_line
			(start -0.25 -1.25)
			(end -0.5 -1)
			(stroke
				(width 0.15)
				(type solid)
			)
			(layer "F.Fab")
		)
		(fp_line
			(start -0.5 -1)
			(end -0.5 1.249)
			(stroke
				(width 0.15)
				(type solid)
			)
			(layer "F.Fab")
		)
		(fp_line
			(start -0.5 1.249)
			(end 0.498 1.249)
			(stroke
				(width 0.15)
				(type solid)
			)
			(layer "F.Fab")
		)
		(fp_text user "${REFERENCE}"
			(at -0.802 4.498 90)
			(layer "F.Fab")
			(hide yes)
			(effects
				(font
					(size 0.7 0.7)
					(thickness 0.15)
				)
				(justify left bottom)
			)
		)
		(fp_text user "Author: Antmicro"
			(at -0.802 5.7 90)
			(layer "F.Fab")
			(hide yes)
			(effects
				(font
					(size 0.7 0.7)
					(thickness 0.15)
				)
				(justify left bottom)
			)
		)
		(fp_text user "License: Apache-2.0"
			(at -0.802 6.9 90)
			(layer "F.Fab")
			(hide yes)
			(effects
				(font
					(size 0.7 0.7)
					(thickness 0.15)
				)
				(justify left bottom)
			)
		)
		(pad "1" smd roundrect
			(at -0.387 -1)
			(size 0.25 0.55)
			(layers "F.Cu" "F.Paste" "F.Mask")
			(roundrect_rratio 0.25)
			(net 282 "/USB3/USBC1_CC1")
			(pintype "passive")
		)
		(pad "2" smd roundrect
			(at -0.387 -0.5)
			(size 0.25 0.55)
			(layers "F.Cu" "F.Paste" "F.Mask")
			(roundrect_rratio 0.25)
			(net 433 "USB0_D_P")
			(pintype "passive")
		)
		(pad "3" smd roundrect
			(at -0.387 0)
			(size 0.4 0.55)
			(layers "F.Cu" "F.Paste" "F.Mask")
			(roundrect_rratio 0.25)
			(net 1 "GND")
			(pintype "power_in")
		)
		(pad "4" smd roundrect
			(at -0.387 0.498)
			(size 0.25 0.55)
			(layers "F.Cu" "F.Paste" "F.Mask")
			(roundrect_rratio 0.25)
			(net 40 "USB0_D_N")
			(pintype "passive")
		)
		(pad "5" smd roundrect
			(at -0.387 0.998)
			(size 0.25 0.55)
			(layers "F.Cu" "F.Paste" "F.Mask")
			(roundrect_rratio 0.25)
			(net 283 "/USB3/USBC1_CC2")
			(pintype "passive")
		)
		(pad "6" smd roundrect
			(at 0.385 0.998)
			(size 0.25 0.55)
			(layers "F.Cu" "F.Paste" "F.Mask")
			(roundrect_rratio 0.25)
			(net 283 "/USB3/USBC1_CC2")
			(pintype "passive")
		)
		(pad "7" smd roundrect
			(at 0.385 0.498)
			(size 0.25 0.55)
			(layers "F.Cu" "F.Paste" "F.Mask")
			(roundrect_rratio 0.25)
			(net 40 "USB0_D_N")
			(pintype "passive")
		)
		(pad "8" smd roundrect
			(at 0.385 0)
			(size 0.4 0.55)
			(layers "F.Cu" "F.Paste" "F.Mask")
			(roundrect_rratio 0.25)
			(net 1 "GND")
			(pintype "passive")
		)
		(pad "9" smd roundrect
			(at 0.385 -0.5)
			(size 0.25 0.55)
			(layers "F.Cu" "F.Paste" "F.Mask")
			(roundrect_rratio 0.25)
			(net 433 "USB0_D_P")
			(pintype "passive")
		)
		(pad "10" smd roundrect
			(at 0.385 -1)
			(size 0.25 0.55)
			(layers "F.Cu" "F.Paste" "F.Mask")
			(roundrect_rratio 0.25)
			(net 282 "/USB3/USBC1_CC1")
			(pintype "passive")
		)
	)
	(footprint "antmicro-footprints:Mech_M2_2242_H2.5mm"
		(layer "F.Cu")
		(at 79.25 95.15 90)
		(property "Reference" "A2"
			(at -0.001 -12.11 90)
			(layer "F.SilkS")
			(hide yes)
			(effects
				(font
					(size 0.7 0.7)
					(thickness 0.15)
				)
				(justify right bottom)
			)
		)
		(property "Value" "Mech_M2_2242_H2.5mm"
			(at -0.001 6.857 90)
			(layer "F.Fab")
			(effects
				(font
					(size 0.7 0.7)
					(thickness 0.15)
				)
				(justify right bottom)
			)
		)
		(property "Footprint" "antmicro-footprints:Mech_M2_2242_H2.5mm"
			(at 0 0 90)
			(layer "F.Fab")
			(hide yes)
			(effects
				(font
					(size 1.27 1.27)
					(thickness 0.15)
				)
			)
		)
		(property "MPN" ""
			(at 0 0 90)
			(unlocked yes)
			(layer "F.Fab")
			(hide yes)
			(effects
				(font
					(size 1 1)
					(thickness 0.15)
				)
			)
		)
		(property "Manufacturer" ""
			(at 0 0 90)
			(unlocked yes)
			(layer "F.Fab")
			(hide yes)
			(effects
				(font
					(size 1 1)
					(thickness 0.15)
				)
			)
		)
		(property "Author" "Antmicro"
			(at 0 0 90)
			(unlocked yes)
			(layer "F.Fab")
			(hide yes)
			(effects
				(font
					(size 1 1)
					(thickness 0.15)
				)
			)
		)
		(property "License" "Apache-2.0"
			(at 0 0 90)
			(unlocked yes)
			(layer "F.Fab")
			(hide yes)
			(effects
				(font
					(size 1 1)
					(thickness 0.15)
				)
			)
		)
		(sheetname "M.2")
		(sheetfile "m-2.kicad_sch")
		(attr through_hole exclude_from_pos_files exclude_from_bom allow_missing_courtyard
			dnp
		)
		(fp_text user "${REFERENCE}"
			(at -11 66.248 90)
			(layer "F.Fab")
			(hide yes)
			(effects
				(font
					(size 0.7 0.7)
					(thickness 0.15)
				)
				(justify left bottom)
			)
		)
		(fp_text user "Author: Antmicro"
			(at -11 67.45 90)
			(layer "F.Fab")
			(hide yes)
			(effects
				(font
					(size 0.7 0.7)
					(thickness 0.15)
				)
				(justify left bottom)
			)
		)
		(fp_text user "License: Apache-2.0"
			(at -11 68.65 90)
			(layer "F.Fab")
			(hide yes)
			(effects
				(font
					(size 0.7 0.7)
					(thickness 0.15)
				)
				(justify left bottom)
			)
		)
	)
	(footprint "antmicro-footprints:R_0402_1005Metric"
		(layer "F.Cu")
		(at 66.5 119 90)
		(descr "Resistor SMD 0402")
		(tags "resistor SMD 0402")
		(property "Reference" "R99"
			(at -2.95 0.45 90)
			(layer "F.SilkS")
			(effects
				(font
					(size 0.7 0.7)
					(thickness 0.15)
				)
				(justify left bottom)
			)
		)
		(property "Value" "R_10k_0402"
			(at 0 1.4 90)
			(layer "F.Fab")
			(effects
				(font
					(size 0.7 0.7)
					(thickness 0.15)
				)
				(justify left bottom)
			)
		)
		(property "Footprint" "antmicro-footprints:R_0402_1005Metric"
			(at 0 0 90)
			(layer "F.Fab")
			(hide yes)
			(effects
				(font
					(size 1.27 1.27)
					(thickness 0.15)
				)
			)
		)
		(property "Datasheet" "https://www.bourns.com/docs/product-datasheets/cr.pdf"
			(at 0 0 90)
			(layer "F.Fab")
			(hide yes)
			(effects
				(font
					(size 1.27 1.27)
					(thickness 0.15)
				)
			)
		)
		(property "Author" "Antmicro"
			(at 185.5 52.5 0)
			(layer "F.Fab")
			(hide yes)
			(effects
				(font
					(size 1 1)
					(thickness 0.15)
				)
			)
		)
		(property "License" "Apache-2.0"
			(at 185.5 52.5 0)
			(layer "F.Fab")
			(hide yes)
			(effects
				(font
					(size 1 1)
					(thickness 0.15)
				)
			)
		)
		(property "MPN" "CR0402-FX-1002GLF"
			(at 185.5 52.5 0)
			(layer "F.Fab")
			(hide yes)
			(effects
				(font
					(size 1 1)
					(thickness 0.15)
				)
			)
		)
		(property "Manufacturer" "Bourns"
			(at 185.5 52.5 0)
			(layer "F.Fab")
			(hide yes)
			(effects
				(font
					(size 1 1)
					(thickness 0.15)
				)
			)
		)
		(property "Tolerance" "1%"
			(at 185.5 52.5 0)
			(layer "F.Fab")
			(hide yes)
			(effects
				(font
					(size 1 1)
					(thickness 0.15)
				)
			)
		)
		(property "Val" "10k"
			(at 185.5 52.5 0)
			(layer "F.Fab")
			(hide yes)
			(effects
				(font
					(size 1 1)
					(thickness 0.15)
				)
			)
		)
		(sheetname "USB Debug, DP")
		(sheetfile "usb.kicad_sch")
		(attr smd)
		(fp_rect
			(start -0.925 -0.47)
			(end 0.925 0.47)
			(stroke
				(width 0.05)
				(type default)
			)
			(fill none)
			(layer "F.CrtYd")
		)
		(fp_rect
			(start -0.5 -0.25)
			(end 0.5 0.25)
			(stroke
				(width 0.15)
				(type solid)
			)
			(fill none)
			(layer "F.Fab")
		)
		(fp_text user "License: Apache-2.0"
			(at -0.95 5.169 90)
			(layer "F.Fab")
			(hide yes)
			(effects
				(font
					(size 0.7 0.7)
					(thickness 0.15)
				)
				(justify left bottom)
			)
		)
		(fp_text user "Author: Antmicro"
			(at -0.95 4.169 90)
			(layer "F.Fab")
			(hide yes)
			(effects
				(font
					(size 0.7 0.7)
					(thickness 0.15)
				)
				(justify left bottom)
			)
		)
		(fp_text user "${REFERENCE}"
			(at -0.95 3.168 90)
			(layer "F.Fab")
			(hide yes)
			(effects
				(font
					(size 0.7 0.7)
					(thickness 0.15)
				)
				(justify left bottom)
			)
		)
		(pad "1" smd roundrect
			(at -0.48 0 90)
			(size 0.59 0.64)
			(layers "F.Cu" "F.Paste" "F.Mask")
			(roundrect_rratio 0.25)
			(net 1 "GND")
			(pintype "passive")
		)
		(pad "2" smd roundrect
			(at 0.48 0 90)
			(size 0.59 0.64)
			(layers "F.Cu" "F.Paste" "F.Mask")
			(roundrect_rratio 0.25)
			(net 673 "Net-(U12-EN)")
			(pintype "passive")
		)
	)
	(footprint "antmicro-footprints:R_0402_1005Metric"
		(layer "F.Cu")
		(at 110.8 102.65 -90)
		(descr "Resistor SMD 0402")
		(tags "resistor SMD 0402")
		(property "Reference" "R124"
			(at -0.85 -0.06 -90)
			(layer "F.SilkS")
			(effects
				(font
					(size 0.7 0.7)
					(thickness 0.15)
				)
				(justify left bottom)
			)
		)
		(property "Value" "R_0R_0402"
			(at 0 1.4 -90)
			(layer "F.Fab")
			(effects
				(font
					(size 0.7 0.7)
					(thickness 0.15)
				)
				(justify left bottom)
			)
		)
		(property "Footprint" "antmicro-footprints:R_0402_1005Metric"
			(at 0 0 -90)
			(layer "F.Fab")
			(hide yes)
			(effects
				(font
					(size 1.27 1.27)
					(thickness 0.15)
				)
			)
		)
		(property "Datasheet" "https://industrial.panasonic.com/cdbs/www-data/pdf/RDA0000/AOA0000C301.pdf"
			(at 0 0 -90)
			(layer "F.Fab")
			(hide yes)
			(effects
				(font
					(size 1.27 1.27)
					(thickness 0.15)
				)
			)
		)
		(property "Author" "Antmicro"
			(at 8.15 213.45 0)
			(layer "F.Fab")
			(hide yes)
			(effects
				(font
					(size 1 1)
					(thickness 0.15)
				)
			)
		)
		(property "Current" "1A"
			(at 8.15 213.45 0)
			(layer "F.Fab")
			(hide yes)
			(effects
				(font
					(size 1 1)
					(thickness 0.15)
				)
			)
		)
		(property "License" "Apache-2.0"
			(at 8.15 213.45 0)
			(layer "F.Fab")
			(hide yes)
			(effects
				(font
					(size 1 1)
					(thickness 0.15)
				)
			)
		)
		(property "MPN" "ERJ2GE0R00X"
			(at 8.15 213.45 0)
			(layer "F.Fab")
			(hide yes)
			(effects
				(font
					(size 1 1)
					(thickness 0.15)
				)
			)
		)
		(property "Manufacturer" "Panasonic"
			(at 8.15 213.45 0)
			(layer "F.Fab")
			(hide yes)
			(effects
				(font
					(size 1 1)
					(thickness 0.15)
				)
			)
		)
		(property "Tolerance" ""
			(at 8.15 213.45 0)
			(layer "F.Fab")
			(hide yes)
			(effects
				(font
					(size 1 1)
					(thickness 0.15)
				)
			)
		)
		(property "Val" "0R"
			(at 8.15 213.45 0)
			(layer "F.Fab")
			(hide yes)
			(effects
				(font
					(size 1 1)
					(thickness 0.15)
				)
			)
		)
		(sheetname "USB3")
		(sheetfile "usb3.kicad_sch")
		(attr smd exclude_from_pos_files exclude_from_bom dnp)
		(fp_rect
			(start -0.925 -0.47)
			(end 0.925 0.47)
			(stroke
				(width 0.05)
				(type default)
			)
			(fill none)
			(layer "F.CrtYd")
		)
		(fp_rect
			(start -0.5 -0.25)
			(end 0.5 0.25)
			(stroke
				(width 0.15)
				(type solid)
			)
			(fill none)
			(layer "F.Fab")
		)
		(fp_text user "Author: Antmicro"
			(at -0.95 4.169 -90)
			(layer "F.Fab")
			(hide yes)
			(effects
				(font
					(size 0.7 0.7)
					(thickness 0.15)
				)
				(justify left bottom)
			)
		)
		(fp_text user "License: Apache-2.0"
			(at -0.95 5.169 -90)
			(layer "F.Fab")
			(hide yes)
			(effects
				(font
					(size 0.7 0.7)
					(thickness 0.15)
				)
				(justify left bottom)
			)
		)
		(fp_text user "${REFERENCE}"
			(at -0.95 3.168 -90)
			(layer "F.Fab")
			(hide yes)
			(effects
				(font
					(size 0.7 0.7)
					(thickness 0.15)
				)
				(justify left bottom)
			)
		)
		(pad "1" smd roundrect
			(at -0.48 0 270)
			(size 0.59 0.64)
			(layers "F.Cu" "F.Paste" "F.Mask")
			(roundrect_rratio 0.25)
			(net 251 "SYS_SDA")
			(pintype "passive")
		)
		(pad "2" smd roundrect
			(at 0.48 0 270)
			(size 0.59 0.64)
			(layers "F.Cu" "F.Paste" "F.Mask")
			(roundrect_rratio 0.25)
			(net 362 "/USB3/USBC1_I2C_SDA")
			(pintype "passive")
		)
	)
	(footprint "antmicro-footprints:C_0402_1005Metric"
		(layer "F.Cu")
		(at 147.3 119.3)
		(descr "Capacitor SMD 0402")
		(tags "capacitor SMD 0402")
		(property "Reference" "C115"
			(at -1.4 1.3 0)
			(layer "F.SilkS")
			(effects
				(font
					(size 0.7 0.7)
					(thickness 0.15)
				)
				(justify left bottom)
			)
		)
		(property "Value" "C_1u_0402"
			(at 0 1.4 0)
			(layer "F.Fab")
			(effects
				(font
					(size 0.7 0.7)
					(thickness 0.15)
				)
				(justify left bottom)
			)
		)
		(property "Footprint" "antmicro-footprints:C_0402_1005Metric"
			(at 0 0 0)
			(layer "F.Fab")
			(hide yes)
			(effects
				(font
					(size 1.27 1.27)
					(thickness 0.15)
				)
			)
		)
		(property "Datasheet" "https://product.tdk.com/en/search/capacitor/ceramic/mlcc/info?part_no=C1005X6S1A105K050BC"
			(at 0 0 0)
			(layer "F.Fab")
			(hide yes)
			(effects
				(font
					(size 1.27 1.27)
					(thickness 0.15)
				)
			)
		)
		(property "Author" "Antmicro"
			(at 0 0 0)
			(layer "F.Fab")
			(hide yes)
			(effects
				(font
					(size 1 1)
					(thickness 0.15)
				)
			)
		)
		(property "Dielectric" ""
			(at 0 0 0)
			(layer "F.Fab")
			(hide yes)
			(effects
				(font
					(size 1 1)
					(thickness 0.15)
				)
			)
		)
		(property "License" "Apache-2.0"
			(at 0 0 0)
			(layer "F.Fab")
			(hide yes)
			(effects
				(font
					(size 1 1)
					(thickness 0.15)
				)
			)
		)
		(property "MPN" "C1005X6S1A105K050BC"
			(at 0 0 0)
			(layer "F.Fab")
			(hide yes)
			(effects
				(font
					(size 1 1)
					(thickness 0.15)
				)
			)
		)
		(property "Manufacturer" "TDK"
			(at 0 0 0)
			(layer "F.Fab")
			(hide yes)
			(effects
				(font
					(size 1 1)
					(thickness 0.15)
				)
			)
		)
		(property "Val" "1u"
			(at 0 0 0)
			(layer "F.Fab")
			(hide yes)
			(effects
				(font
					(size 1 1)
					(thickness 0.15)
				)
			)
		)
		(property "Voltage" ""
			(at 0 0 0)
			(layer "F.Fab")
			(hide yes)
			(effects
				(font
					(size 1 1)
					(thickness 0.15)
				)
			)
		)
		(sheetname "Peripherals")
		(sheetfile "peripherals.kicad_sch")
		(attr smd)
		(fp_rect
			(start -0.925 -0.47)
			(end 0.925 0.47)
			(stroke
				(width 0.05)
				(type default)
			)
			(fill none)
			(layer "F.CrtYd")
		)
		(fp_line
			(start -0.494 -0.25)
			(end 0.504 -0.25)
			(stroke
				(width 0.15)
				(type solid)
			)
			(layer "F.Fab")
		)
		(fp_line
			(start -0.494 0.248)
			(end -0.494 -0.25)
			(stroke
				(width 0.15)
				(type solid)
			)
			(layer "F.Fab")
		)
		(fp_line
			(start 0.504 -0.25)
			(end 0.504 0.248)
			(stroke
				(width 0.15)
				(type solid)
			)
			(layer "F.Fab")
		)
		(fp_line
			(start 0.504 0.248)
			(end -0.494 0.248)
			(stroke
				(width 0.15)
				(type solid)
			)
			(layer "F.Fab")
		)
		(fp_text user "License: Apache-2.0"
			(at -0.932 5.17 0)
			(layer "F.Fab")
			(hide yes)
			(effects
				(font
					(size 0.7 0.7)
					(thickness 0.15)
				)
				(justify left bottom)
			)
		)
		(fp_text user "${REFERENCE}"
			(at -0.932 3.168 0)
			(layer "F.Fab")
			(hide yes)
			(effects
				(font
					(size 0.7 0.7)
					(thickness 0.15)
				)
				(justify left bottom)
			)
		)
		(fp_text user "Author: Antmicro"
			(at -0.932 4.17 0)
			(layer "F.Fab")
			(hide yes)
			(effects
				(font
					(size 0.7 0.7)
					(thickness 0.15)
				)
				(justify left bottom)
			)
		)
		(pad "1" smd roundrect
			(at -0.48 0)
			(size 0.59 0.64)
			(layers "F.Cu" "F.Paste" "F.Mask")
			(roundrect_rratio 0.25)
			(net 485 "/Peripherals/VCC_CONN")
			(pintype "passive")
		)
		(pad "2" smd roundrect
			(at 0.48 0)
			(size 0.59 0.64)
			(layers "F.Cu" "F.Paste" "F.Mask")
			(roundrect_rratio 0.25)
			(net 1 "GND")
			(pintype "passive")
		)
	)
	(footprint "antmicro-footprints:R_0402_1005Metric"
		(layer "F.Cu")
		(at 107.64 124.8 90)
		(descr "Resistor SMD 0402")
		(tags "resistor SMD 0402")
		(property "Reference" "R140"
			(at 2.725 0.435 90)
			(layer "F.SilkS")
			(effects
				(font
					(size 0.7 0.7)
					(thickness 0.15)
				)
				(justify left bottom)
			)
		)
		(property "Value" "R_470R_0402"
			(at 0 1.4 90)
			(layer "F.Fab")
			(effects
				(font
					(size 0.7 0.7)
					(thickness 0.15)
				)
				(justify left bottom)
			)
		)
		(property "Footprint" "antmicro-footprints:R_0402_1005Metric"
			(at 0 0 90)
			(layer "F.Fab")
			(hide yes)
			(effects
				(font
					(size 1.27 1.27)
					(thickness 0.15)
				)
			)
		)
		(property "Datasheet" "https://www.bourns.com/docs/product-datasheets/cr.pdf"
			(at 0 0 90)
			(layer "F.Fab")
			(hide yes)
			(effects
				(font
					(size 1.27 1.27)
					(thickness 0.15)
				)
			)
		)
		(property "Author" "Antmicro"
			(at 232.44 17.16 0)
			(layer "F.Fab")
			(hide yes)
			(effects
				(font
					(size 1 1)
					(thickness 0.15)
				)
			)
		)
		(property "License" "Apache-2.0"
			(at 232.44 17.16 0)
			(layer "F.Fab")
			(hide yes)
			(effects
				(font
					(size 1 1)
					(thickness 0.15)
				)
			)
		)
		(property "MPN" "CR0402-FX-4700GLF"
			(at 232.44 17.16 0)
			(layer "F.Fab")
			(hide yes)
			(effects
				(font
					(size 1 1)
					(thickness 0.15)
				)
			)
		)
		(property "Manufacturer" "Bourns"
			(at 232.44 17.16 0)
			(layer "F.Fab")
			(hide yes)
			(effects
				(font
					(size 1 1)
					(thickness 0.15)
				)
			)
		)
		(property "Tolerance" "1%"
			(at 232.44 17.16 0)
			(layer "F.Fab")
			(hide yes)
			(effects
				(font
					(size 1 1)
					(thickness 0.15)
				)
			)
		)
		(property "Val" "470R"
			(at 232.44 17.16 0)
			(layer "F.Fab")
			(hide yes)
			(effects
				(font
					(size 1 1)
					(thickness 0.15)
				)
			)
		)
		(sheetname "USB3")
		(sheetfile "usb3.kicad_sch")
		(attr smd)
		(fp_rect
			(start -0.925 -0.47)
			(end 0.925 0.47)
			(stroke
				(width 0.05)
				(type default)
			)
			(fill none)
			(layer "F.CrtYd")
		)
		(fp_rect
			(start -0.5 -0.25)
			(end 0.5 0.25)
			(stroke
				(width 0.15)
				(type solid)
			)
			(fill none)
			(layer "F.Fab")
		)
		(fp_text user "${REFERENCE}"
			(at -0.95 3.168 90)
			(layer "F.Fab")
			(hide yes)
			(effects
				(font
					(size 0.7 0.7)
					(thickness 0.15)
				)
				(justify left bottom)
			)
		)
		(fp_text user "License: Apache-2.0"
			(at -0.95 5.169 90)
			(layer "F.Fab")
			(hide yes)
			(effects
				(font
					(size 0.7 0.7)
					(thickness 0.15)
				)
				(justify left bottom)
			)
		)
		(fp_text user "Author: Antmicro"
			(at -0.95 4.169 90)
			(layer "F.Fab")
			(hide yes)
			(effects
				(font
					(size 0.7 0.7)
					(thickness 0.15)
				)
				(justify left bottom)
			)
		)
		(pad "1" smd roundrect
			(at -0.48 0 90)
			(size 0.59 0.64)
			(layers "F.Cu" "F.Paste" "F.Mask")
			(roundrect_rratio 0.25)
			(net 150 "Net-(D11-A)")
			(pintype "passive")
		)
		(pad "2" smd roundrect
			(at 0.48 0 90)
			(size 0.59 0.64)
			(layers "F.Cu" "F.Paste" "F.Mask")
			(roundrect_rratio 0.25)
			(net 270 "/USB3/USBC1_VBUS")
			(pintype "passive")
		)
	)
	(footprint "antmicro-footprints:C_0402_1005Metric"
		(layer "F.Cu")
		(at 60.7 109.4 -90)
		(descr "Capacitor SMD 0402")
		(tags "capacitor SMD 0402")
		(property "Reference" "C45"
			(at 1.15 0.35 -90)
			(layer "F.SilkS")
			(effects
				(font
					(size 0.7 0.7)
					(thickness 0.15)
				)
				(justify left bottom)
			)
		)
		(property "Value" "C_100n_0402"
			(at 0 1.4 -90)
			(layer "F.Fab")
			(effects
				(font
					(size 0.7 0.7)
					(thickness 0.15)
				)
				(justify left bottom)
			)
		)
		(property "Footprint" "antmicro-footprints:C_0402_1005Metric"
			(at 0 0 -90)
			(layer "F.Fab")
			(hide yes)
			(effects
				(font
					(size 1.27 1.27)
					(thickness 0.15)
				)
			)
		)
		(property "Datasheet" "https://www.murata.com/products/productdetail?partno=GRM155R61H104KE14%23"
			(at 0 0 -90)
			(layer "F.Fab")
			(hide yes)
			(effects
				(font
					(size 1.27 1.27)
					(thickness 0.15)
				)
			)
		)
		(property "Author" "Antmicro"
			(at -48.7 170.1 0)
			(layer "F.Fab")
			(hide yes)
			(effects
				(font
					(size 1 1)
					(thickness 0.15)
				)
			)
		)
		(property "Dielectric" "X5R"
			(at -48.7 170.1 0)
			(layer "F.Fab")
			(hide yes)
			(effects
				(font
					(size 1 1)
					(thickness 0.15)
				)
			)
		)
		(property "License" "Apache-2.0"
			(at -48.7 170.1 0)
			(layer "F.Fab")
			(hide yes)
			(effects
				(font
					(size 1 1)
					(thickness 0.15)
				)
			)
		)
		(property "MPN" "GRM155R61H104KE14D"
			(at -48.7 170.1 0)
			(layer "F.Fab")
			(hide yes)
			(effects
				(font
					(size 1 1)
					(thickness 0.15)
				)
			)
		)
		(property "Manufacturer" "Murata"
			(at -48.7 170.1 0)
			(layer "F.Fab")
			(hide yes)
			(effects
				(font
					(size 1 1)
					(thickness 0.15)
				)
			)
		)
		(property "Val" "100n"
			(at -48.7 170.1 0)
			(layer "F.Fab")
			(hide yes)
			(effects
				(font
					(size 1 1)
					(thickness 0.15)
				)
			)
		)
		(property "Voltage" "50V"
			(at -48.7 170.1 0)
			(layer "F.Fab")
			(hide yes)
			(effects
				(font
					(size 1 1)
					(thickness 0.15)
				)
			)
		)
		(sheetname "USB Debug, DP")
		(sheetfile "usb.kicad_sch")
		(attr smd)
		(fp_rect
			(start -0.925 -0.47)
			(end 0.925 0.47)
			(stroke
				(width 0.05)
				(type default)
			)
			(fill none)
			(layer "F.CrtYd")
		)
		(fp_line
			(start -0.494 0.248)
			(end -0.494 -0.25)
			(stroke
				(width 0.15)
				(type solid)
			)
			(layer "F.Fab")
		)
		(fp_line
			(start 0.504 0.248)
			(end -0.494 0.248)
			(stroke
				(width 0.15)
				(type solid)
			)
			(layer "F.Fab")
		)
		(fp_line
			(start -0.494 -0.25)
			(end 0.504 -0.25)
			(stroke
				(width 0.15)
				(type solid)
			)
			(layer "F.Fab")
		)
		(fp_line
			(start 0.504 -0.25)
			(end 0.504 0.248)
			(stroke
				(width 0.15)
				(type solid)
			)
			(layer "F.Fab")
		)
		(fp_text user "Author: Antmicro"
			(at -0.932 4.17 -90)
			(layer "F.Fab")
			(hide yes)
			(effects
				(font
					(size 0.7 0.7)
					(thickness 0.15)
				)
				(justify left bottom)
			)
		)
		(fp_text user "${REFERENCE}"
			(at -0.932 3.168 -90)
			(layer "F.Fab")
			(hide yes)
			(effects
				(font
					(size 0.7 0.7)
					(thickness 0.15)
				)
				(justify left bottom)
			)
		)
		(fp_text user "License: Apache-2.0"
			(at -0.932 5.17 -90)
			(layer "F.Fab")
			(hide yes)
			(effects
				(font
					(size 0.7 0.7)
					(thickness 0.15)
				)
				(justify left bottom)
			)
		)
		(pad "1" smd roundrect
			(at -0.48 0 270)
			(size 0.59 0.64)
			(layers "F.Cu" "F.Paste" "F.Mask")
			(roundrect_rratio 0.25)
			(net 99 "+5V")
			(pintype "passive")
		)
		(pad "2" smd roundrect
			(at 0.48 0 270)
			(size 0.59 0.64)
			(layers "F.Cu" "F.Paste" "F.Mask")
			(roundrect_rratio 0.25)
			(net 1 "GND")
			(pintype "passive")
		)
	)
	(footprint "antmicro-footprints:TP_SMD_0.75mm"
		(layer "F.Cu")
		(at 102.95 86.925 180)
		(property "Reference" "TP21"
			(at -0.175 -0.4508 180)
			(layer "F.SilkS")
			(effects
				(font
					(size 0.7 0.7)
					(thickness 0.15)
				)
				(justify left bottom)
			)
		)
		(property "Value" "TP_0.75mm_SMD"
			(at 0 1.2 180)
			(layer "F.Fab")
			(effects
				(font
					(size 0.7 0.7)
					(thickness 0.15)
				)
				(justify left bottom)
			)
		)
		(property "Footprint" "antmicro-footprints:TP_SMD_0.75mm"
			(at 0 0 180)
			(layer "F.Fab")
			(hide yes)
			(effects
				(font
					(size 1.27 1.27)
					(thickness 0.15)
				)
			)
		)
		(property "Author" "Antmicro"
			(at 205.9 173.85 0)
			(layer "F.Fab")
			(hide yes)
			(effects
				(font
					(size 1 1)
					(thickness 0.15)
				)
			)
		)
		(property "License" "Apache-2.0"
			(at 205.9 173.85 0)
			(layer "F.Fab")
			(hide yes)
			(effects
				(font
					(size 1 1)
					(thickness 0.15)
				)
			)
		)
		(property "MPN" ""
			(at 205.9 173.85 0)
			(layer "F.Fab")
			(hide yes)
			(effects
				(font
					(size 1 1)
					(thickness 0.15)
				)
			)
		)
		(property "Manufacturer" ""
			(at 205.9 173.85 0)
			(layer "F.Fab")
			(hide yes)
			(effects
				(font
					(size 1 1)
					(thickness 0.15)
				)
			)
		)
		(sheetname "HDMI")
		(sheetfile "hdmi.kicad_sch")
		(attr exclude_from_pos_files exclude_from_bom)
		(fp_circle
			(center 0 0)
			(end 0.475 0)
			(stroke
				(width 0.05)
				(type default)
			)
			(fill none)
			(layer "F.CrtYd")
		)
		(fp_text user "Author: Antmicro"
			(at -0.4 3.901 180)
			(layer "F.Fab")
			(hide yes)
			(effects
				(font
					(size 0.7 0.7)
					(thickness 0.15)
				)
				(justify left bottom)
			)
		)
		(fp_text user "License: Apache-2.0"
			(at -0.4 5.101 180)
			(layer "F.Fab")
			(hide yes)
			(effects
				(font
					(size 0.7 0.7)
					(thickness 0.15)
				)
				(justify left bottom)
			)
		)
		(fp_text user "${REFERENCE}"
			(at -0.4 2.7 180)
			(layer "F.Fab")
			(hide yes)
			(effects
				(font
					(size 0.7 0.7)
					(thickness 0.15)
				)
				(justify left bottom)
			)
		)
		(pad "1" smd circle
			(at 0 0 180)
			(size 0.75 0.75)
			(layers "F.Cu" "F.Mask")
			(net 428 "DP1_HPD")
			(pinfunction "1")
			(pintype "passive")
		)
	)
	(footprint "antmicro-footprints:LED_0603_1608Metric_G"
		(layer "F.Cu")
		(at 68.8 127.15 90)
		(descr "LED SMD 0603 Green")
		(tags "LED SMD 0603 Green")
		(property "Reference" "D9"
			(at -1.175 -2 180)
			(layer "F.SilkS")
			(effects
				(font
					(size 0.7 0.7)
					(thickness 0.15)
				)
				(justify left bottom)
			)
		)
		(property "Value" "LED_G_0603_LTST-C190GKT"
			(at 2.2 0.8 90)
			(layer "F.Fab")
			(effects
				(font
					(size 0.7 0.7)
					(thickness 0.15)
				)
				(justify left bottom)
			)
		)
		(property "Footprint" "antmicro-footprints:LED_0603_1608Metric_G"
			(at 0 0 90)
			(layer "F.Fab")
			(hide yes)
			(effects
				(font
					(size 1.27 1.27)
					(thickness 0.15)
				)
			)
		)
		(property "Datasheet" "https://media.digikey.com/pdf/Data%20Sheets/Lite-On%20PDFs/LTST-C190GKT.pdf"
			(at 0 0 90)
			(layer "F.Fab")
			(hide yes)
			(effects
				(font
					(size 1.27 1.27)
					(thickness 0.15)
				)
			)
		)
		(property "Author" "Antmicro"
			(at 195.95 58.35 0)
			(layer "F.Fab")
			(hide yes)
			(effects
				(font
					(size 1 1)
					(thickness 0.15)
				)
			)
		)
		(property "Color" "Green"
			(at 195.95 58.35 0)
			(layer "F.Fab")
			(hide yes)
			(effects
				(font
					(size 1 1)
					(thickness 0.15)
				)
			)
		)
		(property "License" "Apache-2.0"
			(at 195.95 58.35 0)
			(layer "F.Fab")
			(hide yes)
			(effects
				(font
					(size 1 1)
					(thickness 0.15)
				)
			)
		)
		(property "MPN" "LTST-C190GKT"
			(at 195.95 58.35 0)
			(layer "F.Fab")
			(hide yes)
			(effects
				(font
					(size 1 1)
					(thickness 0.15)
				)
			)
		)
		(property "Manufacturer" "Lite-On"
			(at 195.95 58.35 0)
			(layer "F.Fab")
			(hide yes)
			(effects
				(font
					(size 1 1)
					(thickness 0.15)
				)
			)
		)
		(sheetname "USB Debug, DP")
		(sheetfile "usb.kicad_sch")
		(attr smd)
		(fp_line
			(start 0.22 -0.35)
			(end -0.22 -0.35)
			(stroke
				(width 0.15)
				(type solid)
			)
			(layer "F.SilkS")
		)
		(fp_line
			(start -1.18 -0.319)
			(end -1.18 0.321)
			(stroke
				(width 0.15)
				(type solid)
			)
			(layer "F.SilkS")
		)
		(fp_line
			(start 0.105328 0.001008)
			(end 0.24 0.001)
			(stroke
				(width 0.1)
				(type solid)
			)
			(layer "F.SilkS")
		)
		(fp_line
			(start -0.094672 0.001008)
			(end 0.105328 -0.198992)
			(stroke
				(width 0.1)
				(type solid)
			)
			(layer "F.SilkS")
		)
		(fp_line
			(start -0.094672 0.001008)
			(end -0.24 0.001008)
			(stroke
				(width 0.1)
				(type solid)
			)
			(layer "F.SilkS")
		)
		(fp_line
			(start 0.105328 0.201008)
			(end 0.105328 -0.198992)
			(stroke
				(width 0.1)
				(type solid)
			)
			(layer "F.SilkS")
		)
		(fp_line
			(start 0.105328 0.201008)
			(end -0.094672 0.001008)
			(stroke
				(width 0.1)
				(type solid)
			)
			(layer "F.SilkS")
		)
		(fp_line
			(start -0.094672 0.201008)
			(end -0.094672 -0.198992)
			(stroke
				(width 0.1)
				(type solid)
			)
			(layer "F.SilkS")
		)
		(fp_line
			(start 0.22 0.35)
			(end -0.22 0.35)
			(stroke
				(width 0.15)
				(type solid)
			)
			(layer "F.SilkS")
		)
		(fp_rect
			(start 1.25 0.65)
			(end -1.25 -0.65)
			(stroke
				(width 0.05)
				(type solid)
			)
			(fill none)
			(layer "F.CrtYd")
		)
		(fp_line
			(start 0.201 -0.202)
			(end -0.101 0)
			(stroke
				(width 0.15)
				(type solid)
			)
			(layer "F.Fab")
		)
		(fp_line
			(start -0.199 -0.202)
			(end -0.199 0.1)
			(stroke
				(width 0.15)
				(type solid)
			)
			(layer "F.Fab")
		)
		(fp_line
			(start 0.599 0)
			(end 0.201 0)
			(stroke
				(width 0.15)
				(type solid)
			)
			(layer "F.Fab")
		)
		(fp_line
			(start 0.201 0)
			(end 0.201 -0.202)
			(stroke
				(width 0.15)
				(type solid)
			)
			(layer "F.Fab")
		)
		(fp_line
			(start -0.101 0)
			(end 0.201 0.2)
			(stroke
				(width 0.15)
				(type solid)
			)
			(layer "F.Fab")
		)
		(fp_line
			(start -0.199 0)
			(end -0.597 0)
			(stroke
				(width 0.15)
				(type solid)
			)
			(layer "F.Fab")
		)
		(fp_line
			(start 0.201 0.2)
			(end 0.201 0)
			(stroke
				(width 0.15)
				(type solid)
			)
			(layer "F.Fab")
		)
		(fp_line
			(start -0.199 0.2)
			(end -0.199 0.1)
			(stroke
				(width 0.15)
				(type solid)
			)
			(layer "F.Fab")
		)
		(fp_rect
			(start 0.848 0.4)
			(end -0.85 -0.402)
			(stroke
				(width 0.15)
				(type solid)
			)
			(fill none)
			(layer "F.Fab")
		)
		(fp_text user "License: Apache-2.0"
			(at -1.4224 3.599 90)
			(layer "F.Fab")
			(hide yes)
			(effects
				(font
					(size 0.7 0.7)
					(thickness 0.15)
				)
				(justify left bottom)
			)
		)
		(fp_text user "${REFERENCE}"
			(at -1.4224 5.999 90)
			(layer "F.Fab")
			(hide yes)
			(effects
				(font
					(size 0.7 0.7)
					(thickness 0.15)
				)
				(justify left bottom)
			)
		)
		(fp_text user "Author: Antmicro"
			(at -1.4224 4.799 90)
			(layer "F.Fab")
			(hide yes)
			(effects
				(font
					(size 0.7 0.7)
					(thickness 0.15)
				)
				(justify left bottom)
			)
		)
		(pad "1" smd roundrect
			(at -0.7 0 270)
			(size 0.8 1)
			(layers "F.Cu" "F.Paste" "F.Mask")
			(roundrect_rratio 0.2)
			(net 1 "GND")
			(pinfunction "C")
			(pintype "passive")
		)
		(pad "2" smd roundrect
			(at 0.7 0 270)
			(size 0.8 1)
			(layers "F.Cu" "F.Paste" "F.Mask")
			(roundrect_rratio 0.2)
			(net 147 "Net-(D9-A)")
			(pinfunction "A")
			(pintype "passive")
		)
	)
	(footprint "antmicro-footprints:R_0402_1005Metric"
		(layer "F.Cu")
		(at 104.2 115.8 -90)
		(descr "Resistor SMD 0402")
		(tags "resistor SMD 0402")
		(property "Reference" "R136"
			(at -0.9 -0.45 -90)
			(layer "F.SilkS")
			(effects
				(font
					(size 0.7 0.7)
					(thickness 0.15)
				)
				(justify left bottom)
			)
		)
		(property "Value" "R_10k_0402"
			(at 0 1.4 -90)
			(layer "F.Fab")
			(effects
				(font
					(size 0.7 0.7)
					(thickness 0.15)
				)
				(justify left bottom)
			)
		)
		(property "Footprint" "antmicro-footprints:R_0402_1005Metric"
			(at 0 0 -90)
			(layer "F.Fab")
			(hide yes)
			(effects
				(font
					(size 1.27 1.27)
					(thickness 0.15)
				)
			)
		)
		(property "Datasheet" "https://www.bourns.com/docs/product-datasheets/cr.pdf"
			(at 0 0 -90)
			(layer "F.Fab")
			(hide yes)
			(effects
				(font
					(size 1.27 1.27)
					(thickness 0.15)
				)
			)
		)
		(property "Author" "Antmicro"
			(at -11.6 220 0)
			(layer "F.Fab")
			(hide yes)
			(effects
				(font
					(size 1 1)
					(thickness 0.15)
				)
			)
		)
		(property "License" "Apache-2.0"
			(at -11.6 220 0)
			(layer "F.Fab")
			(hide yes)
			(effects
				(font
					(size 1 1)
					(thickness 0.15)
				)
			)
		)
		(property "MPN" "CR0402-FX-1002GLF"
			(at -11.6 220 0)
			(layer "F.Fab")
			(hide yes)
			(effects
				(font
					(size 1 1)
					(thickness 0.15)
				)
			)
		)
		(property "Manufacturer" "Bourns"
			(at -11.6 220 0)
			(layer "F.Fab")
			(hide yes)
			(effects
				(font
					(size 1 1)
					(thickness 0.15)
				)
			)
		)
		(property "Tolerance" "1%"
			(at -11.6 220 0)
			(layer "F.Fab")
			(hide yes)
			(effects
				(font
					(size 1 1)
					(thickness 0.15)
				)
			)
		)
		(property "Val" "10k"
			(at -11.6 220 0)
			(layer "F.Fab")
			(hide yes)
			(effects
				(font
					(size 1 1)
					(thickness 0.15)
				)
			)
		)
		(sheetname "USB3")
		(sheetfile "usb3.kicad_sch")
		(attr smd)
		(fp_rect
			(start -0.925 -0.47)
			(end 0.925 0.47)
			(stroke
				(width 0.05)
				(type default)
			)
			(fill none)
			(layer "F.CrtYd")
		)
		(fp_rect
			(start -0.5 -0.25)
			(end 0.5 0.25)
			(stroke
				(width 0.15)
				(type solid)
			)
			(fill none)
			(layer "F.Fab")
		)
		(fp_text user "${REFERENCE}"
			(at -0.95 3.168 -90)
			(layer "F.Fab")
			(hide yes)
			(effects
				(font
					(size 0.7 0.7)
					(thickness 0.15)
				)
				(justify left bottom)
			)
		)
		(fp_text user "Author: Antmicro"
			(at -0.95 4.169 -90)
			(layer "F.Fab")
			(hide yes)
			(effects
				(font
					(size 0.7 0.7)
					(thickness 0.15)
				)
				(justify left bottom)
			)
		)
		(fp_text user "License: Apache-2.0"
			(at -0.95 5.169 -90)
			(layer "F.Fab")
			(hide yes)
			(effects
				(font
					(size 0.7 0.7)
					(thickness 0.15)
				)
				(justify left bottom)
			)
		)
		(pad "1" smd roundrect
			(at -0.48 0 270)
			(size 0.59 0.64)
			(layers "F.Cu" "F.Paste" "F.Mask")
			(roundrect_rratio 0.25)
			(net 562 "USBC1_PEN")
			(pintype "passive")
		)
		(pad "2" smd roundrect
			(at 0.48 0 270)
			(size 0.59 0.64)
			(layers "F.Cu" "F.Paste" "F.Mask")
			(roundrect_rratio 0.25)
			(net 284 "/USB3/USBC1_ID")
			(pintype "passive")
		)
	)
	(footprint "antmicro-footprints:SOT-523"
		(layer "F.Cu")
		(at 132.1 121.34 180)
		(property "Reference" "Q10"
			(at 1 -1.01 -90)
			(layer "F.SilkS")
			(effects
				(font
					(size 0.7 0.7)
					(thickness 0.15)
				)
				(justify left bottom)
			)
		)
		(property "Value" "PJE138K"
			(at 0.1 1.824 180)
			(layer "F.Fab")
			(effects
				(font
					(size 0.7 0.7)
					(thickness 0.15)
				)
				(justify left bottom)
			)
		)
		(property "Footprint" "antmicro-footprints:SOT-523"
			(at 0 0 180)
			(layer "F.Fab")
			(hide yes)
			(effects
				(font
					(size 1.27 1.27)
					(thickness 0.15)
				)
			)
		)
		(property "Datasheet" "https://www.mouser.com/datasheet/2/1057/PJE138K-1876698.pdf"
			(at 0 0 180)
			(layer "F.Fab")
			(hide yes)
			(effects
				(font
					(size 1.27 1.27)
					(thickness 0.15)
				)
			)
		)
		(property "Author" "Antmicro"
			(at 264.2 242.68 0)
			(layer "F.Fab")
			(hide yes)
			(effects
				(font
					(size 1 1)
					(thickness 0.15)
				)
			)
		)
		(property "License" "Apache-2.0"
			(at 264.2 242.68 0)
			(layer "F.Fab")
			(hide yes)
			(effects
				(font
					(size 1 1)
					(thickness 0.15)
				)
			)
		)
		(property "MPN" "PJE138K_R1_00001"
			(at 264.2 242.68 0)
			(layer "F.Fab")
			(hide yes)
			(effects
				(font
					(size 1 1)
					(thickness 0.15)
				)
			)
		)
		(property "Manufacturer" "PANJIT"
			(at 264.2 242.68 0)
			(layer "F.Fab")
			(hide yes)
			(effects
				(font
					(size 1 1)
					(thickness 0.15)
				)
			)
		)
		(sheetname "Peripherals")
		(sheetfile "peripherals.kicad_sch")
		(attr smd)
		(fp_line
			(start -0.277 -0.551)
			(end -0.277 -0.75)
			(stroke
				(width 0.15)
				(type solid)
			)
			(layer "F.SilkS")
		)
		(fp_line
			(start -0.725 -0.551)
			(end -0.277 -0.551)
			(stroke
				(width 0.15)
				(type solid)
			)
			(layer "F.SilkS")
		)
		(fp_line
			(start -0.927 -0.051)
			(end -0.927 -0.351)
			(stroke
				(width 0.15)
				(type solid)
			)
			(layer "F.SilkS")
		)
		(fp_line
			(start -0.927 -0.351)
			(end -0.725 -0.551)
			(stroke
				(width 0.15)
				(type solid)
			)
			(layer "F.SilkS")
		)
		(fp_circle
			(center -0.9652 0.9652)
			(end -0.9152 0.9652)
			(stroke
				(width 0.15)
				(type solid)
			)
			(fill solid)
			(layer "F.SilkS")
		)
		(fp_line
			(start 1.1 -1.16)
			(end 1.1 1.15)
			(stroke
				(width 0.05)
				(type solid)
			)
			(layer "F.CrtYd")
		)
		(fp_line
			(start -1.12 1.15)
			(end 1.1 1.15)
			(stroke
				(width 0.05)
				(type solid)
			)
			(layer "F.CrtYd")
		)
		(fp_line
			(start -1.12 -1.16)
			(end 1.1 -1.16)
			(stroke
				(width 0.05)
				(type solid)
			)
			(layer "F.CrtYd")
		)
		(fp_line
			(start -1.12 -1.16)
			(end -1.12 1.15)
			(stroke
				(width 0.05)
				(type solid)
			)
			(layer "F.CrtYd")
		)
		(fp_line
			(start 0.8 0.424)
			(end -0.802 0.424)
			(stroke
				(width 0.15)
				(type solid)
			)
			(layer "F.Fab")
		)
		(fp_line
			(start 0.8 -0.425)
			(end 0.8 0.424)
			(stroke
				(width 0.15)
				(type solid)
			)
			(layer "F.Fab")
		)
		(fp_line
			(start 0.8 -0.425)
			(end -0.652 -0.425)
			(stroke
				(width 0.15)
				(type solid)
			)
			(layer "F.Fab")
		)
		(fp_line
			(start -0.652 -0.425)
			(end -0.802 -0.276)
			(stroke
				(width 0.15)
				(type solid)
			)
			(layer "F.Fab")
		)
		(fp_line
			(start -0.802 -0.276)
			(end -0.802 0.424)
			(stroke
				(width 0.15)
				(type solid)
			)
			(layer "F.Fab")
		)
		(fp_circle
			(center -0.9652 0.9652)
			(end -0.9144 0.9652)
			(stroke
				(width 0.15)
				(type solid)
			)
			(fill none)
			(layer "F.Fab")
		)
		(fp_text user "Author: Antmicro"
			(at -1.12 6.224 180)
			(layer "F.Fab")
			(hide yes)
			(effects
				(font
					(size 0.7 0.7)
					(thickness 0.15)
				)
				(justify left bottom)
			)
		)
		(fp_text user "License: Apache-2.0"
			(at -1.12 5.024 180)
			(layer "F.Fab")
			(hide yes)
			(effects
				(font
					(size 0.7 0.7)
					(thickness 0.15)
				)
				(justify left bottom)
			)
		)
		(fp_text user "${REFERENCE}"
			(at -1.12 3.824 180)
			(layer "F.Fab")
			(hide yes)
			(effects
				(font
					(size 0.7 0.7)
					(thickness 0.15)
				)
				(justify left bottom)
			)
		)
		(pad "1" smd rect
			(at -0.5 0.65 180)
			(size 0.4 0.51)
			(layers "F.Cu" "F.Paste" "F.Mask")
			(net 44 "USER_LED1")
			(pinfunction "G")
			(pintype "passive")
		)
		(pad "2" smd rect
			(at 0.498 0.65 180)
			(size 0.4 0.51)
			(layers "F.Cu" "F.Paste" "F.Mask")
			(net 1 "GND")
			(pinfunction "S")
			(pintype "passive")
		)
		(pad "3" smd rect
			(at 0 -0.652 180)
			(size 0.4 0.51)
			(layers "F.Cu" "F.Paste" "F.Mask")
			(net 181 "Net-(D27-C)")
			(pinfunction "D")
			(pintype "passive")
		)
	)
	(footprint "antmicro-footprints:USON-10_2.5x1mm_P0.5mm"
		(layer "F.Cu")
		(at 78 115.5 90)
		(descr "USON-10 2.5x1mm_ Pitch 0.5mm")
		(tags "USON-10 2.5x1mm Pitch 0.5mm")
		(property "Reference" "U14"
			(at 0.89 -0.6 180)
			(layer "F.SilkS")
			(effects
				(font
					(size 0.7 0.7)
					(thickness 0.15)
				)
				(justify left bottom)
			)
		)
		(property "Value" "TPD4E05U06QDQARQ1"
			(at 0.018 2.499 90)
			(layer "F.Fab")
			(effects
				(font
					(size 0.7 0.7)
					(thickness 0.15)
				)
				(justify left bottom)
			)
		)
		(property "Footprint" "antmicro-footprints:USON-10_2.5x1mm_P0.5mm"
			(at 0 0 90)
			(layer "F.Fab")
			(hide yes)
			(effects
				(font
					(size 1.27 1.27)
					(thickness 0.15)
				)
			)
		)
		(property "Datasheet" "https://www.ti.com/lit/ds/symlink/tpd4e05u06-q1.pdf?HQS=dis-mous-null-mousermode-dsf-pf-null-wwe&ts=1663591265741&ref_url=https%253A%252F%252Fwww.mouser.com%252F"
			(at 0 0 90)
			(layer "F.Fab")
			(hide yes)
			(effects
				(font
					(size 1.27 1.27)
					(thickness 0.15)
				)
			)
		)
		(property "Author" "Antmicro"
			(at 193.5 37.5 0)
			(layer "F.Fab")
			(hide yes)
			(effects
				(font
					(size 1 1)
					(thickness 0.15)
				)
			)
		)
		(property "License" "Apache-2.0"
			(at 193.5 37.5 0)
			(layer "F.Fab")
			(hide yes)
			(effects
				(font
					(size 1 1)
					(thickness 0.15)
				)
			)
		)
		(property "MPN" "TPD4E05U06QDQARQ1"
			(at 193.5 37.5 0)
			(layer "F.Fab")
			(hide yes)
			(effects
				(font
					(size 1 1)
					(thickness 0.15)
				)
			)
		)
		(property "Manufacturer" "Texas Instruments"
			(at 193.5 37.5 0)
			(layer "F.Fab")
			(hide yes)
			(effects
				(font
					(size 1 1)
					(thickness 0.15)
				)
			)
		)
		(sheetname "USB Debug, DP")
		(sheetfile "usb.kicad_sch")
		(attr smd)
		(fp_line
			(start 0.498 -1.401)
			(end -0.5 -1.401)
			(stroke
				(width 0.15)
				(type solid)
			)
			(layer "F.SilkS")
		)
		(fp_line
			(start 0.498 1.398)
			(end -0.5 1.398)
			(stroke
				(width 0.15)
				(type solid)
			)
			(layer "F.SilkS")
		)
		(fp_circle
			(center -0.68 -1.27)
			(end -0.63 -1.27)
			(stroke
				(width 0.15)
				(type solid)
			)
			(fill solid)
			(layer "F.SilkS")
		)
		(fp_rect
			(start -0.8 -1.5)
			(end 0.8 1.499)
			(stroke
				(width 0.05)
				(type solid)
			)
			(fill none)
			(layer "F.CrtYd")
		)
		(fp_line
			(start 0.498 -1.25)
			(end -0.25 -1.25)
			(stroke
				(width 0.15)
				(type solid)
			)
			(layer "F.Fab")
		)
		(fp_line
			(start 0.498 -1.25)
			(end 0.498 1.249)
			(stroke
				(width 0.15)
				(type solid)
			)
			(layer "F.Fab")
		)
		(fp_line
			(start -0.25 -1.25)
			(end -0.5 -1)
			(stroke
				(width 0.15)
				(type solid)
			)
			(layer "F.Fab")
		)
		(fp_line
			(start -0.5 -1)
			(end -0.5 1.249)
			(stroke
				(width 0.15)
				(type solid)
			)
			(layer "F.Fab")
		)
		(fp_line
			(start -0.5 1.249)
			(end 0.498 1.249)
			(stroke
				(width 0.15)
				(type solid)
			)
			(layer "F.Fab")
		)
		(fp_text user "License: Apache-2.0"
			(at -0.802 6.9 90)
			(layer "F.Fab")
			(hide yes)
			(effects
				(font
					(size 0.7 0.7)
					(thickness 0.15)
				)
				(justify left bottom)
			)
		)
		(fp_text user "Author: Antmicro"
			(at -0.802 5.7 90)
			(layer "F.Fab")
			(hide yes)
			(effects
				(font
					(size 0.7 0.7)
					(thickness 0.15)
				)
				(justify left bottom)
			)
		)
		(fp_text user "${REFERENCE}"
			(at -0.802 4.498 90)
			(layer "F.Fab")
			(hide yes)
			(effects
				(font
					(size 0.7 0.7)
					(thickness 0.15)
				)
				(justify left bottom)
			)
		)
		(pad "1" smd roundrect
			(at -0.387 -1)
			(size 0.25 0.55)
			(layers "F.Cu" "F.Paste" "F.Mask")
			(roundrect_rratio 0.25)
			(net 125 "/USB Debug, DP/USBC0_RX2_N")
			(pintype "passive")
		)
		(pad "2" smd roundrect
			(at -0.387 -0.5)
			(size 0.25 0.55)
			(layers "F.Cu" "F.Paste" "F.Mask")
			(roundrect_rratio 0.25)
			(net 151 "/USB Debug, DP/USBC0_RX2_P")
			(pintype "passive")
		)
		(pad "3" smd roundrect
			(at -0.387 0)
			(size 0.4 0.55)
			(layers "F.Cu" "F.Paste" "F.Mask")
			(roundrect_rratio 0.25)
			(net 1 "GND")
			(pintype "power_in")
		)
		(pad "4" smd roundrect
			(at -0.387 0.498)
			(size 0.25 0.55)
			(layers "F.Cu" "F.Paste" "F.Mask")
			(roundrect_rratio 0.25)
			(net 201 "/USB Debug, DP/USBC0_CONN_TX2_N")
			(pintype "passive")
		)
		(pad "5" smd roundrect
			(at -0.387 0.998)
			(size 0.25 0.55)
			(layers "F.Cu" "F.Paste" "F.Mask")
			(roundrect_rratio 0.25)
			(net 260 "/USB Debug, DP/USBC0_CONN_TX2_P")
			(pintype "passive")
		)
		(pad "6" smd roundrect
			(at 0.385 0.998)
			(size 0.25 0.55)
			(layers "F.Cu" "F.Paste" "F.Mask")
			(roundrect_rratio 0.25)
			(net 260 "/USB Debug, DP/USBC0_CONN_TX2_P")
			(pintype "passive")
		)
		(pad "7" smd roundrect
			(at 0.385 0.498)
			(size 0.25 0.55)
			(layers "F.Cu" "F.Paste" "F.Mask")
			(roundrect_rratio 0.25)
			(net 201 "/USB Debug, DP/USBC0_CONN_TX2_N")
			(pintype "passive")
		)
		(pad "8" smd roundrect
			(at 0.385 0)
			(size 0.4 0.55)
			(layers "F.Cu" "F.Paste" "F.Mask")
			(roundrect_rratio 0.25)
			(net 1 "GND")
			(pintype "passive")
		)
		(pad "9" smd roundrect
			(at 0.385 -0.5)
			(size 0.25 0.55)
			(layers "F.Cu" "F.Paste" "F.Mask")
			(roundrect_rratio 0.25)
			(net 151 "/USB Debug, DP/USBC0_RX2_P")
			(pintype "passive")
		)
		(pad "10" smd roundrect
			(at 0.385 -1)
			(size 0.25 0.55)
			(layers "F.Cu" "F.Paste" "F.Mask")
			(roundrect_rratio 0.25)
			(net 125 "/USB Debug, DP/USBC0_RX2_N")
			(pintype "passive")
		)
	)
	(footprint "antmicro-footprints:XDFN-2_1x0.60mm"
		(layer "F.Cu")
		(at 147.45 90.8 -90)
		(property "Reference" "D50"
			(at -7.4 0.15 180)
			(layer "F.SilkS")
			(effects
				(font
					(size 0.7 0.7)
					(thickness 0.15)
				)
				(justify left bottom)
			)
		)
		(property "Value" "TPD1E0B04_XDFN-2"
			(at 0 1.5 -90)
			(layer "F.Fab")
			(effects
				(font
					(size 0.7 0.7)
					(thickness 0.15)
				)
				(justify left bottom)
			)
		)
		(property "Footprint" "antmicro-footprints:XDFN-2_1x0.60mm"
			(at 0 0 -90)
			(layer "F.Fab")
			(hide yes)
			(effects
				(font
					(size 1.27 1.27)
					(thickness 0.15)
				)
			)
		)
		(property "Datasheet" "https://www.ti.com/general/docs/suppproductinfo.tsp?distId=26&gotoUrl=https://www.ti.com/lit/gpn/tpd1e0b04"
			(at 0 0 -90)
			(layer "F.Fab")
			(hide yes)
			(effects
				(font
					(size 1.27 1.27)
					(thickness 0.15)
				)
			)
		)
		(property "MPN" "TPD1E0B04DPYR"
			(at 56.65 238.25 0)
			(layer "F.Fab")
			(hide yes)
			(effects
				(font
					(size 1 1)
					(thickness 0.15)
				)
			)
		)
		(property "Manufacturer" "Texas Instruments"
			(at 56.65 238.25 0)
			(layer "F.Fab")
			(hide yes)
			(effects
				(font
					(size 1 1)
					(thickness 0.15)
				)
			)
		)
		(property "Author" "Antmicro"
			(at 56.65 238.25 0)
			(layer "F.Fab")
			(hide yes)
			(effects
				(font
					(size 1 1)
					(thickness 0.15)
				)
			)
		)
		(property "License" "Apache-2.0"
			(at 56.65 238.25 0)
			(layer "F.Fab")
			(hide yes)
			(effects
				(font
					(size 1 1)
					(thickness 0.15)
				)
			)
		)
		(sheetname "Peripherals")
		(sheetfile "peripherals.kicad_sch")
		(attr smd)
		(fp_rect
			(start -0.725 -0.475)
			(end 0.725 0.475)
			(stroke
				(width 0.05)
				(type solid)
			)
			(fill none)
			(layer "F.CrtYd")
		)
		(fp_rect
			(start -0.55 -0.35)
			(end 0.55 0.35)
			(stroke
				(width 0.15)
				(type solid)
			)
			(fill none)
			(layer "F.Fab")
		)
		(fp_text user "Author: Antmicro"
			(at -0.8 4.4 -90)
			(layer "F.Fab")
			(hide yes)
			(effects
				(font
					(size 0.7 0.7)
					(thickness 0.15)
				)
				(justify left bottom)
			)
		)
		(fp_text user "${REFERENCE}"
			(at -0.8 3.2 -90)
			(layer "F.Fab")
			(hide yes)
			(effects
				(font
					(size 0.7 0.7)
					(thickness 0.15)
				)
				(justify left bottom)
			)
		)
		(fp_text user "License: Apache-2.0"
			(at -0.8 5.6 -90)
			(layer "F.Fab")
			(hide yes)
			(effects
				(font
					(size 0.7 0.7)
					(thickness 0.15)
				)
				(justify left bottom)
			)
		)
		(pad "1" smd roundrect
			(at -0.351 0 270)
			(size 0.3 0.5)
			(layers "F.Cu" "F.Paste" "F.Mask")
			(roundrect_rratio 0.25)
			(net 472 "PCIE3_CLK_P")
			(pinfunction "C")
			(pintype "passive")
		)
		(pad "2" smd roundrect
			(at 0.349 0 270)
			(size 0.3 0.5)
			(layers "F.Cu" "F.Paste" "F.Mask")
			(roundrect_rratio 0.25)
			(net 1 "GND")
			(pinfunction "A")
			(pintype "passive")
		)
	)
	(footprint "antmicro-footprints:XDFN-2_1x0.60mm"
		(layer "F.Cu")
		(at 131.4 123.34 90)
		(property "Reference" "D57"
			(at 0.69 -1.45 -90)
			(layer "F.SilkS")
			(effects
				(font
					(size 0.7 0.7)
					(thickness 0.15)
				)
				(justify left bottom)
			)
		)
		(property "Value" "TPD1E0B04_XDFN-2"
			(at 0 1.5 90)
			(layer "F.Fab")
			(effects
				(font
					(size 0.7 0.7)
					(thickness 0.15)
				)
				(justify left bottom)
			)
		)
		(property "Footprint" "antmicro-footprints:XDFN-2_1x0.60mm"
			(at 0 0 90)
			(layer "F.Fab")
			(hide yes)
			(effects
				(font
					(size 1.27 1.27)
					(thickness 0.15)
				)
			)
		)
		(property "Datasheet" "https://www.ti.com/general/docs/suppproductinfo.tsp?distId=26&gotoUrl=https://www.ti.com/lit/gpn/tpd1e0b04"
			(at 0 0 90)
			(layer "F.Fab")
			(hide yes)
			(effects
				(font
					(size 1.27 1.27)
					(thickness 0.15)
				)
			)
		)
		(property "MPN" "TPD1E0B04DPYR"
			(at 254.74 -8.06 0)
			(layer "F.Fab")
			(hide yes)
			(effects
				(font
					(size 1 1)
					(thickness 0.15)
				)
			)
		)
		(property "Manufacturer" "Texas Instruments"
			(at 254.74 -8.06 0)
			(layer "F.Fab")
			(hide yes)
			(effects
				(font
					(size 1 1)
					(thickness 0.15)
				)
			)
		)
		(property "Author" "Antmicro"
			(at 254.74 -8.06 0)
			(layer "F.Fab")
			(hide yes)
			(effects
				(font
					(size 1 1)
					(thickness 0.15)
				)
			)
		)
		(property "License" "Apache-2.0"
			(at 254.74 -8.06 0)
			(layer "F.Fab")
			(hide yes)
			(effects
				(font
					(size 1 1)
					(thickness 0.15)
				)
			)
		)
		(sheetname "Peripherals")
		(sheetfile "peripherals.kicad_sch")
		(attr smd)
		(fp_rect
			(start -0.725 -0.475)
			(end 0.725 0.475)
			(stroke
				(width 0.05)
				(type solid)
			)
			(fill none)
			(layer "F.CrtYd")
		)
		(fp_rect
			(start -0.55 -0.35)
			(end 0.55 0.35)
			(stroke
				(width 0.15)
				(type solid)
			)
			(fill none)
			(layer "F.Fab")
		)
		(fp_text user "${REFERENCE}"
			(at -0.8 3.2 90)
			(layer "F.Fab")
			(hide yes)
			(effects
				(font
					(size 0.7 0.7)
					(thickness 0.15)
				)
				(justify left bottom)
			)
		)
		(fp_text user "Author: Antmicro"
			(at -0.8 4.4 90)
			(layer "F.Fab")
			(hide yes)
			(effects
				(font
					(size 0.7 0.7)
					(thickness 0.15)
				)
				(justify left bottom)
			)
		)
		(fp_text user "License: Apache-2.0"
			(at -0.8 5.6 90)
			(layer "F.Fab")
			(hide yes)
			(effects
				(font
					(size 0.7 0.7)
					(thickness 0.15)
				)
				(justify left bottom)
			)
		)
		(pad "1" smd roundrect
			(at -0.351 0 90)
			(size 0.3 0.5)
			(layers "F.Cu" "F.Paste" "F.Mask")
			(roundrect_rratio 0.25)
			(net 1 "GND")
			(pinfunction "C")
			(pintype "passive")
		)
		(pad "2" smd roundrect
			(at 0.349 0 90)
			(size 0.3 0.5)
			(layers "F.Cu" "F.Paste" "F.Mask")
			(roundrect_rratio 0.25)
			(net 660 "I2C1_SDA")
			(pinfunction "A")
			(pintype "passive")
		)
	)
	(footprint "antmicro-footprints:C_0402_1005Metric"
		(layer "F.Cu")
		(at 136.35 86.25 180)
		(descr "Capacitor SMD 0402")
		(tags "capacitor SMD 0402")
		(property "Reference" "C108"
			(at 3.65 -0.45 180)
			(layer "F.SilkS")
			(effects
				(font
					(size 0.7 0.7)
					(thickness 0.15)
				)
				(justify left bottom)
			)
		)
		(property "Value" "C_220n_0402"
			(at 0 1.4 180)
			(layer "F.Fab")
			(effects
				(font
					(size 0.7 0.7)
					(thickness 0.15)
				)
				(justify left bottom)
			)
		)
		(property "Footprint" "antmicro-footprints:C_0402_1005Metric"
			(at 0 0 180)
			(layer "F.Fab")
			(hide yes)
			(effects
				(font
					(size 1.27 1.27)
					(thickness 0.15)
				)
			)
		)
		(property "Datasheet" "https://www.yageo.com/en/Chart/Download/pdf/CC0402KRX5R6BB224"
			(at 0 0 180)
			(layer "F.Fab")
			(hide yes)
			(effects
				(font
					(size 1.27 1.27)
					(thickness 0.15)
				)
			)
		)
		(property "Author" "Antmicro"
			(at 272.7 172.5 0)
			(layer "F.Fab")
			(hide yes)
			(effects
				(font
					(size 1 1)
					(thickness 0.15)
				)
			)
		)
		(property "Dielectric" ""
			(at 272.7 172.5 0)
			(layer "F.Fab")
			(hide yes)
			(effects
				(font
					(size 1 1)
					(thickness 0.15)
				)
			)
		)
		(property "License" "Apache-2.0"
			(at 272.7 172.5 0)
			(layer "F.Fab")
			(hide yes)
			(effects
				(font
					(size 1 1)
					(thickness 0.15)
				)
			)
		)
		(property "MPN" "CC0402KRX5R6BB224"
			(at 272.7 172.5 0)
			(layer "F.Fab")
			(hide yes)
			(effects
				(font
					(size 1 1)
					(thickness 0.15)
				)
			)
		)
		(property "Manufacturer" "YAGEO"
			(at 272.7 172.5 0)
			(layer "F.Fab")
			(hide yes)
			(effects
				(font
					(size 1 1)
					(thickness 0.15)
				)
			)
		)
		(property "Val" "220n"
			(at 272.7 172.5 0)
			(layer "F.Fab")
			(hide yes)
			(effects
				(font
					(size 1 1)
					(thickness 0.15)
				)
			)
		)
		(property "Voltage" ""
			(at 272.7 172.5 0)
			(layer "F.Fab")
			(hide yes)
			(effects
				(font
					(size 1 1)
					(thickness 0.15)
				)
			)
		)
		(sheetname "Peripherals")
		(sheetfile "peripherals.kicad_sch")
		(attr smd)
		(fp_rect
			(start -0.925 -0.47)
			(end 0.925 0.47)
			(stroke
				(width 0.05)
				(type default)
			)
			(fill none)
			(layer "F.CrtYd")
		)
		(fp_line
			(start 0.504 0.248)
			(end -0.494 0.248)
			(stroke
				(width 0.15)
				(type solid)
			)
			(layer "F.Fab")
		)
		(fp_line
			(start 0.504 -0.25)
			(end 0.504 0.248)
			(stroke
				(width 0.15)
				(type solid)
			)
			(layer "F.Fab")
		)
		(fp_line
			(start -0.494 0.248)
			(end -0.494 -0.25)
			(stroke
				(width 0.15)
				(type solid)
			)
			(layer "F.Fab")
		)
		(fp_line
			(start -0.494 -0.25)
			(end 0.504 -0.25)
			(stroke
				(width 0.15)
				(type solid)
			)
			(layer "F.Fab")
		)
		(fp_text user "License: Apache-2.0"
			(at -0.932 5.17 180)
			(layer "F.Fab")
			(hide yes)
			(effects
				(font
					(size 0.7 0.7)
					(thickness 0.15)
				)
				(justify left bottom)
			)
		)
		(fp_text user "Author: Antmicro"
			(at -0.932 4.17 180)
			(layer "F.Fab")
			(hide yes)
			(effects
				(font
					(size 0.7 0.7)
					(thickness 0.15)
				)
				(justify left bottom)
			)
		)
		(fp_text user "${REFERENCE}"
			(at -0.932 3.168 180)
			(layer "F.Fab")
			(hide yes)
			(effects
				(font
					(size 0.7 0.7)
					(thickness 0.15)
				)
				(justify left bottom)
			)
		)
		(pad "1" smd roundrect
			(at -0.48 0 180)
			(size 0.59 0.64)
			(layers "F.Cu" "F.Paste" "F.Mask")
			(roundrect_rratio 0.25)
			(net 411 "/Peripherals/PCIE2_TX0_CONN_N")
			(pintype "passive")
		)
		(pad "2" smd roundrect
			(at 0.48 0 180)
			(size 0.59 0.64)
			(layers "F.Cu" "F.Paste" "F.Mask")
			(roundrect_rratio 0.25)
			(net 156 "PCIE2_TX0_N")
			(pintype "passive")
		)
	)
	(footprint "antmicro-footprints:C_0402_1005Metric"
		(layer "F.Cu")
		(at 74.6 110.967469 -90)
		(descr "Capacitor SMD 0402")
		(tags "capacitor SMD 0402")
		(property "Reference" "C62"
			(at 2.982531 -0.4 -90)
			(layer "F.SilkS")
			(effects
				(font
					(size 0.7 0.7)
					(thickness 0.15)
				)
				(justify left bottom)
			)
		)
		(property "Value" "C_100n_0402"
			(at 0 1.4 -90)
			(layer "F.Fab")
			(effects
				(font
					(size 0.7 0.7)
					(thickness 0.15)
				)
				(justify left bottom)
			)
		)
		(property "Footprint" "antmicro-footprints:C_0402_1005Metric"
			(at 0 0 -90)
			(layer "F.Fab")
			(hide yes)
			(effects
				(font
					(size 1.27 1.27)
					(thickness 0.15)
				)
			)
		)
		(property "Datasheet" "https://www.murata.com/products/productdetail?partno=GRM155R61H104KE14%23"
			(at 0 0 -90)
			(layer "F.Fab")
			(hide yes)
			(effects
				(font
					(size 1.27 1.27)
					(thickness 0.15)
				)
			)
		)
		(property "Author" "Antmicro"
			(at -36.367469 185.567469 0)
			(layer "F.Fab")
			(hide yes)
			(effects
				(font
					(size 1 1)
					(thickness 0.15)
				)
			)
		)
		(property "Dielectric" "X5R"
			(at -36.367469 185.567469 0)
			(layer "F.Fab")
			(hide yes)
			(effects
				(font
					(size 1 1)
					(thickness 0.15)
				)
			)
		)
		(property "License" "Apache-2.0"
			(at -36.367469 185.567469 0)
			(layer "F.Fab")
			(hide yes)
			(effects
				(font
					(size 1 1)
					(thickness 0.15)
				)
			)
		)
		(property "MPN" "GRM155R61H104KE14D"
			(at -36.367469 185.567469 0)
			(layer "F.Fab")
			(hide yes)
			(effects
				(font
					(size 1 1)
					(thickness 0.15)
				)
			)
		)
		(property "Manufacturer" "Murata"
			(at -36.367469 185.567469 0)
			(layer "F.Fab")
			(hide yes)
			(effects
				(font
					(size 1 1)
					(thickness 0.15)
				)
			)
		)
		(property "Val" "100n"
			(at -36.367469 185.567469 0)
			(layer "F.Fab")
			(hide yes)
			(effects
				(font
					(size 1 1)
					(thickness 0.15)
				)
			)
		)
		(property "Voltage" "50V"
			(at -36.367469 185.567469 0)
			(layer "F.Fab")
			(hide yes)
			(effects
				(font
					(size 1 1)
					(thickness 0.15)
				)
			)
		)
		(sheetname "USB Debug, DP")
		(sheetfile "usb.kicad_sch")
		(attr smd)
		(fp_rect
			(start -0.925 -0.47)
			(end 0.925 0.47)
			(stroke
				(width 0.05)
				(type default)
			)
			(fill none)
			(layer "F.CrtYd")
		)
		(fp_line
			(start -0.494 0.248)
			(end -0.494 -0.25)
			(stroke
				(width 0.15)
				(type solid)
			)
			(layer "F.Fab")
		)
		(fp_line
			(start 0.504 0.248)
			(end -0.494 0.248)
			(stroke
				(width 0.15)
				(type solid)
			)
			(layer "F.Fab")
		)
		(fp_line
			(start -0.494 -0.25)
			(end 0.504 -0.25)
			(stroke
				(width 0.15)
				(type solid)
			)
			(layer "F.Fab")
		)
		(fp_line
			(start 0.504 -0.25)
			(end 0.504 0.248)
			(stroke
				(width 0.15)
				(type solid)
			)
			(layer "F.Fab")
		)
		(fp_text user "${REFERENCE}"
			(at -0.932 3.168 -90)
			(layer "F.Fab")
			(hide yes)
			(effects
				(font
					(size 0.7 0.7)
					(thickness 0.15)
				)
				(justify left bottom)
			)
		)
		(fp_text user "License: Apache-2.0"
			(at -0.932 5.17 -90)
			(layer "F.Fab")
			(hide yes)
			(effects
				(font
					(size 0.7 0.7)
					(thickness 0.15)
				)
				(justify left bottom)
			)
		)
		(fp_text user "Author: Antmicro"
			(at -0.932 4.17 -90)
			(layer "F.Fab")
			(hide yes)
			(effects
				(font
					(size 0.7 0.7)
					(thickness 0.15)
				)
				(justify left bottom)
			)
		)
		(pad "1" smd roundrect
			(at -0.48 0 270)
			(size 0.59 0.64)
			(layers "F.Cu" "F.Paste" "F.Mask")
			(roundrect_rratio 0.25)
			(net 197 "/USB Debug, DP/USBC0_TX1_N")
			(pintype "passive")
		)
		(pad "2" smd roundrect
			(at 0.48 0 270)
			(size 0.59 0.64)
			(layers "F.Cu" "F.Paste" "F.Mask")
			(roundrect_rratio 0.25)
			(net 198 "/USB Debug, DP/USBC0_CONN_TX1_N")
			(pintype "passive")
		)
	)
	(footprint "antmicro-footprints:R_0402_1005Metric"
		(layer "F.Cu")
		(at 68.27 85.5 180)
		(descr "Resistor SMD 0402")
		(tags "resistor SMD 0402")
		(property "Reference" "R5"
			(at -4.14 3.15 0)
			(layer "F.SilkS")
			(effects
				(font
					(size 0.7 0.7)
					(thickness 0.15)
				)
				(justify right bottom)
			)
		)
		(property "Value" "R_0R_0402"
			(at 0 1.4 0)
			(layer "F.Fab")
			(effects
				(font
					(size 0.7 0.7)
					(thickness 0.15)
				)
				(justify right bottom)
			)
		)
		(property "Footprint" "antmicro-footprints:R_0402_1005Metric"
			(at 0 0 0)
			(layer "F.Fab")
			(hide yes)
			(effects
				(font
					(size 1.27 1.27)
					(thickness 0.15)
				)
			)
		)
		(property "Datasheet" "https://industrial.panasonic.com/cdbs/www-data/pdf/RDA0000/AOA0000C301.pdf"
			(at 0 0 0)
			(layer "F.Fab")
			(hide yes)
			(effects
				(font
					(size 1.27 1.27)
					(thickness 0.15)
				)
			)
		)
		(property "Author" "Antmicro"
			(at -16.4 149.4 90)
			(layer "F.Fab")
			(hide yes)
			(effects
				(font
					(size 1 1)
					(thickness 0.15)
				)
			)
		)
		(property "Current" "1A"
			(at -16.4 149.4 90)
			(layer "F.Fab")
			(hide yes)
			(effects
				(font
					(size 1 1)
					(thickness 0.15)
				)
			)
		)
		(property "License" "Apache-2.0"
			(at -16.4 149.4 90)
			(layer "F.Fab")
			(hide yes)
			(effects
				(font
					(size 1 1)
					(thickness 0.15)
				)
			)
		)
		(property "MPN" "ERJ2GE0R00X"
			(at -16.4 149.4 90)
			(layer "F.Fab")
			(hide yes)
			(effects
				(font
					(size 1 1)
					(thickness 0.15)
				)
			)
		)
		(property "Manufacturer" "Panasonic"
			(at -16.4 149.4 90)
			(layer "F.Fab")
			(hide yes)
			(effects
				(font
					(size 1 1)
					(thickness 0.15)
				)
			)
		)
		(property "Tolerance" ""
			(at -16.4 149.4 90)
			(layer "F.Fab")
			(hide yes)
			(effects
				(font
					(size 1 1)
					(thickness 0.15)
				)
			)
		)
		(property "Val" "0R"
			(at -16.4 149.4 90)
			(layer "F.Fab")
			(hide yes)
			(effects
				(font
					(size 1 1)
					(thickness 0.15)
				)
			)
		)
		(sheetname "SoM")
		(sheetfile "som.kicad_sch")
		(attr smd exclude_from_pos_files exclude_from_bom dnp)
		(fp_rect
			(start -0.925 -0.47)
			(end 0.925 0.47)
			(stroke
				(width 0.05)
				(type default)
			)
			(fill none)
			(layer "F.CrtYd")
		)
		(fp_rect
			(start -0.5 -0.25)
			(end 0.5 0.25)
			(stroke
				(width 0.15)
				(type solid)
			)
			(fill none)
			(layer "F.Fab")
		)
		(fp_text user "License: Apache-2.0"
			(at -0.95 5.169 0)
			(layer "F.Fab")
			(hide yes)
			(effects
				(font
					(size 0.7 0.7)
					(thickness 0.15)
				)
				(justify right bottom)
			)
		)
		(fp_text user "Author: Antmicro"
			(at -0.95 4.169 0)
			(layer "F.Fab")
			(hide yes)
			(effects
				(font
					(size 0.7 0.7)
					(thickness 0.15)
				)
				(justify right bottom)
			)
		)
		(fp_text user "${REFERENCE}"
			(at -0.95 3.168 0)
			(layer "F.Fab")
			(hide yes)
			(effects
				(font
					(size 0.7 0.7)
					(thickness 0.15)
				)
				(justify right bottom)
			)
		)
		(pad "1" smd roundrect
			(at -0.48 0 180)
			(size 0.59 0.64)
			(layers "F.Cu" "F.Paste" "F.Mask")
			(roundrect_rratio 0.25)
			(net 753 "Net-(J15H-GPIO13{slash}PWM)")
			(pintype "passive")
		)
		(pad "2" smd roundrect
			(at 0.48 0 180)
			(size 0.59 0.64)
			(layers "F.Cu" "F.Paste" "F.Mask")
			(roundrect_rratio 0.25)
			(net 243 "VSYNC_CAM3")
			(pintype "passive")
		)
	)
	(footprint "antmicro-footprints:XDFN-2_1x0.60mm"
		(layer "F.Cu")
		(at 147.45 89.5 90)
		(property "Reference" "D49"
			(at 7 -0.15 0)
			(layer "F.SilkS")
			(effects
				(font
					(size 0.7 0.7)
					(thickness 0.15)
				)
				(justify left bottom)
			)
		)
		(property "Value" "TPD1E0B04_XDFN-2"
			(at 0 1.5 90)
			(layer "F.Fab")
			(effects
				(font
					(size 0.7 0.7)
					(thickness 0.15)
				)
				(justify left bottom)
			)
		)
		(property "Footprint" "antmicro-footprints:XDFN-2_1x0.60mm"
			(at 0 0 90)
			(layer "F.Fab")
			(hide yes)
			(effects
				(font
					(size 1.27 1.27)
					(thickness 0.15)
				)
			)
		)
		(property "Datasheet" "https://www.ti.com/general/docs/suppproductinfo.tsp?distId=26&gotoUrl=https://www.ti.com/lit/gpn/tpd1e0b04"
			(at 0 0 90)
			(layer "F.Fab")
			(hide yes)
			(effects
				(font
					(size 1.27 1.27)
					(thickness 0.15)
				)
			)
		)
		(property "MPN" "TPD1E0B04DPYR"
			(at 236.95 -57.95 0)
			(layer "F.Fab")
			(hide yes)
			(effects
				(font
					(size 1 1)
					(thickness 0.15)
				)
			)
		)
		(property "Manufacturer" "Texas Instruments"
			(at 236.95 -57.95 0)
			(layer "F.Fab")
			(hide yes)
			(effects
				(font
					(size 1 1)
					(thickness 0.15)
				)
			)
		)
		(property "Author" "Antmicro"
			(at 236.95 -57.95 0)
			(layer "F.Fab")
			(hide yes)
			(effects
				(font
					(size 1 1)
					(thickness 0.15)
				)
			)
		)
		(property "License" "Apache-2.0"
			(at 236.95 -57.95 0)
			(layer "F.Fab")
			(hide yes)
			(effects
				(font
					(size 1 1)
					(thickness 0.15)
				)
			)
		)
		(sheetname "Peripherals")
		(sheetfile "peripherals.kicad_sch")
		(attr smd)
		(fp_rect
			(start -0.725 -0.475)
			(end 0.725 0.475)
			(stroke
				(width 0.05)
				(type solid)
			)
			(fill none)
			(layer "F.CrtYd")
		)
		(fp_rect
			(start -0.55 -0.35)
			(end 0.55 0.35)
			(stroke
				(width 0.15)
				(type solid)
			)
			(fill none)
			(layer "F.Fab")
		)
		(fp_text user "License: Apache-2.0"
			(at -0.8 5.6 90)
			(layer "F.Fab")
			(hide yes)
			(effects
				(font
					(size 0.7 0.7)
					(thickness 0.15)
				)
				(justify left bottom)
			)
		)
		(fp_text user "Author: Antmicro"
			(at -0.8 4.4 90)
			(layer "F.Fab")
			(hide yes)
			(effects
				(font
					(size 0.7 0.7)
					(thickness 0.15)
				)
				(justify left bottom)
			)
		)
		(fp_text user "${REFERENCE}"
			(at -0.8 3.2 90)
			(layer "F.Fab")
			(hide yes)
			(effects
				(font
					(size 0.7 0.7)
					(thickness 0.15)
				)
				(justify left bottom)
			)
		)
		(pad "1" smd roundrect
			(at -0.351 0 90)
			(size 0.3 0.5)
			(layers "F.Cu" "F.Paste" "F.Mask")
			(roundrect_rratio 0.25)
			(net 471 "PCIE3_CLK_N")
			(pinfunction "C")
			(pintype "passive")
		)
		(pad "2" smd roundrect
			(at 0.349 0 90)
			(size 0.3 0.5)
			(layers "F.Cu" "F.Paste" "F.Mask")
			(roundrect_rratio 0.25)
			(net 1 "GND")
			(pinfunction "A")
			(pintype "passive")
		)
	)
	(footprint "antmicro-footprints:R_0603_1608Metric"
		(layer "F.Cu")
		(at 68.525 91.675 90)
		(descr "Resistor SMD 0603")
		(tags "resistor SMD 0603")
		(property "Reference" "R178"
			(at -4.005 0.46 90)
			(layer "F.SilkS")
			(effects
				(font
					(size 0.7 0.7)
					(thickness 0.15)
				)
				(justify left bottom)
			)
		)
		(property "Value" "R_0R_22.4A_0603"
			(at 0 1.6 90)
			(layer "F.Fab")
			(effects
				(font
					(size 0.7 0.7)
					(thickness 0.15)
				)
				(justify left bottom)
			)
		)
		(property "Footprint" "antmicro-footprints:R_0603_1608Metric"
			(at 0 0 90)
			(layer "F.Fab")
			(hide yes)
			(effects
				(font
					(size 1.27 1.27)
					(thickness 0.15)
				)
			)
		)
		(property "Datasheet" "https://fscdn.rohm.com/en/products/databook/datasheet/passive/resistor/chip_resistor/pmr-jpw-e.pdf"
			(at 0 0 90)
			(layer "F.Fab")
			(hide yes)
			(effects
				(font
					(size 1.27 1.27)
					(thickness 0.15)
				)
			)
		)
		(property "Author" "Antmicro"
			(at 160.11 23.23 0)
			(layer "F.Fab")
			(hide yes)
			(effects
				(font
					(size 1 1)
					(thickness 0.15)
				)
			)
		)
		(property "License" "Apache-2.0"
			(at 160.11 23.23 0)
			(layer "F.Fab")
			(hide yes)
			(effects
				(font
					(size 1 1)
					(thickness 0.15)
				)
			)
		)
		(property "MPN" "PMR03EZPJ000"
			(at 160.11 23.23 0)
			(layer "F.Fab")
			(hide yes)
			(effects
				(font
					(size 1 1)
					(thickness 0.15)
				)
			)
		)
		(property "Manufacturer" "ROHM Semiconductor"
			(at 160.11 23.23 0)
			(layer "F.Fab")
			(hide yes)
			(effects
				(font
					(size 1 1)
					(thickness 0.15)
				)
			)
		)
		(property "Max. Curr." "22.4A"
			(at 160.11 23.23 0)
			(layer "F.Fab")
			(hide yes)
			(effects
				(font
					(size 1 1)
					(thickness 0.15)
				)
			)
		)
		(property "Tolerance" "template_tolerance"
			(at 160.11 23.23 0)
			(layer "F.Fab")
			(hide yes)
			(effects
				(font
					(size 1 1)
					(thickness 0.15)
				)
			)
		)
		(property "Val" "0R"
			(at 160.11 23.23 0)
			(layer "F.Fab")
			(hide yes)
			(effects
				(font
					(size 1 1)
					(thickness 0.15)
				)
			)
		)
		(sheetname "Supply")
		(sheetfile "supply.kicad_sch")
		(attr smd)
		(fp_line
			(start -0.15 -0.4)
			(end 0.15 -0.4)
			(stroke
				(width 0.15)
				(type solid)
			)
			(layer "F.SilkS")
		)
		(fp_line
			(start -0.15 0.4)
			(end 0.15 0.4)
			(stroke
				(width 0.15)
				(type solid)
			)
			(layer "F.SilkS")
		)
		(fp_rect
			(start -1.25 -0.65)
			(end 1.25 0.65)
			(stroke
				(width 0.05)
				(type solid)
			)
			(fill none)
			(layer "F.CrtYd")
		)
		(fp_rect
			(start -0.8 -0.4)
			(end 0.8 0.4)
			(stroke
				(width 0.15)
				(type solid)
			)
			(fill none)
			(layer "F.Fab")
		)
		(fp_text user "${REFERENCE}"
			(at -1.25 3.898 90)
			(layer "F.Fab")
			(hide yes)
			(effects
				(font
					(size 0.7 0.7)
					(thickness 0.15)
				)
				(justify left bottom)
			)
		)
		(fp_text user "License: Apache-2.0"
			(at -1.25 5.9 90)
			(layer "F.Fab")
			(hide yes)
			(effects
				(font
					(size 0.7 0.7)
					(thickness 0.15)
				)
				(justify left bottom)
			)
		)
		(fp_text user "Author: Antmicro"
			(at -1.25 4.9 90)
			(layer "F.Fab")
			(hide yes)
			(effects
				(font
					(size 0.7 0.7)
					(thickness 0.15)
				)
				(justify left bottom)
			)
		)
		(pad "1" smd roundrect
			(at -0.7 0 90)
			(size 0.8 1)
			(layers "F.Cu" "F.Paste" "F.Mask")
			(roundrect_rratio 0.2)
			(net 641 "/Supply/3V3_OUT")
			(pintype "passive")
		)
		(pad "2" smd roundrect
			(at 0.7 0 90)
			(size 0.8 1)
			(layers "F.Cu" "F.Paste" "F.Mask")
			(roundrect_rratio 0.2)
			(net 87 "+3V3")
			(pintype "passive")
		)
	)
	(footprint "antmicro-footprints:R_0402_1005Metric"
		(layer "F.Cu")
		(at 105.154938 107.045)
		(descr "Resistor SMD 0402")
		(tags "resistor SMD 0402")
		(property "Reference" "R202"
			(at -3.654938 0.405 0)
			(layer "F.SilkS")
			(effects
				(font
					(size 0.7 0.7)
					(thickness 0.15)
				)
				(justify left bottom)
			)
		)
		(property "Value" "R_0R_0402"
			(at 0 1.4 0)
			(layer "F.Fab")
			(effects
				(font
					(size 0.7 0.7)
					(thickness 0.15)
				)
				(justify left bottom)
			)
		)
		(property "Footprint" "antmicro-footprints:R_0402_1005Metric"
			(at 0 0 0)
			(layer "F.Fab")
			(hide yes)
			(effects
				(font
					(size 1.27 1.27)
					(thickness 0.15)
				)
			)
		)
		(property "Datasheet" "https://industrial.panasonic.com/cdbs/www-data/pdf/RDA0000/AOA0000C301.pdf"
			(at 0 0 0)
			(layer "F.Fab")
			(hide yes)
			(effects
				(font
					(size 1.27 1.27)
					(thickness 0.15)
				)
			)
		)
		(property "Author" "Antmicro"
			(at 0 0 0)
			(layer "F.Fab")
			(hide yes)
			(effects
				(font
					(size 1 1)
					(thickness 0.15)
				)
			)
		)
		(property "Current" "1A"
			(at 0 0 0)
			(layer "F.Fab")
			(hide yes)
			(effects
				(font
					(size 1 1)
					(thickness 0.15)
				)
			)
		)
		(property "License" "Apache-2.0"
			(at 0 0 0)
			(layer "F.Fab")
			(hide yes)
			(effects
				(font
					(size 1 1)
					(thickness 0.15)
				)
			)
		)
		(property "MPN" "ERJ2GE0R00X"
			(at 0 0 0)
			(layer "F.Fab")
			(hide yes)
			(effects
				(font
					(size 1 1)
					(thickness 0.15)
				)
			)
		)
		(property "Manufacturer" "Panasonic"
			(at 0 0 0)
			(layer "F.Fab")
			(hide yes)
			(effects
				(font
					(size 1 1)
					(thickness 0.15)
				)
			)
		)
		(property "Tolerance" ""
			(at 0 0 0)
			(layer "F.Fab")
			(hide yes)
			(effects
				(font
					(size 1 1)
					(thickness 0.15)
				)
			)
		)
		(property "Val" "0R"
			(at 0 0 0)
			(layer "F.Fab")
			(hide yes)
			(effects
				(font
					(size 1 1)
					(thickness 0.15)
				)
			)
		)
		(sheetname "USB3")
		(sheetfile "usb3.kicad_sch")
		(attr smd)
		(fp_rect
			(start -0.925 -0.47)
			(end 0.925 0.47)
			(stroke
				(width 0.05)
				(type default)
			)
			(fill none)
			(layer "F.CrtYd")
		)
		(fp_rect
			(start -0.5 -0.25)
			(end 0.5 0.25)
			(stroke
				(width 0.15)
				(type solid)
			)
			(fill none)
			(layer "F.Fab")
		)
		(fp_text user "${REFERENCE}"
			(at -0.95 3.168 0)
			(layer "F.Fab")
			(hide yes)
			(effects
				(font
					(size 0.7 0.7)
					(thickness 0.15)
				)
				(justify left bottom)
			)
		)
		(fp_text user "License: Apache-2.0"
			(at -0.95 5.169 0)
			(layer "F.Fab")
			(hide yes)
			(effects
				(font
					(size 0.7 0.7)
					(thickness 0.15)
				)
				(justify left bottom)
			)
		)
		(fp_text user "Author: Antmicro"
			(at -0.95 4.169 0)
			(layer "F.Fab")
			(hide yes)
			(effects
				(font
					(size 0.7 0.7)
					(thickness 0.15)
				)
				(justify left bottom)
			)
		)
		(pad "1" smd roundrect
			(at -0.48 0)
			(size 0.59 0.64)
			(layers "F.Cu" "F.Paste" "F.Mask")
			(roundrect_rratio 0.25)
			(net 173 "USBSS2_TX_P")
			(pintype "passive")
		)
		(pad "2" smd roundrect
			(at 0.48 0)
			(size 0.59 0.64)
			(layers "F.Cu" "F.Paste" "F.Mask")
			(roundrect_rratio 0.25)
			(net 610 "/USB3/USBSS1_C_TX_N")
			(pintype "passive")
		)
	)
	(footprint "antmicro-footprints:C_Pol_EIA-X"
		(layer "F.Cu")
		(at 63.505 83.59)
		(property "Reference" "C1"
			(at -5.995 1.29 0)
			(layer "F.SilkS")
			(effects
				(font
					(size 0.7 0.7)
					(thickness 0.15)
				)
				(justify left bottom)
			)
		)
		(property "Value" "C_Pol_100u_25V_KEMET-T521-D-107"
			(at 0 3.3 0)
			(layer "F.Fab")
			(effects
				(font
					(size 0.7 0.7)
					(thickness 0.15)
				)
				(justify left bottom)
			)
		)
		(property "Footprint" "antmicro-footprints:C_Pol_EIA-X"
			(at 0 0 0)
			(layer "F.Fab")
			(hide yes)
			(effects
				(font
					(size 1.27 1.27)
					(thickness 0.15)
				)
			)
		)
		(property "Datasheet" "https://content.kemet.com/datasheets/KEM_T2076_T52X-530.pdf"
			(at 0 0 0)
			(layer "F.Fab")
			(hide yes)
			(effects
				(font
					(size 1.27 1.27)
					(thickness 0.15)
				)
			)
		)
		(property "Description" "Surface Mount Tantalum Capacitor, 100 µF, 25 V, 2917 [7343 Metric], ± 20%, 0.04 ohm"
			(at 0 0 0)
			(layer "F.Fab")
			(hide yes)
			(effects
				(font
					(size 1.27 1.27)
					(thickness 0.15)
				)
			)
		)
		(property "Val" "100u"
			(at 0 0 0)
			(unlocked yes)
			(layer "F.Fab")
			(hide yes)
			(effects
				(font
					(size 1 1)
					(thickness 0.15)
				)
			)
		)
		(property "MPN" "T521D107M025ATE040"
			(at 0 0 0)
			(unlocked yes)
			(layer "F.Fab")
			(hide yes)
			(effects
				(font
					(size 1 1)
					(thickness 0.15)
				)
			)
		)
		(property "Manufacturer" "KEMET"
			(at 0 0 0)
			(unlocked yes)
			(layer "F.Fab")
			(hide yes)
			(effects
				(font
					(size 1 1)
					(thickness 0.15)
				)
			)
		)
		(property "License" "Apache-2.0"
			(at 0 0 0)
			(unlocked yes)
			(layer "F.Fab")
			(hide yes)
			(effects
				(font
					(size 1 1)
					(thickness 0.15)
				)
			)
		)
		(property "Author" "Antmicro"
			(at 0 0 0)
			(unlocked yes)
			(layer "F.Fab")
			(hide yes)
			(effects
				(font
					(size 1 1)
					(thickness 0.15)
				)
			)
		)
		(property "Voltage" "25V"
			(at 0 0 0)
			(unlocked yes)
			(layer "F.Fab")
			(hide yes)
			(effects
				(font
					(size 1 1)
					(thickness 0.15)
				)
			)
		)
		(property "Dielectric" "template_dielectric"
			(at 0 0 0)
			(unlocked yes)
			(layer "F.Fab")
			(hide yes)
			(effects
				(font
					(size 1 1)
					(thickness 0.15)
				)
			)
		)
		(sheetname "SoM")
		(sheetfile "som.kicad_sch")
		(attr smd)
		(fp_line
			(start -4.5 -1.8)
			(end -4 -1.8)
			(stroke
				(width 0.15)
				(type solid)
			)
			(layer "F.SilkS")
		)
		(fp_line
			(start -4.25 -2.05)
			(end -4.25 -1.551)
			(stroke
				(width 0.15)
				(type solid)
			)
			(layer "F.SilkS")
		)
		(fp_line
			(start -3.6 -2.2)
			(end 3.6 -2.2)
			(stroke
				(width 0.15)
				(type solid)
			)
			(layer "F.SilkS")
		)
		(fp_line
			(start -3.6 -1.44)
			(end -3.6 -2.2)
			(stroke
				(width 0.15)
				(type solid)
			)
			(layer "F.SilkS")
		)
		(fp_line
			(start -3.6 2.2)
			(end -3.6 1.44)
			(stroke
				(width 0.15)
				(type solid)
			)
			(layer "F.SilkS")
		)
		(fp_line
			(start -3.6 2.2)
			(end 3.6 2.2)
			(stroke
				(width 0.15)
				(type solid)
			)
			(layer "F.SilkS")
		)
		(fp_line
			(start 3.6 -1.44)
			(end 3.6 -2.2)
			(stroke
				(width 0.15)
				(type solid)
			)
			(layer "F.SilkS")
		)
		(fp_line
			(start 3.6 2.2)
			(end 3.6 1.44)
			(stroke
				(width 0.15)
				(type solid)
			)
			(layer "F.SilkS")
		)
		(fp_line
			(start -4.7 -1.4)
			(end -4.7 1.45)
			(stroke
				(width 0.05)
				(type solid)
			)
			(layer "F.CrtYd")
		)
		(fp_line
			(start -4.7 -1.4)
			(end -3.75 -1.4)
			(stroke
				(width 0.05)
				(type solid)
			)
			(layer "F.CrtYd")
		)
		(fp_line
			(start -3.75 -2.4)
			(end -3.75 -1.4)
			(stroke
				(width 0.05)
				(type solid)
			)
			(layer "F.CrtYd")
		)
		(fp_line
			(start -3.75 -2.4)
			(end 3.8 -2.4)
			(stroke
				(width 0.05)
				(type solid)
			)
			(layer "F.CrtYd")
		)
		(fp_line
			(start -3.75 1.45)
			(end -4.7 1.45)
			(stroke
				(width 0.05)
				(type solid)
			)
			(layer "F.CrtYd")
		)
		(fp_line
			(start -3.75 1.45)
			(end -3.75 2.4)
			(stroke
				(width 0.05)
				(type solid)
			)
			(layer "F.CrtYd")
		)
		(fp_line
			(start -3.75 2.4)
			(end 3.8 2.4)
			(stroke
				(width 0.05)
				(type solid)
			)
			(layer "F.CrtYd")
		)
		(fp_line
			(start 3.8 -1.45)
			(end 3.8 -2.4)
			(stroke
				(width 0.05)
				(type solid)
			)
			(layer "F.CrtYd")
		)
		(fp_line
			(start 3.8 -1.45)
			(end 4.75 -1.45)
			(stroke
				(width 0.05)
				(type solid)
			)
			(layer "F.CrtYd")
		)
		(fp_line
			(start 3.8 2.4)
			(end 3.8 1.4)
			(stroke
				(width 0.05)
				(type solid)
			)
			(layer "F.CrtYd")
		)
		(fp_line
			(start 4.75 1.4)
			(end 3.8 1.4)
			(stroke
				(width 0.05)
				(type solid)
			)
			(layer "F.CrtYd")
		)
		(fp_line
			(start 4.75 1.4)
			(end 4.75 -1.45)
			(stroke
				(width 0.05)
				(type solid)
			)
			(layer "F.CrtYd")
		)
		(fp_line
			(start -3.799 -2.3)
			(end 3.799 -2.3)
			(stroke
				(width 0.15)
				(type solid)
			)
			(layer "F.Fab")
		)
		(fp_line
			(start -3.799 2.3)
			(end -3.799 -2.3)
			(stroke
				(width 0.15)
				(type solid)
			)
			(layer "F.Fab")
		)
		(fp_line
			(start 3.799 -2.3)
			(end 3.799 2.3)
			(stroke
				(width 0.15)
				(type solid)
			)
			(layer "F.Fab")
		)
		(fp_line
			(start 3.799 2.3)
			(end -3.799 2.3)
			(stroke
				(width 0.15)
				(type solid)
			)
			(layer "F.Fab")
		)
		(fp_text user "License: Apache-2.0"
			(at -4.5 6.79 0)
			(layer "F.Fab")
			(hide yes)
			(effects
				(font
					(size 0.7 0.7)
					(thickness 0.15)
				)
				(justify left bottom)
			)
		)
		(fp_text user "Author: Antmicro"
			(at -4.5 5.59 0)
			(layer "F.Fab")
			(hide yes)
			(effects
				(font
					(size 0.7 0.7)
					(thickness 0.15)
				)
				(justify left bottom)
			)
		)
		(fp_text user "${REFERENCE}"
			(at -4.5 4.39 0)
			(layer "F.Fab")
			(hide yes)
			(effects
				(font
					(size 0.7 0.7)
					(thickness 0.15)
				)
				(justify left bottom)
			)
		)
		(pad "1" smd roundrect
			(at -3.25 0)
			(size 2.5 2.33)
			(layers "F.Cu" "F.Paste" "F.Mask")
			(roundrect_rratio 0.1)
			(net 438 "/SoM/SoM_VIN")
			(pintype "passive")
		)
		(pad "2" smd roundrect
			(at 3.25 0)
			(size 2.5 2.33)
			(layers "F.Cu" "F.Paste" "F.Mask")
			(roundrect_rratio 0.1)
			(net 1 "GND")
			(pintype "passive")
		)
	)
	(footprint "antmicro-footprints:R_0402_1005Metric"
		(layer "F.Cu")
		(at 85.4 115.8)
		(descr "Resistor SMD 0402")
		(tags "resistor SMD 0402")
		(property "Reference" "R227"
			(at -3.96 3.79 0)
			(layer "F.SilkS")
			(effects
				(font
					(size 0.7 0.7)
					(thickness 0.15)
				)
				(justify left bottom)
			)
		)
		(property "Value" "R_2k2_0402"
			(at 0 1.4 0)
			(layer "F.Fab")
			(effects
				(font
					(size 0.7 0.7)
					(thickness 0.15)
				)
				(justify left bottom)
			)
		)
		(property "Footprint" "antmicro-footprints:R_0402_1005Metric"
			(at 0 0 0)
			(layer "F.Fab")
			(hide yes)
			(effects
				(font
					(size 1.27 1.27)
					(thickness 0.15)
				)
			)
		)
		(property "Datasheet" "https://www.bourns.com/docs/product-datasheets/cr.pdf"
			(at 0 0 0)
			(layer "F.Fab")
			(hide yes)
			(effects
				(font
					(size 1.27 1.27)
					(thickness 0.15)
				)
			)
		)
		(property "Author" "Antmicro"
			(at 0 0 0)
			(layer "F.Fab")
			(hide yes)
			(effects
				(font
					(size 1 1)
					(thickness 0.15)
				)
			)
		)
		(property "License" "Apache-2.0"
			(at 0 0 0)
			(layer "F.Fab")
			(hide yes)
			(effects
				(font
					(size 1 1)
					(thickness 0.15)
				)
			)
		)
		(property "MPN" "CR0402-FX-2201GLF"
			(at 0 0 0)
			(layer "F.Fab")
			(hide yes)
			(effects
				(font
					(size 1 1)
					(thickness 0.15)
				)
			)
		)
		(property "Manufacturer" "Bourns"
			(at 0 0 0)
			(layer "F.Fab")
			(hide yes)
			(effects
				(font
					(size 1 1)
					(thickness 0.15)
				)
			)
		)
		(property "Tolerance" "1%"
			(at 0 0 0)
			(layer "F.Fab")
			(hide yes)
			(effects
				(font
					(size 1 1)
					(thickness 0.15)
				)
			)
		)
		(property "Val" "2k2"
			(at 0 0 0)
			(layer "F.Fab")
			(hide yes)
			(effects
				(font
					(size 1 1)
					(thickness 0.15)
				)
			)
		)
		(sheetname "HDMI")
		(sheetfile "hdmi.kicad_sch")
		(attr smd)
		(fp_rect
			(start -0.925 -0.47)
			(end 0.925 0.47)
			(stroke
				(width 0.05)
				(type default)
			)
			(fill none)
			(layer "F.CrtYd")
		)
		(fp_rect
			(start -0.5 -0.25)
			(end 0.5 0.25)
			(stroke
				(width 0.15)
				(type solid)
			)
			(fill none)
			(layer "F.Fab")
		)
		(fp_text user "License: Apache-2.0"
			(at -0.95 5.169 0)
			(layer "F.Fab")
			(hide yes)
			(effects
				(font
					(size 0.7 0.7)
					(thickness 0.15)
				)
				(justify left bottom)
			)
		)
		(fp_text user "Author: Antmicro"
			(at -0.95 4.169 0)
			(layer "F.Fab")
			(hide yes)
			(effects
				(font
					(size 0.7 0.7)
					(thickness 0.15)
				)
				(justify left bottom)
			)
		)
		(fp_text user "${REFERENCE}"
			(at -0.95 3.168 0)
			(layer "F.Fab")
			(hide yes)
			(effects
				(font
					(size 0.7 0.7)
					(thickness 0.15)
				)
				(justify left bottom)
			)
		)
		(pad "1" smd roundrect
			(at -0.48 0)
			(size 0.59 0.64)
			(layers "F.Cu" "F.Paste" "F.Mask")
			(roundrect_rratio 0.25)
			(net 1 "GND")
			(pintype "passive")
		)
		(pad "2" smd roundrect
			(at 0.48 0)
			(size 0.59 0.64)
			(layers "F.Cu" "F.Paste" "F.Mask")
			(roundrect_rratio 0.25)
			(net 529 "/HDMI/HDMI_HPD_5V")
			(pintype "passive")
		)
	)
	(footprint "antmicro-footprints:SOT-523"
		(layer "F.Cu")
		(at 136.3 121.34 180)
		(property "Reference" "Q9"
			(at -2.05 -0.52 -90)
			(layer "F.SilkS")
			(effects
				(font
					(size 0.7 0.7)
					(thickness 0.15)
				)
				(justify left bottom)
			)
		)
		(property "Value" "PJE138K"
			(at 0.1 1.824 180)
			(layer "F.Fab")
			(effects
				(font
					(size 0.7 0.7)
					(thickness 0.15)
				)
				(justify left bottom)
			)
		)
		(property "Footprint" "antmicro-footprints:SOT-523"
			(at 0 0 180)
			(layer "F.Fab")
			(hide yes)
			(effects
				(font
					(size 1.27 1.27)
					(thickness 0.15)
				)
			)
		)
		(property "Datasheet" "https://www.mouser.com/datasheet/2/1057/PJE138K-1876698.pdf"
			(at 0 0 180)
			(layer "F.Fab")
			(hide yes)
			(effects
				(font
					(size 1.27 1.27)
					(thickness 0.15)
				)
			)
		)
		(property "Author" "Antmicro"
			(at 272.6 242.68 0)
			(layer "F.Fab")
			(hide yes)
			(effects
				(font
					(size 1 1)
					(thickness 0.15)
				)
			)
		)
		(property "License" "Apache-2.0"
			(at 272.6 242.68 0)
			(layer "F.Fab")
			(hide yes)
			(effects
				(font
					(size 1 1)
					(thickness 0.15)
				)
			)
		)
		(property "MPN" "PJE138K_R1_00001"
			(at 272.6 242.68 0)
			(layer "F.Fab")
			(hide yes)
			(effects
				(font
					(size 1 1)
					(thickness 0.15)
				)
			)
		)
		(property "Manufacturer" "PANJIT"
			(at 272.6 242.68 0)
			(layer "F.Fab")
			(hide yes)
			(effects
				(font
					(size 1 1)
					(thickness 0.15)
				)
			)
		)
		(sheetname "Peripherals")
		(sheetfile "peripherals.kicad_sch")
		(attr smd)
		(fp_line
			(start -0.277 -0.551)
			(end -0.277 -0.75)
			(stroke
				(width 0.15)
				(type solid)
			)
			(layer "F.SilkS")
		)
		(fp_line
			(start -0.725 -0.551)
			(end -0.277 -0.551)
			(stroke
				(width 0.15)
				(type solid)
			)
			(layer "F.SilkS")
		)
		(fp_line
			(start -0.927 -0.051)
			(end -0.927 -0.351)
			(stroke
				(width 0.15)
				(type solid)
			)
			(layer "F.SilkS")
		)
		(fp_line
			(start -0.927 -0.351)
			(end -0.725 -0.551)
			(stroke
				(width 0.15)
				(type solid)
			)
			(layer "F.SilkS")
		)
		(fp_circle
			(center -0.9652 0.9652)
			(end -0.9152 0.9652)
			(stroke
				(width 0.15)
				(type solid)
			)
			(fill solid)
			(layer "F.SilkS")
		)
		(fp_line
			(start 1.1 -1.16)
			(end 1.1 1.15)
			(stroke
				(width 0.05)
				(type solid)
			)
			(layer "F.CrtYd")
		)
		(fp_line
			(start -1.12 1.15)
			(end 1.1 1.15)
			(stroke
				(width 0.05)
				(type solid)
			)
			(layer "F.CrtYd")
		)
		(fp_line
			(start -1.12 -1.16)
			(end 1.1 -1.16)
			(stroke
				(width 0.05)
				(type solid)
			)
			(layer "F.CrtYd")
		)
		(fp_line
			(start -1.12 -1.16)
			(end -1.12 1.15)
			(stroke
				(width 0.05)
				(type solid)
			)
			(layer "F.CrtYd")
		)
		(fp_line
			(start 0.8 0.424)
			(end -0.802 0.424)
			(stroke
				(width 0.15)
				(type solid)
			)
			(layer "F.Fab")
		)
		(fp_line
			(start 0.8 -0.425)
			(end 0.8 0.424)
			(stroke
				(width 0.15)
				(type solid)
			)
			(layer "F.Fab")
		)
		(fp_line
			(start 0.8 -0.425)
			(end -0.652 -0.425)
			(stroke
				(width 0.15)
				(type solid)
			)
			(layer "F.Fab")
		)
		(fp_line
			(start -0.652 -0.425)
			(end -0.802 -0.276)
			(stroke
				(width 0.15)
				(type solid)
			)
			(layer "F.Fab")
		)
		(fp_line
			(start -0.802 -0.276)
			(end -0.802 0.424)
			(stroke
				(width 0.15)
				(type solid)
			)
			(layer "F.Fab")
		)
		(fp_circle
			(center -0.9652 0.9652)
			(end -0.9144 0.9652)
			(stroke
				(width 0.15)
				(type solid)
			)
			(fill none)
			(layer "F.Fab")
		)
		(fp_text user "License: Apache-2.0"
			(at -1.12 5.024 180)
			(layer "F.Fab")
			(hide yes)
			(effects
				(font
					(size 0.7 0.7)
					(thickness 0.15)
				)
				(justify left bottom)
			)
		)
		(fp_text user "${REFERENCE}"
			(at -1.12 3.824 180)
			(layer "F.Fab")
			(hide yes)
			(effects
				(font
					(size 0.7 0.7)
					(thickness 0.15)
				)
				(justify left bottom)
			)
		)
		(fp_text user "Author: Antmicro"
			(at -1.12 6.224 180)
			(layer "F.Fab")
			(hide yes)
			(effects
				(font
					(size 0.7 0.7)
					(thickness 0.15)
				)
				(justify left bottom)
			)
		)
		(pad "1" smd rect
			(at -0.5 0.65 180)
			(size 0.4 0.51)
			(layers "F.Cu" "F.Paste" "F.Mask")
			(net 440 "USER_LED0")
			(pinfunction "G")
			(pintype "passive")
		)
		(pad "2" smd rect
			(at 0.498 0.65 180)
			(size 0.4 0.51)
			(layers "F.Cu" "F.Paste" "F.Mask")
			(net 1 "GND")
			(pinfunction "S")
			(pintype "passive")
		)
		(pad "3" smd rect
			(at 0 -0.652 180)
			(size 0.4 0.51)
			(layers "F.Cu" "F.Paste" "F.Mask")
			(net 164 "Net-(D26-C)")
			(pinfunction "D")
			(pintype "passive")
		)
	)
	(footprint "antmicro-footprints:Conn_Molex_PicoBlade_1x4_0533980471"
		(layer "F.Cu")
		(at 51.93 109.95 -90)
		(descr "Molex PicoBlade series connector, 53398-0471")
		(tags "connector Molex PicoBlade side entry")
		(property "Reference" "J10"
			(at -5.825 0.33 0)
			(layer "F.SilkS")
			(effects
				(font
					(size 0.7 0.7)
					(thickness 0.15)
				)
				(justify left bottom)
			)
		)
		(property "Value" "Molex_PicoBlade_1x4_0533980471"
			(at -5.8 3.7 -90)
			(layer "F.Fab")
			(effects
				(font
					(size 0.7 0.7)
					(thickness 0.15)
				)
				(justify left bottom)
			)
		)
		(property "Footprint" "antmicro-footprints:Conn_Molex_PicoBlade_1x4_0533980471"
			(at 0 0 -90)
			(layer "F.Fab")
			(hide yes)
			(effects
				(font
					(size 1.27 1.27)
					(thickness 0.15)
				)
			)
		)
		(property "Datasheet" "https://www.molex.com/molex/products/part-detail/pcb_headers/0533980471"
			(at 0 0 -90)
			(layer "F.Fab")
			(hide yes)
			(effects
				(font
					(size 1.27 1.27)
					(thickness 0.15)
				)
			)
		)
		(property "Author" "Antmicro"
			(at -58.02 161.88 0)
			(layer "F.Fab")
			(hide yes)
			(effects
				(font
					(size 1 1)
					(thickness 0.15)
				)
			)
		)
		(property "License" "Apache-2.0"
			(at -58.02 161.88 0)
			(layer "F.Fab")
			(hide yes)
			(effects
				(font
					(size 1 1)
					(thickness 0.15)
				)
			)
		)
		(property "MPN" "0533980471"
			(at -58.02 161.88 0)
			(layer "F.Fab")
			(hide yes)
			(effects
				(font
					(size 1 1)
					(thickness 0.15)
				)
			)
		)
		(property "Manufacturer" "Molex"
			(at -58.02 161.88 0)
			(layer "F.Fab")
			(hide yes)
			(effects
				(font
					(size 1 1)
					(thickness 0.15)
				)
			)
		)
		(sheetname "Peripherals")
		(sheetfile "peripherals.kicad_sch")
		(attr smd)
		(fp_line
			(start -3.117 2.209)
			(end 3.115 2.209)
			(stroke
				(width 0.15)
				(type solid)
			)
			(layer "F.SilkS")
		)
		(fp_line
			(start -3.485 -0.76)
			(end -3.485 -1.71)
			(stroke
				(width 0.15)
				(type solid)
			)
			(layer "F.SilkS")
		)
		(fp_line
			(start 3.483 -0.76)
			(end 3.483 -1.71)
			(stroke
				(width 0.15)
				(type solid)
			)
			(layer "F.SilkS")
		)
		(fp_line
			(start -3.485 -1.71)
			(end -2.536 -1.71)
			(stroke
				(width 0.15)
				(type solid)
			)
			(layer "F.SilkS")
		)
		(fp_line
			(start -2.536 -1.71)
			(end -2.536 -2.4)
			(stroke
				(width 0.15)
				(type solid)
			)
			(layer "F.SilkS")
		)
		(fp_line
			(start 3.483 -1.71)
			(end 2.535 -1.71)
			(stroke
				(width 0.15)
				(type solid)
			)
			(layer "F.SilkS")
		)
		(fp_rect
			(start -5.677 -2.601)
			(end 5.675 2.7)
			(stroke
				(width 0.05)
				(type solid)
			)
			(fill none)
			(layer "F.CrtYd")
		)
		(fp_line
			(start -4.875 2.1)
			(end -5.077 1.898)
			(stroke
				(width 0.15)
				(type solid)
			)
			(layer "F.Fab")
		)
		(fp_line
			(start -3.375 2.1)
			(end -4.875 2.1)
			(stroke
				(width 0.15)
				(type solid)
			)
			(layer "F.Fab")
		)
		(fp_line
			(start -3.375 2.1)
			(end 3.374 2.1)
			(stroke
				(width 0.15)
				(type solid)
			)
			(layer "F.Fab")
		)
		(fp_line
			(start 3.374 2.1)
			(end 4.873 2.1)
			(stroke
				(width 0.15)
				(type solid)
			)
			(layer "F.Fab")
		)
		(fp_line
			(start 4.873 2.1)
			(end 5.075 1.898)
			(stroke
				(width 0.15)
				(type solid)
			)
			(layer "F.Fab")
		)
		(fp_line
			(start -5.077 1.898)
			(end -5.077 0.099)
			(stroke
				(width 0.15)
				(type solid)
			)
			(layer "F.Fab")
		)
		(fp_line
			(start 5.075 1.898)
			(end 5.075 0.099)
			(stroke
				(width 0.15)
				(type solid)
			)
			(layer "F.Fab")
		)
		(fp_line
			(start -2.025 1.175)
			(end -1.726 1.175)
			(stroke
				(width 0.15)
				(type solid)
			)
			(layer "F.Fab")
		)
		(fp_line
			(start -1.726 1.175)
			(end -1.726 0.575)
			(stroke
				(width 0.15)
				(type solid)
			)
			(layer "F.Fab")
		)
		(fp_line
			(start -0.777 1.175)
			(end -0.476 1.175)
			(stroke
				(width 0.15)
				(type solid)
			)
			(layer "F.Fab")
		)
		(fp_line
			(start -0.476 1.175)
			(end -0.476 0.575)
			(stroke
				(width 0.15)
				(type solid)
			)
			(layer "F.Fab")
		)
		(fp_line
			(start 0.474 1.175)
			(end 0.775 1.175)
			(stroke
				(width 0.15)
				(type solid)
			)
			(layer "F.Fab")
		)
		(fp_line
			(start 0.775 1.175)
			(end 0.775 0.575)
			(stroke
				(width 0.15)
				(type solid)
			)
			(layer "F.Fab")
		)
		(fp_line
			(start 1.725 1.175)
			(end 2.023 1.175)
			(stroke
				(width 0.15)
				(type solid)
			)
			(layer "F.Fab")
		)
		(fp_line
			(start 2.023 1.175)
			(end 2.023 0.575)
			(stroke
				(width 0.15)
				(type solid)
			)
			(layer "F.Fab")
		)
		(fp_line
			(start -2.025 0.575)
			(end -2.025 1.175)
			(stroke
				(width 0.15)
				(type solid)
			)
			(layer "F.Fab")
		)
		(fp_line
			(start -1.726 0.575)
			(end -2.025 0.575)
			(stroke
				(width 0.15)
				(type solid)
			)
			(layer "F.Fab")
		)
		(fp_line
			(start -0.777 0.575)
			(end -0.777 1.175)
			(stroke
				(width 0.15)
				(type solid)
			)
			(layer "F.Fab")
		)
		(fp_line
			(start -0.476 0.575)
			(end -0.777 0.575)
			(stroke
				(width 0.15)
				(type solid)
			)
			(layer "F.Fab")
		)
		(fp_line
			(start 0.474 0.575)
			(end 0.474 1.175)
			(stroke
				(width 0.15)
				(type solid)
			)
			(layer "F.Fab")
		)
		(fp_line
			(start 0.775 0.575)
			(end 0.474 0.575)
			(stroke
				(width 0.15)
				(type solid)
			)
			(layer "F.Fab")
		)
		(fp_line
			(start 1.725 0.575)
			(end 1.725 1.175)
			(stroke
				(width 0.15)
				(type solid)
			)
			(layer "F.Fab")
		)
		(fp_line
			(start 2.023 0.575)
			(end 1.725 0.575)
			(stroke
				(width 0.15)
				(type solid)
			)
			(layer "F.Fab")
		)
		(fp_line
			(start -5.077 0.099)
			(end -4.875 -0.101)
			(stroke
				(width 0.15)
				(type solid)
			)
			(layer "F.Fab")
		)
		(fp_line
			(start 5.075 0.099)
			(end 4.873 -0.101)
			(stroke
				(width 0.15)
				(type solid)
			)
			(layer "F.Fab")
		)
		(fp_line
			(start -4.875 -0.101)
			(end -4.875 -0.701)
			(stroke
				(width 0.15)
				(type solid)
			)
			(layer "F.Fab")
		)
		(fp_line
			(start 4.873 -0.101)
			(end 4.873 -0.701)
			(stroke
				(width 0.15)
				(type solid)
			)
			(layer "F.Fab")
		)
		(fp_line
			(start -4.875 -0.701)
			(end -3.375 -0.701)
			(stroke
				(width 0.15)
				(type solid)
			)
			(layer "F.Fab")
		)
		(fp_line
			(start 4.873 -0.701)
			(end 3.374 -0.701)
			(stroke
				(width 0.15)
				(type solid)
			)
			(layer "F.Fab")
		)
		(fp_line
			(start -1.875 -0.893)
			(end -1.375 -1.601)
			(stroke
				(width 0.15)
				(type solid)
			)
			(layer "F.Fab")
		)
		(fp_line
			(start -3.375 -1.601)
			(end -3.375 2.1)
			(stroke
				(width 0.15)
				(type solid)
			)
			(layer "F.Fab")
		)
		(fp_line
			(start -3.375 -1.601)
			(end 3.374 -1.601)
			(stroke
				(width 0.15)
				(type solid)
			)
			(layer "F.Fab")
		)
		(fp_line
			(start -2.375 -1.601)
			(end -1.875 -0.893)
			(stroke
				(width 0.15)
				(type solid)
			)
			(layer "F.Fab")
		)
		(fp_line
			(start 3.374 -1.601)
			(end 3.374 2.1)
			(stroke
				(width 0.15)
				(type solid)
			)
			(layer "F.Fab")
		)
		(fp_text user "${REFERENCE}"
			(at -5.8 5.2 -90)
			(layer "F.Fab")
			(hide yes)
			(effects
				(font
					(size 0.7 0.7)
					(thickness 0.15)
				)
				(justify left bottom)
			)
		)
		(fp_text user "Author: Antmicro"
			(at -5.8 6.6 -90)
			(layer "F.Fab")
			(hide yes)
			(effects
				(font
					(size 0.7 0.7)
					(thickness 0.15)
				)
				(justify left bottom)
			)
		)
		(fp_text user "License: Apache-2.0"
			(at -5.8 8 -90)
			(layer "F.Fab")
			(hide yes)
			(effects
				(font
					(size 0.7 0.7)
					(thickness 0.15)
				)
				(justify left bottom)
			)
		)
		(pad "1" smd roundrect
			(at -1.875 -1.75 270)
			(size 0.8 1.3)
			(layers "F.Cu" "F.Paste" "F.Mask")
			(roundrect_rratio 0.25)
			(net 1 "GND")
			(pinfunction "1")
			(pintype "passive")
		)
		(pad "2" smd roundrect
			(at -0.625 -1.75 270)
			(size 0.8 1.3)
			(layers "F.Cu" "F.Paste" "F.Mask")
			(roundrect_rratio 0.25)
			(net 99 "+5V")
			(pinfunction "2")
			(pintype "passive")
		)
		(pad "3" smd roundrect
			(at 0.623 -1.75 270)
			(size 0.8 1.3)
			(layers "F.Cu" "F.Paste" "F.Mask")
			(roundrect_rratio 0.25)
			(net 541 "/Peripherals/FAN_TACH_5V")
			(pinfunction "3")
			(pintype "passive")
		)
		(pad "4" smd roundrect
			(at 1.874 -1.75 270)
			(size 0.8 1.3)
			(layers "F.Cu" "F.Paste" "F.Mask")
			(roundrect_rratio 0.25)
			(net 540 "/Peripherals/FAN_PWM_5V")
			(pinfunction "4")
			(pintype "passive")
		)
		(pad "MP1" smd roundrect
			(at -4.425 0.998 270)
			(size 2.1 3)
			(layers "F.Cu" "F.Paste" "F.Mask")
			(roundrect_rratio 0.119048)
			(net 726 "unconnected-(J10-PadMP1)")
			(pinfunction "MP1")
			(pintype "passive+no_connect")
		)
		(pad "MP2" smd roundrect
			(at 4.424 0.998 270)
			(size 2.1 3)
			(layers "F.Cu" "F.Paste" "F.Mask")
			(roundrect_rratio 0.119048)
			(net 727 "unconnected-(J10-PadMP2)")
			(pinfunction "MP2")
			(pintype "passive+no_connect")
		)
	)
	(footprint "antmicro-footprints:R_0402_1005Metric"
		(layer "F.Cu")
		(at 57.8 107.1)
		(descr "Resistor SMD 0402")
		(tags "resistor SMD 0402")
		(property "Reference" "R254"
			(at -3.7 0.15 0)
			(layer "F.SilkS")
			(effects
				(font
					(size 0.7 0.7)
					(thickness 0.15)
				)
				(justify left bottom)
			)
		)
		(property "Value" "R_10k_0402"
			(at 0 1.4 0)
			(layer "F.Fab")
			(effects
				(font
					(size 0.7 0.7)
					(thickness 0.15)
				)
				(justify left bottom)
			)
		)
		(property "Footprint" "antmicro-footprints:R_0402_1005Metric"
			(at 0 0 0)
			(layer "F.Fab")
			(hide yes)
			(effects
				(font
					(size 1.27 1.27)
					(thickness 0.15)
				)
			)
		)
		(property "Datasheet" "https://www.bourns.com/docs/product-datasheets/cr.pdf"
			(at 0 0 0)
			(layer "F.Fab")
			(hide yes)
			(effects
				(font
					(size 1.27 1.27)
					(thickness 0.15)
				)
			)
		)
		(property "Author" "Antmicro"
			(at 0 0 0)
			(layer "F.Fab")
			(hide yes)
			(effects
				(font
					(size 1 1)
					(thickness 0.15)
				)
			)
		)
		(property "License" "Apache-2.0"
			(at 0 0 0)
			(layer "F.Fab")
			(hide yes)
			(effects
				(font
					(size 1 1)
					(thickness 0.15)
				)
			)
		)
		(property "MPN" "CR0402-FX-1002GLF"
			(at 0 0 0)
			(layer "F.Fab")
			(hide yes)
			(effects
				(font
					(size 1 1)
					(thickness 0.15)
				)
			)
		)
		(property "Manufacturer" "Bourns"
			(at 0 0 0)
			(layer "F.Fab")
			(hide yes)
			(effects
				(font
					(size 1 1)
					(thickness 0.15)
				)
			)
		)
		(property "Tolerance" "1%"
			(at 0 0 0)
			(layer "F.Fab")
			(hide yes)
			(effects
				(font
					(size 1 1)
					(thickness 0.15)
				)
			)
		)
		(property "Val" "10k"
			(at 0 0 0)
			(layer "F.Fab")
			(hide yes)
			(effects
				(font
					(size 1 1)
					(thickness 0.15)
				)
			)
		)
		(sheetname "Supply")
		(sheetfile "supply.kicad_sch")
		(attr smd)
		(fp_rect
			(start -0.925 -0.47)
			(end 0.925 0.47)
			(stroke
				(width 0.05)
				(type default)
			)
			(fill none)
			(layer "F.CrtYd")
		)
		(fp_rect
			(start -0.5 -0.25)
			(end 0.5 0.25)
			(stroke
				(width 0.15)
				(type solid)
			)
			(fill none)
			(layer "F.Fab")
		)
		(fp_text user "License: Apache-2.0"
			(at -0.95 5.169 0)
			(layer "F.Fab")
			(hide yes)
			(effects
				(font
					(size 0.7 0.7)
					(thickness 0.15)
				)
				(justify left bottom)
			)
		)
		(fp_text user "${REFERENCE}"
			(at -0.95 3.168 0)
			(layer "F.Fab")
			(hide yes)
			(effects
				(font
					(size 0.7 0.7)
					(thickness 0.15)
				)
				(justify left bottom)
			)
		)
		(fp_text user "Author: Antmicro"
			(at -0.95 4.169 0)
			(layer "F.Fab")
			(hide yes)
			(effects
				(font
					(size 0.7 0.7)
					(thickness 0.15)
				)
				(justify left bottom)
			)
		)
		(pad "1" smd roundrect
			(at -0.48 0)
			(size 0.59 0.64)
			(layers "F.Cu" "F.Paste" "F.Mask")
			(roundrect_rratio 0.25)
			(net 1 "GND")
			(pintype "passive")
		)
		(pad "2" smd roundrect
			(at 0.48 0)
			(size 0.59 0.64)
			(layers "F.Cu" "F.Paste" "F.Mask")
			(roundrect_rratio 0.25)
			(net 630 "Net-(Q15-G)")
			(pintype "passive")
		)
	)
	(footprint "antmicro-footprints:R_0402_1005Metric"
		(layer "F.Cu")
		(at 38.2 103.7 180)
		(descr "Resistor SMD 0402")
		(tags "resistor SMD 0402")
		(property "Reference" "R199"
			(at 3.65 -0.4 180)
			(layer "F.SilkS")
			(effects
				(font
					(size 0.7 0.7)
					(thickness 0.15)
				)
				(justify left bottom)
			)
		)
		(property "Value" "R_470k_0402"
			(at 0 1.4 180)
			(layer "F.Fab")
			(effects
				(font
					(size 0.7 0.7)
					(thickness 0.15)
				)
				(justify left bottom)
			)
		)
		(property "Footprint" "antmicro-footprints:R_0402_1005Metric"
			(at 0 0 180)
			(layer "F.Fab")
			(hide yes)
			(effects
				(font
					(size 1.27 1.27)
					(thickness 0.15)
				)
			)
		)
		(property "Datasheet" "https://www.bourns.com/docs/product-datasheets/cr.pdf"
			(at 0 0 180)
			(layer "F.Fab")
			(hide yes)
			(effects
				(font
					(size 1.27 1.27)
					(thickness 0.15)
				)
			)
		)
		(property "Author" "Antmicro"
			(at 76.4 207.4 0)
			(layer "F.Fab")
			(hide yes)
			(effects
				(font
					(size 1 1)
					(thickness 0.15)
				)
			)
		)
		(property "License" "Apache-2.0"
			(at 76.4 207.4 0)
			(layer "F.Fab")
			(hide yes)
			(effects
				(font
					(size 1 1)
					(thickness 0.15)
				)
			)
		)
		(property "MPN" "CR0402-FX-4703GLF"
			(at 76.4 207.4 0)
			(layer "F.Fab")
			(hide yes)
			(effects
				(font
					(size 1 1)
					(thickness 0.15)
				)
			)
		)
		(property "Manufacturer" "Bourns"
			(at 76.4 207.4 0)
			(layer "F.Fab")
			(hide yes)
			(effects
				(font
					(size 1 1)
					(thickness 0.15)
				)
			)
		)
		(property "Tolerance" "1%"
			(at 76.4 207.4 0)
			(layer "F.Fab")
			(hide yes)
			(effects
				(font
					(size 1 1)
					(thickness 0.15)
				)
			)
		)
		(property "Val" "470k"
			(at 76.4 207.4 0)
			(layer "F.Fab")
			(hide yes)
			(effects
				(font
					(size 1 1)
					(thickness 0.15)
				)
			)
		)
		(sheetname "Ethernet")
		(sheetfile "ethernet.kicad_sch")
		(attr smd exclude_from_pos_files exclude_from_bom dnp)
		(fp_rect
			(start -0.925 -0.47)
			(end 0.925 0.47)
			(stroke
				(width 0.05)
				(type default)
			)
			(fill none)
			(layer "F.CrtYd")
		)
		(fp_rect
			(start -0.5 -0.25)
			(end 0.5 0.25)
			(stroke
				(width 0.15)
				(type solid)
			)
			(fill none)
			(layer "F.Fab")
		)
		(fp_text user "${REFERENCE}"
			(at -0.95 3.168 180)
			(layer "F.Fab")
			(hide yes)
			(effects
				(font
					(size 0.7 0.7)
					(thickness 0.15)
				)
				(justify left bottom)
			)
		)
		(fp_text user "Author: Antmicro"
			(at -0.95 4.169 180)
			(layer "F.Fab")
			(hide yes)
			(effects
				(font
					(size 0.7 0.7)
					(thickness 0.15)
				)
				(justify left bottom)
			)
		)
		(fp_text user "License: Apache-2.0"
			(at -0.95 5.169 180)
			(layer "F.Fab")
			(hide yes)
			(effects
				(font
					(size 0.7 0.7)
					(thickness 0.15)
				)
				(justify left bottom)
			)
		)
		(pad "1" smd roundrect
			(at -0.48 0 180)
			(size 0.59 0.64)
			(layers "F.Cu" "F.Paste" "F.Mask")
			(roundrect_rratio 0.25)
			(net 650 "/Ethernet/ULS-12_CTRL")
			(pintype "passive")
		)
		(pad "2" smd roundrect
			(at 0.48 0 180)
			(size 0.59 0.64)
			(layers "F.Cu" "F.Paste" "F.Mask")
			(roundrect_rratio 0.25)
			(net 105 "/Ethernet/VDD")
			(pintype "passive")
		)
	)
	(footprint "antmicro-footprints:R_0402_1005Metric"
		(layer "F.Cu")
		(at 105.2 115.8 -90)
		(descr "Resistor SMD 0402")
		(tags "resistor SMD 0402")
		(property "Reference" "R184"
			(at -0.89 -0.45 -90)
			(layer "F.SilkS")
			(effects
				(font
					(size 0.7 0.7)
					(thickness 0.15)
				)
				(justify left bottom)
			)
		)
		(property "Value" "R_1k_0402"
			(at 0 1.4 -90)
			(layer "F.Fab")
			(effects
				(font
					(size 0.7 0.7)
					(thickness 0.15)
				)
				(justify left bottom)
			)
		)
		(property "Footprint" "antmicro-footprints:R_0402_1005Metric"
			(at 0 0 -90)
			(layer "F.Fab")
			(hide yes)
			(effects
				(font
					(size 1.27 1.27)
					(thickness 0.15)
				)
			)
		)
		(property "Datasheet" "https://www.bourns.com/docs/product-datasheets/cr.pdf"
			(at 0 0 -90)
			(layer "F.Fab")
			(hide yes)
			(effects
				(font
					(size 1.27 1.27)
					(thickness 0.15)
				)
			)
		)
		(property "Author" "Antmicro"
			(at -10.6 221 0)
			(layer "F.Fab")
			(hide yes)
			(effects
				(font
					(size 1 1)
					(thickness 0.15)
				)
			)
		)
		(property "License" "Apache-2.0"
			(at -10.6 221 0)
			(layer "F.Fab")
			(hide yes)
			(effects
				(font
					(size 1 1)
					(thickness 0.15)
				)
			)
		)
		(property "MPN" "CR0402-FX-1001GLF"
			(at -10.6 221 0)
			(layer "F.Fab")
			(hide yes)
			(effects
				(font
					(size 1 1)
					(thickness 0.15)
				)
			)
		)
		(property "Manufacturer" "Bourns"
			(at -10.6 221 0)
			(layer "F.Fab")
			(hide yes)
			(effects
				(font
					(size 1 1)
					(thickness 0.15)
				)
			)
		)
		(property "Tolerance" "1%"
			(at -10.6 221 0)
			(layer "F.Fab")
			(hide yes)
			(effects
				(font
					(size 1 1)
					(thickness 0.15)
				)
			)
		)
		(property "Val" "1k"
			(at -10.6 221 0)
			(layer "F.Fab")
			(hide yes)
			(effects
				(font
					(size 1 1)
					(thickness 0.15)
				)
			)
		)
		(sheetname "USB3")
		(sheetfile "usb3.kicad_sch")
		(attr smd)
		(fp_rect
			(start -0.925 -0.47)
			(end 0.925 0.47)
			(stroke
				(width 0.05)
				(type default)
			)
			(fill none)
			(layer "F.CrtYd")
		)
		(fp_rect
			(start -0.5 -0.25)
			(end 0.5 0.25)
			(stroke
				(width 0.15)
				(type solid)
			)
			(fill none)
			(layer "F.Fab")
		)
		(fp_text user "${REFERENCE}"
			(at -0.95 3.168 -90)
			(layer "F.Fab")
			(hide yes)
			(effects
				(font
					(size 0.7 0.7)
					(thickness 0.15)
				)
				(justify left bottom)
			)
		)
		(fp_text user "License: Apache-2.0"
			(at -0.95 5.169 -90)
			(layer "F.Fab")
			(hide yes)
			(effects
				(font
					(size 0.7 0.7)
					(thickness 0.15)
				)
				(justify left bottom)
			)
		)
		(fp_text user "Author: Antmicro"
			(at -0.95 4.169 -90)
			(layer "F.Fab")
			(hide yes)
			(effects
				(font
					(size 0.7 0.7)
					(thickness 0.15)
				)
				(justify left bottom)
			)
		)
		(pad "1" smd roundrect
			(at -0.48 0 270)
			(size 0.59 0.64)
			(layers "F.Cu" "F.Paste" "F.Mask")
			(roundrect_rratio 0.25)
			(net 562 "USBC1_PEN")
			(pintype "passive")
		)
		(pad "2" smd roundrect
			(at 0.48 0 270)
			(size 0.59 0.64)
			(layers "F.Cu" "F.Paste" "F.Mask")
			(roundrect_rratio 0.25)
			(net 87 "+3V3")
			(pintype "passive")
		)
	)
	(footprint "antmicro-footprints:R_0402_1005Metric"
		(layer "F.Cu")
		(at 80.23 87.22 90)
		(descr "Resistor SMD 0402")
		(tags "resistor SMD 0402")
		(property "Reference" "R238"
			(at 0.72 0.44 90)
			(layer "F.SilkS")
			(effects
				(font
					(size 0.7 0.7)
					(thickness 0.15)
				)
				(justify left bottom)
			)
		)
		(property "Value" "R_10k_0402"
			(at -1.011843 1.772047 90)
			(layer "F.Fab")
			(effects
				(font
					(size 0.7 0.7)
					(thickness 0.15)
				)
				(justify left bottom)
			)
		)
		(property "Footprint" "antmicro-footprints:R_0402_1005Metric"
			(at 0 0 90)
			(layer "F.Fab")
			(hide yes)
			(effects
				(font
					(size 1.27 1.27)
					(thickness 0.15)
				)
			)
		)
		(property "Datasheet" "https://www.bourns.com/docs/product-datasheets/cr.pdf"
			(at 0 0 90)
			(layer "F.Fab")
			(hide yes)
			(effects
				(font
					(size 1.27 1.27)
					(thickness 0.15)
				)
			)
		)
		(property "Author" "Antmicro"
			(at 167.45 6.99 0)
			(layer "F.Fab")
			(hide yes)
			(effects
				(font
					(size 1 1)
					(thickness 0.15)
				)
			)
		)
		(property "License" "Apache-2.0"
			(at 167.45 6.99 0)
			(layer "F.Fab")
			(hide yes)
			(effects
				(font
					(size 1 1)
					(thickness 0.15)
				)
			)
		)
		(property "MPN" "CR0402-FX-1002GLF"
			(at 167.45 6.99 0)
			(layer "F.Fab")
			(hide yes)
			(effects
				(font
					(size 1 1)
					(thickness 0.15)
				)
			)
		)
		(property "Manufacturer" "Bourns"
			(at 167.45 6.99 0)
			(layer "F.Fab")
			(hide yes)
			(effects
				(font
					(size 1 1)
					(thickness 0.15)
				)
			)
		)
		(property "Tolerance" "1%"
			(at 167.45 6.99 0)
			(layer "F.Fab")
			(hide yes)
			(effects
				(font
					(size 1 1)
					(thickness 0.15)
				)
			)
		)
		(property "Val" "10k"
			(at 167.45 6.99 0)
			(layer "F.Fab")
			(hide yes)
			(effects
				(font
					(size 1 1)
					(thickness 0.15)
				)
			)
		)
		(sheetname "Supply")
		(sheetfile "supply.kicad_sch")
		(attr smd)
		(fp_rect
			(start -0.925 -0.47)
			(end 0.925 0.47)
			(stroke
				(width 0.05)
				(type default)
			)
			(fill none)
			(layer "F.CrtYd")
		)
		(fp_rect
			(start -0.5 -0.25)
			(end 0.5 0.25)
			(stroke
				(width 0.15)
				(type solid)
			)
			(fill none)
			(layer "F.Fab")
		)
		(fp_text user "${REFERENCE}"
			(at -0.95 3.168 90)
			(layer "F.Fab")
			(hide yes)
			(effects
				(font
					(size 0.7 0.7)
					(thickness 0.15)
				)
				(justify left bottom)
			)
		)
		(fp_text user "Author: Antmicro"
			(at -0.95 4.169 90)
			(layer "F.Fab")
			(hide yes)
			(effects
				(font
					(size 0.7 0.7)
					(thickness 0.15)
				)
				(justify left bottom)
			)
		)
		(fp_text user "License: Apache-2.0"
			(at -0.95 5.169 90)
			(layer "F.Fab")
			(hide yes)
			(effects
				(font
					(size 0.7 0.7)
					(thickness 0.15)
				)
				(justify left bottom)
			)
		)
		(pad "1" smd roundrect
			(at -0.48 0 90)
			(size 0.59 0.64)
			(layers "F.Cu" "F.Paste" "F.Mask")
			(roundrect_rratio 0.25)
			(net 1 "GND")
			(pintype "passive")
		)
		(pad "2" smd roundrect
			(at 0.48 0 90)
			(size 0.59 0.64)
			(layers "F.Cu" "F.Paste" "F.Mask")
			(roundrect_rratio 0.25)
			(net 711 "/Supply/3V3_FB")
			(pintype "passive")
		)
	)
	(footprint "antmicro-footprints:C_0603_1608Metric"
		(layer "F.Cu")
		(at 114.7 102.85 90)
		(descr "Capacitor SMD 0603")
		(tags "capacitor 0603")
		(property "Reference" "C12"
			(at -1.55 -0.6 90)
			(layer "F.SilkS")
			(effects
				(font
					(size 0.7 0.7)
					(thickness 0.15)
				)
				(justify left bottom)
			)
		)
		(property "Value" "C_10u_0603"
			(at 0 1.6 90)
			(layer "F.Fab")
			(effects
				(font
					(size 0.7 0.7)
					(thickness 0.15)
				)
				(justify left bottom)
			)
		)
		(property "Footprint" "antmicro-footprints:C_0603_1608Metric"
			(at 0 0 90)
			(layer "F.Fab")
			(hide yes)
			(effects
				(font
					(size 1.27 1.27)
					(thickness 0.15)
				)
			)
		)
		(property "Datasheet" "https://www.murata.com/products/productdetail?partno=GRM188R61A106KE69%23"
			(at 0 0 90)
			(layer "F.Fab")
			(hide yes)
			(effects
				(font
					(size 1.27 1.27)
					(thickness 0.15)
				)
			)
		)
		(property "Author" "Antmicro"
			(at 217.55 -11.85 0)
			(layer "F.Fab")
			(hide yes)
			(effects
				(font
					(size 1 1)
					(thickness 0.15)
				)
			)
		)
		(property "Dielectric" "template_dielectric"
			(at 217.55 -11.85 0)
			(layer "F.Fab")
			(hide yes)
			(effects
				(font
					(size 1 1)
					(thickness 0.15)
				)
			)
		)
		(property "License" "Apache-2.0"
			(at 217.55 -11.85 0)
			(layer "F.Fab")
			(hide yes)
			(effects
				(font
					(size 1 1)
					(thickness 0.15)
				)
			)
		)
		(property "MPN" "GRM188R61A106KE69D"
			(at 217.55 -11.85 0)
			(layer "F.Fab")
			(hide yes)
			(effects
				(font
					(size 1 1)
					(thickness 0.15)
				)
			)
		)
		(property "Manufacturer" "Murata"
			(at 217.55 -11.85 0)
			(layer "F.Fab")
			(hide yes)
			(effects
				(font
					(size 1 1)
					(thickness 0.15)
				)
			)
		)
		(property "Val" "10u"
			(at 217.55 -11.85 0)
			(layer "F.Fab")
			(hide yes)
			(effects
				(font
					(size 1 1)
					(thickness 0.15)
				)
			)
		)
		(property "Voltage" ""
			(at 217.55 -11.85 0)
			(layer "F.Fab")
			(hide yes)
			(effects
				(font
					(size 1 1)
					(thickness 0.15)
				)
			)
		)
		(sheetname "M.2")
		(sheetfile "m-2.kicad_sch")
		(attr smd)
		(fp_line
			(start -0.15 -0.4)
			(end 0.15 -0.4)
			(stroke
				(width 0.15)
				(type solid)
			)
			(layer "F.SilkS")
		)
		(fp_line
			(start -0.15 0.4)
			(end 0.15 0.4)
			(stroke
				(width 0.15)
				(type solid)
			)
			(layer "F.SilkS")
		)
		(fp_rect
			(start -1.25 -0.65)
			(end 1.25 0.65)
			(stroke
				(width 0.05)
				(type solid)
			)
			(fill none)
			(layer "F.CrtYd")
		)
		(fp_rect
			(start -0.8 -0.4)
			(end 0.8 0.4)
			(stroke
				(width 0.15)
				(type solid)
			)
			(fill none)
			(layer "F.Fab")
		)
		(fp_text user "License: Apache-2.0"
			(at -1.682 5.895 90)
			(layer "F.Fab")
			(hide yes)
			(effects
				(font
					(size 0.7 0.7)
					(thickness 0.15)
				)
				(justify left bottom)
			)
		)
		(fp_text user "${REFERENCE}"
			(at -1.682 3.895 90)
			(layer "F.Fab")
			(hide yes)
			(effects
				(font
					(size 0.7 0.7)
					(thickness 0.15)
				)
				(justify left bottom)
			)
		)
		(fp_text user "Author: Antmicro"
			(at -1.682 4.894 90)
			(layer "F.Fab")
			(hide yes)
			(effects
				(font
					(size 0.7 0.7)
					(thickness 0.15)
				)
				(justify left bottom)
			)
		)
		(pad "1" smd roundrect
			(at -0.7 0 90)
			(size 0.8 1)
			(layers "F.Cu" "F.Paste" "F.Mask")
			(roundrect_rratio 0.2)
			(net 87 "+3V3")
			(pintype "passive")
		)
		(pad "2" smd roundrect
			(at 0.7 0 90)
			(size 0.8 1)
			(layers "F.Cu" "F.Paste" "F.Mask")
			(roundrect_rratio 0.2)
			(net 1 "GND")
			(pintype "passive")
		)
	)
	(footprint "antmicro-footprints:R_0402_1005Metric"
		(layer "F.Cu")
		(at 85.4 114.8)
		(descr "Resistor SMD 0402")
		(tags "resistor SMD 0402")
		(property "Reference" "R226"
			(at -3.98 3.72 0)
			(layer "F.SilkS")
			(effects
				(font
					(size 0.7 0.7)
					(thickness 0.15)
				)
				(justify left bottom)
			)
		)
		(property "Value" "R_0R_0402"
			(at 0 1.4 0)
			(layer "F.Fab")
			(effects
				(font
					(size 0.7 0.7)
					(thickness 0.15)
				)
				(justify left bottom)
			)
		)
		(property "Footprint" "antmicro-footprints:R_0402_1005Metric"
			(at 0 0 0)
			(layer "F.Fab")
			(hide yes)
			(effects
				(font
					(size 1.27 1.27)
					(thickness 0.15)
				)
			)
		)
		(property "Datasheet" "https://industrial.panasonic.com/cdbs/www-data/pdf/RDA0000/AOA0000C301.pdf"
			(at 0 0 0)
			(layer "F.Fab")
			(hide yes)
			(effects
				(font
					(size 1.27 1.27)
					(thickness 0.15)
				)
			)
		)
		(property "Author" "Antmicro"
			(at 0 0 0)
			(layer "F.Fab")
			(hide yes)
			(effects
				(font
					(size 1 1)
					(thickness 0.15)
				)
			)
		)
		(property "Current" "1A"
			(at 0 0 0)
			(layer "F.Fab")
			(hide yes)
			(effects
				(font
					(size 1 1)
					(thickness 0.15)
				)
			)
		)
		(property "License" "Apache-2.0"
			(at 0 0 0)
			(layer "F.Fab")
			(hide yes)
			(effects
				(font
					(size 1 1)
					(thickness 0.15)
				)
			)
		)
		(property "MPN" "ERJ2GE0R00X"
			(at 0 0 0)
			(layer "F.Fab")
			(hide yes)
			(effects
				(font
					(size 1 1)
					(thickness 0.15)
				)
			)
		)
		(property "Manufacturer" "Panasonic"
			(at 0 0 0)
			(layer "F.Fab")
			(hide yes)
			(effects
				(font
					(size 1 1)
					(thickness 0.15)
				)
			)
		)
		(property "Tolerance" ""
			(at 0 0 0)
			(layer "F.Fab")
			(hide yes)
			(effects
				(font
					(size 1 1)
					(thickness 0.15)
				)
			)
		)
		(property "Val" "0R"
			(at 0 0 0)
			(layer "F.Fab")
			(hide yes)
			(effects
				(font
					(size 1 1)
					(thickness 0.15)
				)
			)
		)
		(sheetname "HDMI")
		(sheetfile "hdmi.kicad_sch")
		(attr smd)
		(fp_rect
			(start -0.925 -0.47)
			(end 0.925 0.47)
			(stroke
				(width 0.05)
				(type default)
			)
			(fill none)
			(layer "F.CrtYd")
		)
		(fp_rect
			(start -0.5 -0.25)
			(end 0.5 0.25)
			(stroke
				(width 0.15)
				(type solid)
			)
			(fill none)
			(layer "F.Fab")
		)
		(fp_text user "Author: Antmicro"
			(at -0.95 4.169 0)
			(layer "F.Fab")
			(hide yes)
			(effects
				(font
					(size 0.7 0.7)
					(thickness 0.15)
				)
				(justify left bottom)
			)
		)
		(fp_text user "License: Apache-2.0"
			(at -0.95 5.169 0)
			(layer "F.Fab")
			(hide yes)
			(effects
				(font
					(size 0.7 0.7)
					(thickness 0.15)
				)
				(justify left bottom)
			)
		)
		(fp_text user "${REFERENCE}"
			(at -0.95 3.168 0)
			(layer "F.Fab")
			(hide yes)
			(effects
				(font
					(size 0.7 0.7)
					(thickness 0.15)
				)
				(justify left bottom)
			)
		)
		(pad "1" smd roundrect
			(at -0.48 0)
			(size 0.59 0.64)
			(layers "F.Cu" "F.Paste" "F.Mask")
			(roundrect_rratio 0.25)
			(net 703 "/HDMI/HDMI_HPD")
			(pintype "passive")
		)
		(pad "2" smd roundrect
			(at 0.48 0)
			(size 0.59 0.64)
			(layers "F.Cu" "F.Paste" "F.Mask")
			(roundrect_rratio 0.25)
			(net 529 "/HDMI/HDMI_HPD_5V")
			(pintype "passive")
		)
	)
	(footprint "antmicro-footprints:SOD-923"
		(layer "F.Cu")
		(at 60.925 91.4)
		(property "Reference" "D32"
			(at 0.605 0.46 0)
			(unlocked yes)
			(layer "F.SilkS")
			(effects
				(font
					(size 0.7 0.7)
					(thickness 0.15)
				)
				(justify left bottom)
			)
		)
		(property "Value" "ESD9X5.0ST5G"
			(at 0 1.3 0)
			(unlocked yes)
			(layer "F.Fab")
			(effects
				(font
					(size 0.7 0.7)
					(thickness 0.15)
				)
				(justify left bottom)
			)
		)
		(property "Footprint" "antmicro-footprints:SOD-923"
			(at 0 0 0)
			(layer "B.Fab")
			(hide yes)
			(effects
				(font
					(size 1.27 1.27)
					(thickness 0.15)
				)
				(justify mirror)
			)
		)
		(property "Datasheet" "https://www.onsemi.com/pdf/datasheet/esd9x3.3st5g-d.pdf"
			(at 0 0 0)
			(layer "B.Fab")
			(hide yes)
			(effects
				(font
					(size 1.27 1.27)
					(thickness 0.15)
				)
				(justify mirror)
			)
		)
		(property "Author" "Antmicro"
			(at 143.39 -28.57 90)
			(layer "F.Fab")
			(hide yes)
			(effects
				(font
					(size 1 1)
					(thickness 0.15)
				)
			)
		)
		(property "License" "Apache-2.0"
			(at 143.39 -28.57 90)
			(layer "F.Fab")
			(hide yes)
			(effects
				(font
					(size 1 1)
					(thickness 0.15)
				)
			)
		)
		(property "MPN" "ESD9X5.0ST5G"
			(at 143.39 -28.57 90)
			(layer "F.Fab")
			(hide yes)
			(effects
				(font
					(size 1 1)
					(thickness 0.15)
				)
			)
		)
		(property "Manufacturer" "ON Semiconductor"
			(at 143.39 -28.57 90)
			(layer "F.Fab")
			(hide yes)
			(effects
				(font
					(size 1 1)
					(thickness 0.15)
				)
			)
		)
		(sheetname "Supply")
		(sheetfile "supply.kicad_sch")
		(attr smd)
		(fp_line
			(start -0.5 -0.4)
			(end 0.5 -0.4)
			(stroke
				(width 0.15)
				(type solid)
			)
			(layer "F.SilkS")
		)
		(fp_line
			(start -0.5 -0.3)
			(end -0.5 -0.4)
			(stroke
				(width 0.15)
				(type solid)
			)
			(layer "F.SilkS")
		)
		(fp_line
			(start -0.5 0.4)
			(end -0.5 0.3)
			(stroke
				(width 0.15)
				(type solid)
			)
			(layer "F.SilkS")
		)
		(fp_line
			(start -0.5 0.4)
			(end 0.5 0.4)
			(stroke
				(width 0.15)
				(type solid)
			)
			(layer "F.SilkS")
		)
		(fp_line
			(start -0.16 -0.4)
			(end -0.16 0.4)
			(stroke
				(width 0.15)
				(type solid)
			)
			(layer "F.SilkS")
		)
		(fp_line
			(start 0.5 -0.4)
			(end 0.5 -0.3)
			(stroke
				(width 0.15)
				(type solid)
			)
			(layer "F.SilkS")
		)
		(fp_line
			(start 0.5 0.4)
			(end 0.5 0.3)
			(stroke
				(width 0.15)
				(type solid)
			)
			(layer "F.SilkS")
		)
		(fp_rect
			(start -0.68 -0.41)
			(end 0.68 0.41)
			(stroke
				(width 0.05)
				(type solid)
			)
			(fill none)
			(layer "F.CrtYd")
		)
		(fp_line
			(start -0.202 -0.3)
			(end -0.202 0.298)
			(stroke
				(width 0.15)
				(type solid)
			)
			(layer "F.Fab")
		)
		(fp_rect
			(start -0.402 -0.3)
			(end 0.4 0.298)
			(stroke
				(width 0.15)
				(type solid)
			)
			(fill none)
			(layer "F.Fab")
		)
		(fp_text user "${REFERENCE}"
			(at -0.68 3.3 0)
			(unlocked yes)
			(layer "F.Fab")
			(hide yes)
			(effects
				(font
					(size 0.7 0.7)
					(thickness 0.15)
				)
				(justify left bottom)
			)
		)
		(fp_text user "License: Apache-2.0"
			(at -0.68 4.5 0)
			(layer "F.Fab")
			(hide yes)
			(effects
				(font
					(size 0.7 0.7)
					(thickness 0.15)
				)
				(justify left top)
			)
		)
		(fp_text user "Author: Antmicro"
			(at -0.68 5.7 0)
			(layer "F.Fab")
			(hide yes)
			(effects
				(font
					(size 0.7 0.7)
					(thickness 0.15)
				)
				(justify left top)
			)
		)
		(pad "1" smd roundrect
			(at -0.438 0)
			(size 0.4 0.325)
			(layers "F.Cu" "F.Paste" "F.Mask")
			(roundrect_rratio 0.25)
			(net 787 "+5V_SoM")
			(pinfunction "C")
			(pintype "passive")
		)
		(pad "2" smd roundrect
			(at 0.436 0)
			(size 0.4 0.325)
			(layers "F.Cu" "F.Paste" "F.Mask")
			(roundrect_rratio 0.25)
			(net 1 "GND")
			(pinfunction "A")
			(pintype "passive")
		)
	)
	(footprint "antmicro-footprints:C_0402_1005Metric"
		(layer "F.Cu")
		(at 61.39 100.52 180)
		(descr "Capacitor SMD 0402")
		(tags "capacitor SMD 0402")
		(property "Reference" "C156"
			(at -5.535 -3.555 0)
			(layer "F.SilkS")
			(effects
				(font
					(size 0.7 0.7)
					(thickness 0.15)
				)
				(justify right bottom)
			)
		)
		(property "Value" "C_4u7_25V_0402"
			(at -1.022927 2.155213 0)
			(layer "F.Fab")
			(effects
				(font
					(size 0.7 0.7)
					(thickness 0.15)
				)
				(justify right bottom)
			)
		)
		(property "Footprint" "antmicro-footprints:C_0402_1005Metric"
			(at 0 0 180)
			(layer "F.Fab")
			(hide yes)
			(effects
				(font
					(size 1.27 1.27)
					(thickness 0.15)
				)
			)
		)
		(property "Datasheet" "https://www.murata.com/products/productdetail?partno=GRM155C61E475ME15%23"
			(at 0 0 180)
			(layer "F.Fab")
			(hide yes)
			(effects
				(font
					(size 1.27 1.27)
					(thickness 0.15)
				)
			)
		)
		(property "Author" "Antmicro"
			(at 122.78 201.04 0)
			(layer "F.Fab")
			(hide yes)
			(effects
				(font
					(size 1 1)
					(thickness 0.15)
				)
			)
		)
		(property "Dielectric" "X5S"
			(at 122.78 201.04 0)
			(layer "F.Fab")
			(hide yes)
			(effects
				(font
					(size 1 1)
					(thickness 0.15)
				)
			)
		)
		(property "License" "Apache-2.0"
			(at 122.78 201.04 0)
			(layer "F.Fab")
			(hide yes)
			(effects
				(font
					(size 1 1)
					(thickness 0.15)
				)
			)
		)
		(property "MPN" "GRM155C61E475ME15J"
			(at 122.78 201.04 0)
			(layer "F.Fab")
			(hide yes)
			(effects
				(font
					(size 1 1)
					(thickness 0.15)
				)
			)
		)
		(property "Manufacturer" "Murata"
			(at 122.78 201.04 0)
			(layer "F.Fab")
			(hide yes)
			(effects
				(font
					(size 1 1)
					(thickness 0.15)
				)
			)
		)
		(property "Val" "4u7"
			(at 122.78 201.04 0)
			(layer "F.Fab")
			(hide yes)
			(effects
				(font
					(size 1 1)
					(thickness 0.15)
				)
			)
		)
		(property "Voltage" "25V"
			(at 122.78 201.04 0)
			(layer "F.Fab")
			(hide yes)
			(effects
				(font
					(size 1 1)
					(thickness 0.15)
				)
			)
		)
		(sheetname "Supply")
		(sheetfile "supply.kicad_sch")
		(attr smd)
		(fp_rect
			(start -0.925 -0.47)
			(end 0.925 0.47)
			(stroke
				(width 0.05)
				(type default)
			)
			(fill none)
			(layer "F.CrtYd")
		)
		(fp_line
			(start 0.504 0.248)
			(end -0.494 0.248)
			(stroke
				(width 0.15)
				(type solid)
			)
			(layer "F.Fab")
		)
		(fp_line
			(start 0.504 -0.25)
			(end 0.504 0.248)
			(stroke
				(width 0.15)
				(type solid)
			)
			(layer "F.Fab")
		)
		(fp_line
			(start -0.494 0.248)
			(end -0.494 -0.25)
			(stroke
				(width 0.15)
				(type solid)
			)
			(layer "F.Fab")
		)
		(fp_line
			(start -0.494 -0.25)
			(end 0.504 -0.25)
			(stroke
				(width 0.15)
				(type solid)
			)
			(layer "F.Fab")
		)
		(fp_text user "Author: Antmicro"
			(at -0.939 3.399 0)
			(layer "F.Fab")
			(hide yes)
			(effects
				(font
					(size 0.7 0.7)
					(thickness 0.15)
				)
				(justify right bottom)
			)
		)
		(fp_text user "License: Apache-2.0"
			(at -0.939 5.799 0)
			(layer "F.Fab")
			(hide yes)
			(effects
				(font
					(size 0.7 0.7)
					(thickness 0.15)
				)
				(justify right bottom)
			)
		)
		(fp_text user "${REFERENCE}"
			(at -0.939 4.599 0)
			(layer "F.Fab")
			(hide yes)
			(effects
				(font
					(size 0.7 0.7)
					(thickness 0.15)
				)
				(justify right bottom)
			)
		)
		(pad "1" smd roundrect
			(at -0.48 0 180)
			(size 0.59 0.64)
			(layers "F.Cu" "F.Paste" "F.Mask")
			(roundrect_rratio 0.25)
			(net 1 "GND")
			(pintype "passive")
		)
		(pad "2" smd roundrect
			(at 0.48 0 180)
			(size 0.59 0.64)
			(layers "F.Cu" "F.Paste" "F.Mask")
			(roundrect_rratio 0.25)
			(net 762 "/Supply/5V_VDRV")
			(pintype "passive")
		)
	)
	(footprint "antmicro-footprints:R_0402_1005Metric"
		(layer "F.Cu")
		(at 88.95 88.7 -90)
		(descr "Resistor SMD 0402")
		(tags "resistor SMD 0402")
		(property "Reference" "R278"
			(at -0.92 -0.3 -90)
			(layer "F.SilkS")
			(effects
				(font
					(size 0.7 0.7)
					(thickness 0.15)
				)
				(justify left bottom)
			)
		)
		(property "Value" "R_0R_0402"
			(at 0 1.4 -90)
			(layer "F.Fab")
			(effects
				(font
					(size 0.7 0.7)
					(thickness 0.15)
				)
				(justify left bottom)
			)
		)
		(property "Footprint" "antmicro-footprints:R_0402_1005Metric"
			(at 0 0 -90)
			(layer "F.Fab")
			(hide yes)
			(effects
				(font
					(size 1.27 1.27)
					(thickness 0.15)
				)
			)
		)
		(property "Datasheet" "https://industrial.panasonic.com/cdbs/www-data/pdf/RDA0000/AOA0000C301.pdf"
			(at 0 0 -90)
			(layer "F.Fab")
			(hide yes)
			(effects
				(font
					(size 1.27 1.27)
					(thickness 0.15)
				)
			)
		)
		(property "Author" "Antmicro"
			(at 0.25 177.65 0)
			(layer "F.Fab")
			(hide yes)
			(effects
				(font
					(size 1 1)
					(thickness 0.15)
				)
			)
		)
		(property "Current" "1A"
			(at 0.25 177.65 0)
			(layer "F.Fab")
			(hide yes)
			(effects
				(font
					(size 1 1)
					(thickness 0.15)
				)
			)
		)
		(property "License" "Apache-2.0"
			(at 0.25 177.65 0)
			(layer "F.Fab")
			(hide yes)
			(effects
				(font
					(size 1 1)
					(thickness 0.15)
				)
			)
		)
		(property "MPN" "ERJ2GE0R00X"
			(at 0.25 177.65 0)
			(layer "F.Fab")
			(hide yes)
			(effects
				(font
					(size 1 1)
					(thickness 0.15)
				)
			)
		)
		(property "Manufacturer" "Panasonic"
			(at 0.25 177.65 0)
			(layer "F.Fab")
			(hide yes)
			(effects
				(font
					(size 1 1)
					(thickness 0.15)
				)
			)
		)
		(property "Tolerance" ""
			(at 0.25 177.65 0)
			(layer "F.Fab")
			(hide yes)
			(effects
				(font
					(size 1 1)
					(thickness 0.15)
				)
			)
		)
		(property "Val" "0R"
			(at 0.25 177.65 0)
			(layer "F.Fab")
			(hide yes)
			(effects
				(font
					(size 1 1)
					(thickness 0.15)
				)
			)
		)
		(sheetname "HDMI")
		(sheetfile "hdmi.kicad_sch")
		(attr smd)
		(fp_rect
			(start -0.925 -0.47)
			(end 0.925 0.47)
			(stroke
				(width 0.05)
				(type default)
			)
			(fill none)
			(layer "F.CrtYd")
		)
		(fp_rect
			(start -0.5 -0.25)
			(end 0.5 0.25)
			(stroke
				(width 0.15)
				(type solid)
			)
			(fill none)
			(layer "F.Fab")
		)
		(fp_text user "${REFERENCE}"
			(at -0.95 3.168 -90)
			(layer "F.Fab")
			(hide yes)
			(effects
				(font
					(size 0.7 0.7)
					(thickness 0.15)
				)
				(justify left bottom)
			)
		)
		(fp_text user "Author: Antmicro"
			(at -0.95 4.169 -90)
			(layer "F.Fab")
			(hide yes)
			(effects
				(font
					(size 0.7 0.7)
					(thickness 0.15)
				)
				(justify left bottom)
			)
		)
		(fp_text user "License: Apache-2.0"
			(at -0.95 5.169 -90)
			(layer "F.Fab")
			(hide yes)
			(effects
				(font
					(size 0.7 0.7)
					(thickness 0.15)
				)
				(justify left bottom)
			)
		)
		(pad "1" smd roundrect
			(at -0.48 0 270)
			(size 0.59 0.64)
			(layers "F.Cu" "F.Paste" "F.Mask")
			(roundrect_rratio 0.25)
			(net 680 "/HDMI/DP_MUX_AUX_A-")
			(pintype "passive")
		)
		(pad "2" smd roundrect
			(at 0.48 0 270)
			(size 0.59 0.64)
			(layers "F.Cu" "F.Paste" "F.Mask")
			(roundrect_rratio 0.25)
			(net 701 "/HDMI/HDMI_SDA_3V3")
			(pintype "passive")
		)
	)
	(footprint "antmicro-footprints:XDFN-2_1x0.60mm"
		(layer "F.Cu")
		(at 135.1 89.841 -90)
		(property "Reference" "D44"
			(at 0.298 -0.402 180)
			(layer "F.SilkS")
			(effects
				(font
					(size 0.7 0.7)
					(thickness 0.15)
				)
				(justify left bottom)
			)
		)
		(property "Value" "TPD1E0B04_XDFN-2"
			(at 0 1.5 -90)
			(layer "F.Fab")
			(effects
				(font
					(size 0.7 0.7)
					(thickness 0.15)
				)
				(justify left bottom)
			)
		)
		(property "Footprint" "antmicro-footprints:XDFN-2_1x0.60mm"
			(at 0 0 -90)
			(layer "F.Fab")
			(hide yes)
			(effects
				(font
					(size 1.27 1.27)
					(thickness 0.15)
				)
			)
		)
		(property "Datasheet" "https://www.ti.com/general/docs/suppproductinfo.tsp?distId=26&gotoUrl=https://www.ti.com/lit/gpn/tpd1e0b04"
			(at 0 0 -90)
			(layer "F.Fab")
			(hide yes)
			(effects
				(font
					(size 1.27 1.27)
					(thickness 0.15)
				)
			)
		)
		(property "MPN" "TPD1E0B04DPYR"
			(at 45.259 224.941 0)
			(layer "F.Fab")
			(hide yes)
			(effects
				(font
					(size 1 1)
					(thickness 0.15)
				)
			)
		)
		(property "Manufacturer" "Texas Instruments"
			(at 45.259 224.941 0)
			(layer "F.Fab")
			(hide yes)
			(effects
				(font
					(size 1 1)
					(thickness 0.15)
				)
			)
		)
		(property "Author" "Antmicro"
			(at 45.259 224.941 0)
			(layer "F.Fab")
			(hide yes)
			(effects
				(font
					(size 1 1)
					(thickness 0.15)
				)
			)
		)
		(property "License" "Apache-2.0"
			(at 45.259 224.941 0)
			(layer "F.Fab")
			(hide yes)
			(effects
				(font
					(size 1 1)
					(thickness 0.15)
				)
			)
		)
		(sheetname "Peripherals")
		(sheetfile "peripherals.kicad_sch")
		(attr smd)
		(fp_rect
			(start -0.725 -0.475)
			(end 0.725 0.475)
			(stroke
				(width 0.05)
				(type solid)
			)
			(fill none)
			(layer "F.CrtYd")
		)
		(fp_rect
			(start -0.55 -0.35)
			(end 0.55 0.35)
			(stroke
				(width 0.15)
				(type solid)
			)
			(fill none)
			(layer "F.Fab")
		)
		(fp_text user "Author: Antmicro"
			(at -0.8 4.4 -90)
			(layer "F.Fab")
			(hide yes)
			(effects
				(font
					(size 0.7 0.7)
					(thickness 0.15)
				)
				(justify left bottom)
			)
		)
		(fp_text user "${REFERENCE}"
			(at -0.8 3.2 -90)
			(layer "F.Fab")
			(hide yes)
			(effects
				(font
					(size 0.7 0.7)
					(thickness 0.15)
				)
				(justify left bottom)
			)
		)
		(fp_text user "License: Apache-2.0"
			(at -0.8 5.6 -90)
			(layer "F.Fab")
			(hide yes)
			(effects
				(font
					(size 0.7 0.7)
					(thickness 0.15)
				)
				(justify left bottom)
			)
		)
		(pad "1" smd roundrect
			(at -0.351 0 270)
			(size 0.3 0.5)
			(layers "F.Cu" "F.Paste" "F.Mask")
			(roundrect_rratio 0.25)
			(net 166 "PCIE2_CLK_P")
			(pinfunction "C")
			(pintype "passive")
		)
		(pad "2" smd roundrect
			(at 0.349 0 270)
			(size 0.3 0.5)
			(layers "F.Cu" "F.Paste" "F.Mask")
			(roundrect_rratio 0.25)
			(net 1 "GND")
			(pinfunction "A")
			(pintype "passive")
		)
	)
	(footprint "antmicro-footprints:R_0402_1005Metric"
		(layer "F.Cu")
		(at 61.6 106)
		(descr "Resistor SMD 0402")
		(tags "resistor SMD 0402")
		(property "Reference" "R77"
			(at 0.75 0.45 0)
			(layer "F.SilkS")
			(effects
				(font
					(size 0.7 0.7)
					(thickness 0.15)
				)
				(justify left bottom)
			)
		)
		(property "Value" "R_10k_0402"
			(at 0 1.4 0)
			(layer "F.Fab")
			(effects
				(font
					(size 0.7 0.7)
					(thickness 0.15)
				)
				(justify left bottom)
			)
		)
		(property "Footprint" "antmicro-footprints:R_0402_1005Metric"
			(at 0 0 0)
			(layer "F.Fab")
			(hide yes)
			(effects
				(font
					(size 1.27 1.27)
					(thickness 0.15)
				)
			)
		)
		(property "Datasheet" "https://www.bourns.com/docs/product-datasheets/cr.pdf"
			(at 0 0 0)
			(layer "F.Fab")
			(hide yes)
			(effects
				(font
					(size 1.27 1.27)
					(thickness 0.15)
				)
			)
		)
		(property "Author" "Antmicro"
			(at 0 0 0)
			(layer "F.Fab")
			(hide yes)
			(effects
				(font
					(size 1 1)
					(thickness 0.15)
				)
			)
		)
		(property "License" "Apache-2.0"
			(at 0 0 0)
			(layer "F.Fab")
			(hide yes)
			(effects
				(font
					(size 1 1)
					(thickness 0.15)
				)
			)
		)
		(property "MPN" "CR0402-FX-1002GLF"
			(at 0 0 0)
			(layer "F.Fab")
			(hide yes)
			(effects
				(font
					(size 1 1)
					(thickness 0.15)
				)
			)
		)
		(property "Manufacturer" "Bourns"
			(at 0 0 0)
			(layer "F.Fab")
			(hide yes)
			(effects
				(font
					(size 1 1)
					(thickness 0.15)
				)
			)
		)
		(property "Tolerance" "1%"
			(at 0 0 0)
			(layer "F.Fab")
			(hide yes)
			(effects
				(font
					(size 1 1)
					(thickness 0.15)
				)
			)
		)
		(property "Val" "10k"
			(at 0 0 0)
			(layer "F.Fab")
			(hide yes)
			(effects
				(font
					(size 1 1)
					(thickness 0.15)
				)
			)
		)
		(sheetname "USB Debug, DP")
		(sheetfile "usb.kicad_sch")
		(attr smd)
		(fp_rect
			(start -0.925 -0.47)
			(end 0.925 0.47)
			(stroke
				(width 0.05)
				(type default)
			)
			(fill none)
			(layer "F.CrtYd")
		)
		(fp_rect
			(start -0.5 -0.25)
			(end 0.5 0.25)
			(stroke
				(width 0.15)
				(type solid)
			)
			(fill none)
			(layer "F.Fab")
		)
		(fp_text user "${REFERENCE}"
			(at -0.95 3.168 0)
			(layer "F.Fab")
			(hide yes)
			(effects
				(font
					(size 0.7 0.7)
					(thickness 0.15)
				)
				(justify left bottom)
			)
		)
		(fp_text user "Author: Antmicro"
			(at -0.95 4.169 0)
			(layer "F.Fab")
			(hide yes)
			(effects
				(font
					(size 0.7 0.7)
					(thickness 0.15)
				)
				(justify left bottom)
			)
		)
		(fp_text user "License: Apache-2.0"
			(at -0.95 5.169 0)
			(layer "F.Fab")
			(hide yes)
			(effects
				(font
					(size 0.7 0.7)
					(thickness 0.15)
				)
				(justify left bottom)
			)
		)
		(pad "1" smd roundrect
			(at -0.48 0)
			(size 0.59 0.64)
			(layers "F.Cu" "F.Paste" "F.Mask")
			(roundrect_rratio 0.25)
			(net 1 "GND")
			(pintype "passive")
		)
		(pad "2" smd roundrect
			(at 0.48 0)
			(size 0.59 0.64)
			(layers "F.Cu" "F.Paste" "F.Mask")
			(roundrect_rratio 0.25)
			(net 657 "Net-(U9-EN)")
			(pintype "passive")
		)
	)
	(footprint "antmicro-footprints:XDFN-2_1x0.60mm"
		(layer "F.Cu")
		(at 137.8 82.8 90)
		(property "Reference" "D47"
			(at -0.3 0.4 0)
			(layer "F.SilkS")
			(effects
				(font
					(size 0.7 0.7)
					(thickness 0.15)
				)
				(justify left bottom)
			)
		)
		(property "Value" "TPD1E0B04_XDFN-2"
			(at 0 1.5 90)
			(layer "F.Fab")
			(effects
				(font
					(size 0.7 0.7)
					(thickness 0.15)
				)
				(justify left bottom)
			)
		)
		(property "Footprint" "antmicro-footprints:XDFN-2_1x0.60mm"
			(at 0 0 90)
			(layer "F.Fab")
			(hide yes)
			(effects
				(font
					(size 1.27 1.27)
					(thickness 0.15)
				)
			)
		)
		(property "Datasheet" "https://www.ti.com/general/docs/suppproductinfo.tsp?distId=26&gotoUrl=https://www.ti.com/lit/gpn/tpd1e0b04"
			(at 0 0 90)
			(layer "F.Fab")
			(hide yes)
			(effects
				(font
					(size 1.27 1.27)
					(thickness 0.15)
				)
			)
		)
		(property "MPN" "TPD1E0B04DPYR"
			(at 220.6 -55 0)
			(layer "F.Fab")
			(hide yes)
			(effects
				(font
					(size 1 1)
					(thickness 0.15)
				)
			)
		)
		(property "Manufacturer" "Texas Instruments"
			(at 220.6 -55 0)
			(layer "F.Fab")
			(hide yes)
			(effects
				(font
					(size 1 1)
					(thickness 0.15)
				)
			)
		)
		(property "Author" "Antmicro"
			(at 220.6 -55 0)
			(layer "F.Fab")
			(hide yes)
			(effects
				(font
					(size 1 1)
					(thickness 0.15)
				)
			)
		)
		(property "License" "Apache-2.0"
			(at 220.6 -55 0)
			(layer "F.Fab")
			(hide yes)
			(effects
				(font
					(size 1 1)
					(thickness 0.15)
				)
			)
		)
		(sheetname "Peripherals")
		(sheetfile "peripherals.kicad_sch")
		(attr smd)
		(fp_rect
			(start -0.725 -0.475)
			(end 0.725 0.475)
			(stroke
				(width 0.05)
				(type solid)
			)
			(fill none)
			(layer "F.CrtYd")
		)
		(fp_rect
			(start -0.55 -0.35)
			(end 0.55 0.35)
			(stroke
				(width 0.15)
				(type solid)
			)
			(fill none)
			(layer "F.Fab")
		)
		(fp_text user "Author: Antmicro"
			(at -0.8 4.4 90)
			(layer "F.Fab")
			(hide yes)
			(effects
				(font
					(size 0.7 0.7)
					(thickness 0.15)
				)
				(justify left bottom)
			)
		)
		(fp_text user "${REFERENCE}"
			(at -0.8 3.2 90)
			(layer "F.Fab")
			(hide yes)
			(effects
				(font
					(size 0.7 0.7)
					(thickness 0.15)
				)
				(justify left bottom)
			)
		)
		(fp_text user "License: Apache-2.0"
			(at -0.8 5.6 90)
			(layer "F.Fab")
			(hide yes)
			(effects
				(font
					(size 0.7 0.7)
					(thickness 0.15)
				)
				(justify left bottom)
			)
		)
		(pad "1" smd roundrect
			(at -0.351 0 90)
			(size 0.3 0.5)
			(layers "F.Cu" "F.Paste" "F.Mask")
			(roundrect_rratio 0.25)
			(net 415 "/Peripherals/PCIE2_TX1_CONN_N")
			(pinfunction "C")
			(pintype "passive")
		)
		(pad "2" smd roundrect
			(at 0.349 0 90)
			(size 0.3 0.5)
			(layers "F.Cu" "F.Paste" "F.Mask")
			(roundrect_rratio 0.25)
			(net 1 "GND")
			(pinfunction "A")
			(pintype "passive")
		)
	)
	(footprint "antmicro-footprints:C_0603_1608Metric_EIA"
		(layer "F.Cu")
		(at 59.36 94.63 90)
		(descr "Capacitor SMD 0603, IPC-7351 Density Level A")
		(tags "Capacitor 0603")
		(property "Reference" "C153"
			(at -2.32 28.119999 90)
			(layer "F.SilkS")
			(effects
				(font
					(size 0.7 0.7)
					(thickness 0.15)
				)
				(justify left bottom)
			)
		)
		(property "Value" "C_22u_16V_0603"
			(at -1.42757 1.770288 90)
			(layer "F.Fab")
			(effects
				(font
					(size 0.7 0.7)
					(thickness 0.15)
				)
				(justify left bottom)
			)
		)
		(property "Footprint" "antmicro-footprints:C_0603_1608Metric_EIA"
			(at 0 0 90)
			(layer "F.Fab")
			(hide yes)
			(effects
				(font
					(size 1.27 1.27)
					(thickness 0.15)
				)
			)
		)
		(property "Datasheet" "https://product.samsungsem.com/mlcc/CL10A226MO7JZN.do"
			(at 0 0 90)
			(layer "F.Fab")
			(hide yes)
			(effects
				(font
					(size 1.27 1.27)
					(thickness 0.15)
				)
			)
		)
		(property "Description" "SMD Multilayer Ceramic Capacitor"
			(at 0 0 90)
			(layer "F.Fab")
			(hide yes)
			(effects
				(font
					(size 1.27 1.27)
					(thickness 0.15)
				)
			)
		)
		(property "Manufacturer" "Samsung Electro-Mechanics"
			(at 0 0 90)
			(unlocked yes)
			(layer "F.Fab")
			(hide yes)
			(effects
				(font
					(size 1 1)
					(thickness 0.15)
				)
			)
		)
		(property "MPN" "CL10A226MO7JZNC"
			(at 0 0 90)
			(unlocked yes)
			(layer "F.Fab")
			(hide yes)
			(effects
				(font
					(size 1 1)
					(thickness 0.15)
				)
			)
		)
		(property "Val" "22u"
			(at 0 0 90)
			(unlocked yes)
			(layer "F.Fab")
			(hide yes)
			(effects
				(font
					(size 1 1)
					(thickness 0.15)
				)
			)
		)
		(property "License" "Apache-2.0"
			(at 0 0 90)
			(unlocked yes)
			(layer "F.Fab")
			(hide yes)
			(effects
				(font
					(size 1 1)
					(thickness 0.15)
				)
			)
		)
		(property "Author" "Antmicro"
			(at 0 0 90)
			(unlocked yes)
			(layer "F.Fab")
			(hide yes)
			(effects
				(font
					(size 1 1)
					(thickness 0.15)
				)
			)
		)
		(property "Voltage" "16V"
			(at 0 0 90)
			(unlocked yes)
			(layer "F.Fab")
			(hide yes)
			(effects
				(font
					(size 1 1)
					(thickness 0.15)
				)
			)
		)
		(property "Dielectric" ""
			(at 0 0 90)
			(unlocked yes)
			(layer "F.Fab")
			(hide yes)
			(effects
				(font
					(size 1 1)
					(thickness 0.15)
				)
			)
		)
		(sheetname "Supply")
		(sheetfile "supply.kicad_sch")
		(attr smd)
		(fp_line
			(start -0.15 -0.55)
			(end 0.15 -0.55)
			(stroke
				(width 0.15)
				(type solid)
			)
			(layer "F.SilkS")
		)
		(fp_line
			(start -0.15 0.55)
			(end 0.15 0.55)
			(stroke
				(width 0.15)
				(type solid)
			)
			(layer "F.SilkS")
		)
		(fp_rect
			(start -1.25 -0.65)
			(end 1.25 0.65)
			(stroke
				(width 0.05)
				(type solid)
			)
			(fill none)
			(layer "F.CrtYd")
		)
		(fp_rect
			(start -0.8 -0.45)
			(end 0.8 0.45)
			(stroke
				(width 0.15)
				(type solid)
			)
			(fill none)
			(layer "F.Fab")
		)
		(fp_text user "License: Apache-2.0"
			(at -1.682 5.895 90)
			(layer "F.Fab")
			(hide yes)
			(effects
				(font
					(size 0.7 0.7)
					(thickness 0.15)
				)
				(justify left bottom)
			)
		)
		(fp_text user "${REFERENCE}"
			(at -1.682 3.895 90)
			(layer "F.Fab")
			(hide yes)
			(effects
				(font
					(size 0.7 0.7)
					(thickness 0.15)
				)
				(justify left bottom)
			)
		)
		(fp_text user "Author: Antmicro"
			(at -1.682 4.894 90)
			(layer "F.Fab")
			(hide yes)
			(effects
				(font
					(size 0.7 0.7)
					(thickness 0.15)
				)
				(justify left bottom)
			)
		)
		(pad "1" smd roundrect
			(at -0.7 0 90)
			(size 0.8 1.1)
			(layers "F.Cu" "F.Paste" "F.Mask")
			(roundrect_rratio 0.2)
			(net 1 "GND")
			(pintype "passive")
		)
		(pad "2" smd roundrect
			(at 0.7 0 90)
			(size 0.8 1.1)
			(layers "F.Cu" "F.Paste" "F.Mask")
			(roundrect_rratio 0.2)
			(net 761 "/Supply/5V_OUT")
			(pintype "passive")
		)
	)
	(footprint "antmicro-footprints:TSOT23-6"
		(layer "F.Cu")
		(at 63 110.05 90)
		(property "Reference" "U9"
			(at -1.9 -1.89 90)
			(layer "F.SilkS")
			(effects
				(font
					(size 0.7 0.7)
					(thickness 0.15)
				)
				(justify left bottom)
			)
		)
		(property "Value" "AP22615A_TSOT26"
			(at 0 2.6 90)
			(layer "F.Fab")
			(effects
				(font
					(size 0.7 0.7)
					(thickness 0.15)
				)
				(justify left bottom)
			)
		)
		(property "Footprint" "antmicro-footprints:TSOT23-6"
			(at 0 0 90)
			(layer "F.Fab")
			(hide yes)
			(effects
				(font
					(size 1.27 1.27)
					(thickness 0.15)
				)
			)
		)
		(property "Datasheet" "https://www.mouser.com/datasheet/2/115/DIOD_S_A0008958405_1-2543193.pdf"
			(at 0 0 90)
			(layer "F.Fab")
			(hide yes)
			(effects
				(font
					(size 1.27 1.27)
					(thickness 0.15)
				)
			)
		)
		(property "Author" "Antmicro"
			(at 173.05 47.05 0)
			(layer "F.Fab")
			(hide yes)
			(effects
				(font
					(size 1 1)
					(thickness 0.15)
				)
			)
		)
		(property "License" "Apache-2.0"
			(at 173.05 47.05 0)
			(layer "F.Fab")
			(hide yes)
			(effects
				(font
					(size 1 1)
					(thickness 0.15)
				)
			)
		)
		(property "MPN" "AP22615AWU-7"
			(at 173.05 47.05 0)
			(layer "F.Fab")
			(hide yes)
			(effects
				(font
					(size 1 1)
					(thickness 0.15)
				)
			)
		)
		(property "Manufacturer" "Diodes Incorporated"
			(at 173.05 47.05 0)
			(layer "F.Fab")
			(hide yes)
			(effects
				(font
					(size 1 1)
					(thickness 0.15)
				)
			)
		)
		(sheetname "USB Debug, DP")
		(sheetfile "usb.kicad_sch")
		(attr smd)
		(fp_line
			(start -1 -1.5)
			(end -1 -1.375)
			(stroke
				(width 0.15)
				(type solid)
			)
			(layer "F.SilkS")
		)
		(fp_line
			(start 1 -1.497)
			(end -1 -1.5)
			(stroke
				(width 0.15)
				(type solid)
			)
			(layer "F.SilkS")
		)
		(fp_line
			(start 1 -1.497)
			(end 1 -1.375)
			(stroke
				(width 0.15)
				(type solid)
			)
			(layer "F.SilkS")
		)
		(fp_line
			(start 1 1.55)
			(end 1 1.4)
			(stroke
				(width 0.15)
				(type solid)
			)
			(layer "F.SilkS")
		)
		(fp_line
			(start 1 1.55)
			(end -1 1.55)
			(stroke
				(width 0.15)
				(type solid)
			)
			(layer "F.SilkS")
		)
		(fp_line
			(start -1 1.55)
			(end -1 1.4)
			(stroke
				(width 0.15)
				(type solid)
			)
			(layer "F.SilkS")
		)
		(fp_circle
			(center -1.44 -1.5)
			(end -1.39 -1.5)
			(stroke
				(width 0.15)
				(type solid)
			)
			(fill solid)
			(layer "F.SilkS")
		)
		(fp_rect
			(start 1.93 -1.7)
			(end -1.93 1.7)
			(stroke
				(width 0.05)
				(type solid)
			)
			(fill none)
			(layer "F.CrtYd")
		)
		(fp_line
			(start -0.45 -1.521)
			(end -0.876 -1.096)
			(stroke
				(width 0.15)
				(type solid)
			)
			(layer "F.Fab")
		)
		(fp_rect
			(start 0.875 1.528)
			(end -0.875 -1.525)
			(stroke
				(width 0.15)
				(type solid)
			)
			(fill none)
			(layer "F.Fab")
		)
		(fp_text user "${REFERENCE}"
			(at -1.93 3.8 90)
			(layer "F.Fab")
			(hide yes)
			(effects
				(font
					(size 0.7 0.7)
					(thickness 0.15)
				)
				(justify left bottom)
			)
		)
		(fp_text user "License: Apache-2.0"
			(at -1.93 6.199 90)
			(layer "F.Fab")
			(hide yes)
			(effects
				(font
					(size 0.7 0.7)
					(thickness 0.15)
				)
				(justify left bottom)
			)
		)
		(fp_text user "Author: Antmicro"
			(at -1.93 5 90)
			(layer "F.Fab")
			(hide yes)
			(effects
				(font
					(size 0.7 0.7)
					(thickness 0.15)
				)
				(justify left bottom)
			)
		)
		(pad "1" smd rect
			(at -1.301 -0.947)
			(size 0.7 1.2)
			(layers "F.Cu" "F.Paste" "F.Mask")
			(net 196 "/USB Debug, DP/USBC3_VBUS")
			(pinfunction "OUT")
			(pintype "power_out")
		)
		(pad "2" smd rect
			(at -1.301 0.004)
			(size 0.7 1.2)
			(layers "F.Cu" "F.Paste" "F.Mask")
			(net 1 "GND")
			(pinfunction "GND")
			(pintype "power_in")
		)
		(pad "3" smd rect
			(at -1.301 0.954)
			(size 0.7 1.2)
			(layers "F.Cu" "F.Paste" "F.Mask")
			(net 501 "/USB Debug, DP/USBC3_FLG")
			(pinfunction "FLG")
			(pintype "output")
		)
		(pad "4" smd rect
			(at 1.299 0.954)
			(size 0.7 1.2)
			(layers "F.Cu" "F.Paste" "F.Mask")
			(net 657 "Net-(U9-EN)")
			(pinfunction "EN")
			(pintype "input")
		)
		(pad "5" smd rect
			(at 1.299 0.004)
			(size 0.7 1.2)
			(layers "F.Cu" "F.Paste" "F.Mask")
			(net 672 "Net-(U9-ISET)")
			(pinfunction "ISET")
			(pintype "passive")
		)
		(pad "6" smd rect
			(at 1.299 -0.947)
			(size 0.7 1.2)
			(layers "F.Cu" "F.Paste" "F.Mask")
			(net 99 "+5V")
			(pinfunction "IN")
			(pintype "power_in")
		)
	)
	(footprint "antmicro-footprints:Fiducial_1mm_Mask2mm"
		(layer "F.Cu")
		(at 148.6 69.9)
		(descr "Circular Fiducial, 1mm bare copper, 3mm soldermask opening")
		(tags "fiducial")
		(property "Reference" "FID3"
			(at 0 -1.4 0)
			(layer "F.SilkS")
			(hide yes)
			(effects
				(font
					(size 0.7 0.7)
					(thickness 0.15)
				)
				(justify left bottom)
			)
		)
		(property "Value" "Fiducial_1mm_Mask2mm"
			(at 0 2.2 0)
			(layer "F.Fab")
			(effects
				(font
					(size 0.7 0.7)
					(thickness 0.15)
				)
				(justify left bottom)
			)
		)
		(property "Footprint" "antmicro-footprints:Fiducial_1mm_Mask2mm"
			(at 0 0 0)
			(layer "F.Fab")
			(hide yes)
			(effects
				(font
					(size 1.27 1.27)
					(thickness 0.15)
				)
			)
		)
		(attr board_only exclude_from_pos_files exclude_from_bom)
		(fp_circle
			(center 0 0)
			(end 1.24 0)
			(stroke
				(width 0.05)
				(type solid)
			)
			(fill none)
			(layer "F.CrtYd")
		)
		(fp_circle
			(center 0 0)
			(end 0.999 0)
			(stroke
				(width 0.15)
				(type solid)
			)
			(fill none)
			(layer "F.Fab")
		)
		(fp_text user "License: Apache-2.0"
			(at -1.25 7.003 0)
			(layer "F.Fab")
			(hide yes)
			(effects
				(font
					(size 0.7 0.7)
					(thickness 0.15)
				)
				(justify left bottom)
			)
		)
		(fp_text user "Author: Antmicro"
			(at -1.25 5.803 0)
			(layer "F.Fab")
			(hide yes)
			(effects
				(font
					(size 0.7 0.7)
					(thickness 0.15)
				)
				(justify left bottom)
			)
		)
		(fp_text user "${REFERENCE}"
			(at -1.25 4.603 0)
			(layer "F.Fab")
			(hide yes)
			(effects
				(font
					(size 0.7 0.7)
					(thickness 0.15)
				)
				(justify left bottom)
			)
		)
		(pad "" smd circle
			(at 0 0)
			(size 1 1)
			(layers "F.Cu" "F.Mask")
			(solder_mask_margin 0.5)
			(clearance 0.5)
		)
	)
	(footprint "antmicro-footprints:C_0603_1608Metric_EIA"
		(layer "F.Cu")
		(at 73.89 91.67 -90)
		(descr "Capacitor SMD 0603, IPC-7351 Density Level A")
		(tags "Capacitor 0603")
		(property "Reference" "C154"
			(at -6.406396 -13.78 -90)
			(layer "F.SilkS")
			(effects
				(font
					(size 0.7 0.7)
					(thickness 0.15)
				)
				(justify left bottom)
			)
		)
		(property "Value" "C_22u_16V_0603"
			(at -1.42757 1.770288 -90)
			(layer "F.Fab")
			(effects
				(font
					(size 0.7 0.7)
					(thickness 0.15)
				)
				(justify left bottom)
			)
		)
		(property "Footprint" "antmicro-footprints:C_0603_1608Metric_EIA"
			(at 0 0 -90)
			(layer "F.Fab")
			(hide yes)
			(effects
				(font
					(size 1.27 1.27)
					(thickness 0.15)
				)
			)
		)
		(property "Datasheet" "https://product.samsungsem.com/mlcc/CL10A226MO7JZN.do"
			(at 0 0 -90)
			(layer "F.Fab")
			(hide yes)
			(effects
				(font
					(size 1.27 1.27)
					(thickness 0.15)
				)
			)
		)
		(property "Description" "SMD Multilayer Ceramic Capacitor"
			(at 0 0 -90)
			(layer "F.Fab")
			(hide yes)
			(effects
				(font
					(size 1.27 1.27)
					(thickness 0.15)
				)
			)
		)
		(property "Manufacturer" "Samsung Electro-Mechanics"
			(at 0 0 -90)
			(unlocked yes)
			(layer "F.Fab")
			(hide yes)
			(effects
				(font
					(size 1 1)
					(thickness 0.15)
				)
			)
		)
		(property "MPN" "CL10A226MO7JZNC"
			(at 0 0 -90)
			(unlocked yes)
			(layer "F.Fab")
			(hide yes)
			(effects
				(font
					(size 1 1)
					(thickness 0.15)
				)
			)
		)
		(property "Val" "22u"
			(at 0 0 -90)
			(unlocked yes)
			(layer "F.Fab")
			(hide yes)
			(effects
				(font
					(size 1 1)
					(thickness 0.15)
				)
			)
		)
		(property "License" "Apache-2.0"
			(at 0 0 -90)
			(unlocked yes)
			(layer "F.Fab")
			(hide yes)
			(effects
				(font
					(size 1 1)
					(thickness 0.15)
				)
			)
		)
		(property "Author" "Antmicro"
			(at 0 0 -90)
			(unlocked yes)
			(layer "F.Fab")
			(hide yes)
			(effects
				(font
					(size 1 1)
					(thickness 0.15)
				)
			)
		)
		(property "Voltage" "16V"
			(at 0 0 -90)
			(unlocked yes)
			(layer "F.Fab")
			(hide yes)
			(effects
				(font
					(size 1 1)
					(thickness 0.15)
				)
			)
		)
		(property "Dielectric" ""
			(at 0 0 -90)
			(unlocked yes)
			(layer "F.Fab")
			(hide yes)
			(effects
				(font
					(size 1 1)
					(thickness 0.15)
				)
			)
		)
		(sheetname "Supply")
		(sheetfile "supply.kicad_sch")
		(attr smd)
		(fp_line
			(start -0.15 0.55)
			(end 0.15 0.55)
			(stroke
				(width 0.15)
				(type solid)
			)
			(layer "F.SilkS")
		)
		(fp_line
			(start -0.15 -0.55)
			(end 0.15 -0.55)
			(stroke
				(width 0.15)
				(type solid)
			)
			(layer "F.SilkS")
		)
		(fp_rect
			(start -1.25 -0.65)
			(end 1.25 0.65)
			(stroke
				(width 0.05)
				(type solid)
			)
			(fill none)
			(layer "F.CrtYd")
		)
		(fp_rect
			(start -0.8 -0.45)
			(end 0.8 0.45)
			(stroke
				(width 0.15)
				(type solid)
			)
			(fill none)
			(layer "F.Fab")
		)
		(fp_text user "Author: Antmicro"
			(at -1.682 4.894 -90)
			(layer "F.Fab")
			(hide yes)
			(effects
				(font
					(size 0.7 0.7)
					(thickness 0.15)
				)
				(justify left bottom)
			)
		)
		(fp_text user "License: Apache-2.0"
			(at -1.682 5.895 -90)
			(layer "F.Fab")
			(hide yes)
			(effects
				(font
					(size 0.7 0.7)
					(thickness 0.15)
				)
				(justify left bottom)
			)
		)
		(fp_text user "${REFERENCE}"
			(at -1.682 3.895 -90)
			(layer "F.Fab")
			(hide yes)
			(effects
				(font
					(size 0.7 0.7)
					(thickness 0.15)
				)
				(justify left bottom)
			)
		)
		(pad "1" smd roundrect
			(at -0.7 0 270)
			(size 0.8 1.1)
			(layers "F.Cu" "F.Paste" "F.Mask")
			(roundrect_rratio 0.2)
			(net 1 "GND")
			(pintype "passive")
		)
		(pad "2" smd roundrect
			(at 0.7 0 270)
			(size 0.8 1.1)
			(layers "F.Cu" "F.Paste" "F.Mask")
			(roundrect_rratio 0.2)
			(net 641 "/Supply/3V3_OUT")
			(pintype "passive")
		)
	)
	(footprint "antmicro-footprints:R_0402_1005Metric"
		(layer "F.Cu")
		(at 107.2 110.625 -90)
		(descr "Resistor SMD 0402")
		(tags "resistor SMD 0402")
		(property "Reference" "R126"
			(at 3.625 -0.45 -90)
			(layer "F.SilkS")
			(effects
				(font
					(size 0.7 0.7)
					(thickness 0.15)
				)
				(justify left bottom)
			)
		)
		(property "Value" "R_200k_0402"
			(at 0 1.4 -90)
			(layer "F.Fab")
			(effects
				(font
					(size 0.7 0.7)
					(thickness 0.15)
				)
				(justify left bottom)
			)
		)
		(property "Footprint" "antmicro-footprints:R_0402_1005Metric"
			(at 0 0 -90)
			(layer "F.Fab")
			(hide yes)
			(effects
				(font
					(size 1.27 1.27)
					(thickness 0.15)
				)
			)
		)
		(property "Datasheet" "https://www.bourns.com/docs/product-datasheets/cr.pdf"
			(at 0 0 -90)
			(layer "F.Fab")
			(hide yes)
			(effects
				(font
					(size 1.27 1.27)
					(thickness 0.15)
				)
			)
		)
		(property "Author" "Antmicro"
			(at -3.425 217.825 0)
			(layer "F.Fab")
			(hide yes)
			(effects
				(font
					(size 1 1)
					(thickness 0.15)
				)
			)
		)
		(property "License" "Apache-2.0"
			(at -3.425 217.825 0)
			(layer "F.Fab")
			(hide yes)
			(effects
				(font
					(size 1 1)
					(thickness 0.15)
				)
			)
		)
		(property "MPN" "CR0402-FX-2003GLF"
			(at -3.425 217.825 0)
			(layer "F.Fab")
			(hide yes)
			(effects
				(font
					(size 1 1)
					(thickness 0.15)
				)
			)
		)
		(property "Manufacturer" "Bourns"
			(at -3.425 217.825 0)
			(layer "F.Fab")
			(hide yes)
			(effects
				(font
					(size 1 1)
					(thickness 0.15)
				)
			)
		)
		(property "Tolerance" "1%"
			(at -3.425 217.825 0)
			(layer "F.Fab")
			(hide yes)
			(effects
				(font
					(size 1 1)
					(thickness 0.15)
				)
			)
		)
		(property "Val" "200k"
			(at -3.425 217.825 0)
			(layer "F.Fab")
			(hide yes)
			(effects
				(font
					(size 1 1)
					(thickness 0.15)
				)
			)
		)
		(sheetname "USB3")
		(sheetfile "usb3.kicad_sch")
		(attr smd)
		(fp_rect
			(start -0.925 -0.47)
			(end 0.925 0.47)
			(stroke
				(width 0.05)
				(type default)
			)
			(fill none)
			(layer "F.CrtYd")
		)
		(fp_rect
			(start -0.5 -0.25)
			(end 0.5 0.25)
			(stroke
				(width 0.15)
				(type solid)
			)
			(fill none)
			(layer "F.Fab")
		)
		(fp_text user "${REFERENCE}"
			(at -0.95 3.168 -90)
			(layer "F.Fab")
			(hide yes)
			(effects
				(font
					(size 0.7 0.7)
					(thickness 0.15)
				)
				(justify left bottom)
			)
		)
		(fp_text user "Author: Antmicro"
			(at -0.95 4.169 -90)
			(layer "F.Fab")
			(hide yes)
			(effects
				(font
					(size 0.7 0.7)
					(thickness 0.15)
				)
				(justify left bottom)
			)
		)
		(fp_text user "License: Apache-2.0"
			(at -0.95 5.169 -90)
			(layer "F.Fab")
			(hide yes)
			(effects
				(font
					(size 0.7 0.7)
					(thickness 0.15)
				)
				(justify left bottom)
			)
		)
		(pad "1" smd roundrect
			(at -0.48 0 270)
			(size 0.59 0.64)
			(layers "F.Cu" "F.Paste" "F.Mask")
			(roundrect_rratio 0.25)
			(net 364 "/USB3/USBC1_DIR")
			(pintype "passive")
		)
		(pad "2" smd roundrect
			(at 0.48 0 270)
			(size 0.59 0.64)
			(layers "F.Cu" "F.Paste" "F.Mask")
			(roundrect_rratio 0.25)
			(net 87 "+3V3")
			(pintype "passive")
		)
	)
	(footprint "antmicro-footprints:R_0402_1005Metric"
		(layer "F.Cu")
		(at 96.15 101.4 180)
		(descr "Resistor SMD 0402")
		(tags "resistor SMD 0402")
		(property "Reference" "R162"
			(at -0.8 -0.4 180)
			(layer "F.SilkS")
			(effects
				(font
					(size 0.7 0.7)
					(thickness 0.15)
				)
				(justify left bottom)
			)
		)
		(property "Value" "R_0R_0402"
			(at 0 1.4 180)
			(layer "F.Fab")
			(effects
				(font
					(size 0.7 0.7)
					(thickness 0.15)
				)
				(justify left bottom)
			)
		)
		(property "Footprint" "antmicro-footprints:R_0402_1005Metric"
			(at 0 0 180)
			(layer "F.Fab")
			(hide yes)
			(effects
				(font
					(size 1.27 1.27)
					(thickness 0.15)
				)
			)
		)
		(property "Datasheet" "https://industrial.panasonic.com/cdbs/www-data/pdf/RDA0000/AOA0000C301.pdf"
			(at 0 0 180)
			(layer "F.Fab")
			(hide yes)
			(effects
				(font
					(size 1.27 1.27)
					(thickness 0.15)
				)
			)
		)
		(property "Author" "Antmicro"
			(at 192.3 202.8 0)
			(layer "F.Fab")
			(hide yes)
			(effects
				(font
					(size 1 1)
					(thickness 0.15)
				)
			)
		)
		(property "Current" "1A"
			(at 192.3 202.8 0)
			(layer "F.Fab")
			(hide yes)
			(effects
				(font
					(size 1 1)
					(thickness 0.15)
				)
			)
		)
		(property "License" "Apache-2.0"
			(at 192.3 202.8 0)
			(layer "F.Fab")
			(hide yes)
			(effects
				(font
					(size 1 1)
					(thickness 0.15)
				)
			)
		)
		(property "MPN" "ERJ2GE0R00X"
			(at 192.3 202.8 0)
			(layer "F.Fab")
			(hide yes)
			(effects
				(font
					(size 1 1)
					(thickness 0.15)
				)
			)
		)
		(property "Manufacturer" "Panasonic"
			(at 192.3 202.8 0)
			(layer "F.Fab")
			(hide yes)
			(effects
				(font
					(size 1 1)
					(thickness 0.15)
				)
			)
		)
		(property "Tolerance" ""
			(at 192.3 202.8 0)
			(layer "F.Fab")
			(hide yes)
			(effects
				(font
					(size 1 1)
					(thickness 0.15)
				)
			)
		)
		(property "Val" "0R"
			(at 192.3 202.8 0)
			(layer "F.Fab")
			(hide yes)
			(effects
				(font
					(size 1 1)
					(thickness 0.15)
				)
			)
		)
		(sheetname "CSI")
		(sheetfile "csi.kicad_sch")
		(attr smd)
		(fp_rect
			(start -0.925 -0.47)
			(end 0.925 0.47)
			(stroke
				(width 0.05)
				(type default)
			)
			(fill none)
			(layer "F.CrtYd")
		)
		(fp_rect
			(start -0.5 -0.25)
			(end 0.5 0.25)
			(stroke
				(width 0.15)
				(type solid)
			)
			(fill none)
			(layer "F.Fab")
		)
		(fp_text user "License: Apache-2.0"
			(at -0.95 5.169 180)
			(layer "F.Fab")
			(hide yes)
			(effects
				(font
					(size 0.7 0.7)
					(thickness 0.15)
				)
				(justify left bottom)
			)
		)
		(fp_text user "${REFERENCE}"
			(at -0.95 3.168 180)
			(layer "F.Fab")
			(hide yes)
			(effects
				(font
					(size 0.7 0.7)
					(thickness 0.15)
				)
				(justify left bottom)
			)
		)
		(fp_text user "Author: Antmicro"
			(at -0.95 4.169 180)
			(layer "F.Fab")
			(hide yes)
			(effects
				(font
					(size 0.7 0.7)
					(thickness 0.15)
				)
				(justify left bottom)
			)
		)
		(pad "1" smd roundrect
			(at -0.48 0 180)
			(size 0.59 0.64)
			(layers "F.Cu" "F.Paste" "F.Mask")
			(roundrect_rratio 0.25)
			(net 512 "/CSI/I2C_MUX_SCL")
			(pintype "passive")
		)
		(pad "2" smd roundrect
			(at 0.48 0 180)
			(size 0.59 0.64)
			(layers "F.Cu" "F.Paste" "F.Mask")
			(roundrect_rratio 0.25)
			(net 81 "SCL_CAM")
			(pintype "passive")
		)
	)
	(footprint "antmicro-footprints:R_Array_4x0201_Panasonic_EXB18V"
		(layer "F.Cu")
		(at 97.21 104.25 -135)
		(property "Reference" "R50"
			(at 1.046518 -1.583919 45)
			(layer "F.SilkS")
			(effects
				(font
					(size 0.7 0.7)
					(thickness 0.15)
				)
				(justify left bottom)
			)
		)
		(property "Value" "R_4x0R_0201_array"
			(at -1.1 1.8 -135)
			(layer "F.Fab")
			(effects
				(font
					(size 0.7 0.7)
					(thickness 0.15)
				)
				(justify left bottom)
			)
		)
		(property "Footprint" "antmicro-footprints:R_Array_4x0201_Panasonic_EXB18V"
			(at 0 0 -135)
			(layer "F.Fab")
			(hide yes)
			(effects
				(font
					(size 1.27 1.27)
					(thickness 0.15)
				)
			)
		)
		(property "Datasheet" "http://industrial.panasonic.com/cdbs/www-data/pdf/AOC0000/AOC0000C14.pdf"
			(at 0 0 -135)
			(layer "F.Fab")
			(hide yes)
			(effects
				(font
					(size 1.27 1.27)
					(thickness 0.15)
				)
			)
		)
		(property "Author" "Antmicro"
			(at 92.231968 246.703732 0)
			(layer "F.Fab")
			(hide yes)
			(effects
				(font
					(size 1 1)
					(thickness 0.15)
				)
			)
		)
		(property "License" "Apache-2.0"
			(at 92.231968 246.703732 0)
			(layer "F.Fab")
			(hide yes)
			(effects
				(font
					(size 1 1)
					(thickness 0.15)
				)
			)
		)
		(property "MPN" "EXB-18VR000X"
			(at 92.231968 246.703732 0)
			(layer "F.Fab")
			(hide yes)
			(effects
				(font
					(size 1 1)
					(thickness 0.15)
				)
			)
		)
		(property "Manufacturer" "Panasonic"
			(at 92.231968 246.703732 0)
			(layer "F.Fab")
			(hide yes)
			(effects
				(font
					(size 1 1)
					(thickness 0.15)
				)
			)
		)
		(property "Val" "4x0R_0201"
			(at 92.231968 246.703732 0)
			(layer "F.Fab")
			(hide yes)
			(effects
				(font
					(size 1 1)
					(thickness 0.15)
				)
			)
		)
		(sheetname "CSI")
		(sheetfile "csi.kicad_sch")
		(attr smd)
		(fp_line
			(start 0.799999 -0.45)
			(end 0.799999 0.45)
			(stroke
				(width 0.12)
				(type solid)
			)
			(layer "F.SilkS")
		)
		(fp_line
			(start -0.799999 -0.45)
			(end -0.799999 0.45)
			(stroke
				(width 0.12)
				(type solid)
			)
			(layer "F.SilkS")
		)
		(fp_poly
			(pts
				(xy -0.897999 -0.66) (xy 0.897999 -0.66) (xy 0.897999 0.65) (xy -0.897999 0.65)
			)
			(stroke
				(width 0.05)
				(type solid)
			)
			(fill none)
			(layer "F.CrtYd")
		)
		(fp_text user "${REFERENCE}"
			(at -1.051 3.2 -135)
			(layer "F.Fab")
			(hide yes)
			(effects
				(font
					(size 0.7 0.7)
					(thickness 0.15)
				)
				(justify left bottom)
			)
		)
		(fp_text user "License: Apache-2.0"
			(at -1.051 6 -135)
			(layer "F.Fab")
			(hide yes)
			(effects
				(font
					(size 0.7 0.7)
					(thickness 0.15)
				)
				(justify left bottom)
			)
		)
		(fp_text user "Author: Antmicro"
			(at -1.051 4.599 -135)
			(layer "F.Fab")
			(hide yes)
			(effects
				(font
					(size 0.7 0.7)
					(thickness 0.15)
				)
				(justify left bottom)
			)
		)
		(pad "1" smd roundrect
			(at -0.6 0.298 225)
			(size 0.2 0.4)
			(layers "F.Cu" "F.Paste" "F.Mask")
			(roundrect_rratio 0.25)
			(net 320 "/CSI/SDA_CAM0")
			(pinfunction "R1.1")
			(pintype "passive")
		)
		(pad "2" smd roundrect
			(at -0.202 0.298 225)
			(size 0.2 0.4)
			(layers "F.Cu" "F.Paste" "F.Mask")
			(roundrect_rratio 0.25)
			(net 323 "/CSI/SCL_CAM0")
			(pinfunction "R2.1")
			(pintype "passive")
		)
		(pad "3" smd roundrect
			(at 0.2 0.298 225)
			(size 0.2 0.4)
			(layers "F.Cu" "F.Paste" "F.Mask")
			(roundrect_rratio 0.25)
			(net 329 "/CSI/SDA_CAM1")
			(pinfunction "R3.1")
			(pintype "passive")
		)
		(pad "4" smd roundrect
			(at 0.598 0.298 225)
			(size 0.2 0.4)
			(layers "F.Cu" "F.Paste" "F.Mask")
			(roundrect_rratio 0.25)
			(net 330 "/CSI/SCL_CAM1")
			(pinfunction "R4.1")
			(pintype "passive")
		)
		(pad "5" smd roundrect
			(at 0.598 -0.3 225)
			(size 0.2 0.4)
			(layers "F.Cu" "F.Paste" "F.Mask")
			(roundrect_rratio 0.25)
			(net 563 "Net-(R50-R4.2)")
			(pinfunction "R4.2")
			(pintype "passive")
		)
		(pad "6" smd roundrect
			(at 0.199999 -0.3 225)
			(size 0.2 0.4)
			(layers "F.Cu" "F.Paste" "F.Mask")
			(roundrect_rratio 0.25)
			(net 560 "Net-(R50-R3.2)")
			(pinfunction "R3.2")
			(pintype "passive")
		)
		(pad "7" smd roundrect
			(at -0.202001 -0.3 225)
			(size 0.2 0.4)
			(layers "F.Cu" "F.Paste" "F.Mask")
			(roundrect_rratio 0.25)
			(net 559 "Net-(R50-R2.2)")
			(pinfunction "R2.2")
			(pintype "passive")
		)
		(pad "8" smd roundrect
			(at -0.6 -0.3 225)
			(size 0.2 0.4)
			(layers "F.Cu" "F.Paste" "F.Mask")
			(roundrect_rratio 0.25)
			(net 554 "Net-(R50-R1.2)")
			(pinfunction "R1.2")
			(pintype "passive")
		)
	)
	(footprint "antmicro-footprints:R_0402_1005Metric"
		(layer "F.Cu")
		(at 66.21 98.93 180)
		(descr "Resistor SMD 0402")
		(tags "resistor SMD 0402")
		(property "Reference" "R170"
			(at -1.14 -2.295 0)
			(layer "F.SilkS")
			(effects
				(font
					(size 0.7 0.7)
					(thickness 0.15)
				)
				(justify right bottom)
			)
		)
		(property "Value" "R_73k2_0402"
			(at -1.011843 1.772047 0)
			(layer "F.Fab")
			(effects
				(font
					(size 0.7 0.7)
					(thickness 0.15)
				)
				(justify right bottom)
			)
		)
		(property "Footprint" "antmicro-footprints:R_0402_1005Metric"
			(at 0 0 180)
			(layer "F.Fab")
			(hide yes)
			(effects
				(font
					(size 1.27 1.27)
					(thickness 0.15)
				)
			)
		)
		(property "Datasheet" "https://www.bourns.com/docs/product-datasheets/cr.pdf"
			(at 0 0 180)
			(layer "F.Fab")
			(hide yes)
			(effects
				(font
					(size 1.27 1.27)
					(thickness 0.15)
				)
			)
		)
		(property "Author" "Antmicro"
			(at 132.42 197.86 0)
			(layer "F.Fab")
			(hide yes)
			(effects
				(font
					(size 1 1)
					(thickness 0.15)
				)
			)
		)
		(property "License" "Apache-2.0"
			(at 132.42 197.86 0)
			(layer "F.Fab")
			(hide yes)
			(effects
				(font
					(size 1 1)
					(thickness 0.15)
				)
			)
		)
		(property "MPN" "CR0402-FX-7322GLF"
			(at 132.42 197.86 0)
			(layer "F.Fab")
			(hide yes)
			(effects
				(font
					(size 1 1)
					(thickness 0.15)
				)
			)
		)
		(property "Manufacturer" "Bourns"
			(at 132.42 197.86 0)
			(layer "F.Fab")
			(hide yes)
			(effects
				(font
					(size 1 1)
					(thickness 0.15)
				)
			)
		)
		(property "Tolerance" "1%"
			(at 132.42 197.86 0)
			(layer "F.Fab")
			(hide yes)
			(effects
				(font
					(size 1 1)
					(thickness 0.15)
				)
			)
		)
		(property "Val" "73k2"
			(at 132.42 197.86 0)
			(layer "F.Fab")
			(hide yes)
			(effects
				(font
					(size 1 1)
					(thickness 0.15)
				)
			)
		)
		(sheetname "Supply")
		(sheetfile "supply.kicad_sch")
		(attr smd)
		(fp_rect
			(start -0.925 -0.47)
			(end 0.925 0.47)
			(stroke
				(width 0.05)
				(type default)
			)
			(fill none)
			(layer "F.CrtYd")
		)
		(fp_rect
			(start -0.5 -0.25)
			(end 0.5 0.25)
			(stroke
				(width 0.15)
				(type solid)
			)
			(fill none)
			(layer "F.Fab")
		)
		(fp_text user "License: Apache-2.0"
			(at -0.95 5.169 0)
			(layer "F.Fab")
			(hide yes)
			(effects
				(font
					(size 0.7 0.7)
					(thickness 0.15)
				)
				(justify right bottom)
			)
		)
		(fp_text user "Author: Antmicro"
			(at -0.95 4.169 0)
			(layer "F.Fab")
			(hide yes)
			(effects
				(font
					(size 0.7 0.7)
					(thickness 0.15)
				)
				(justify right bottom)
			)
		)
		(fp_text user "${REFERENCE}"
			(at -0.95 3.168 0)
			(layer "F.Fab")
			(hide yes)
			(effects
				(font
					(size 0.7 0.7)
					(thickness 0.15)
				)
				(justify right bottom)
			)
		)
		(pad "1" smd roundrect
			(at -0.48 0 180)
			(size 0.59 0.64)
			(layers "F.Cu" "F.Paste" "F.Mask")
			(roundrect_rratio 0.25)
			(net 766 "/Supply/5V_FB")
			(pintype "passive")
		)
		(pad "2" smd roundrect
			(at 0.48 0 180)
			(size 0.59 0.64)
			(layers "F.Cu" "F.Paste" "F.Mask")
			(roundrect_rratio 0.25)
			(net 761 "/Supply/5V_OUT")
			(pintype "passive")
		)
	)
	(footprint "antmicro-footprints:SW_KMR211NGLFS_SMD"
		(layer "F.Cu")
		(at 64.2 125.9)
		(property "Reference" "S4"
			(at -0.8 -1.8 0)
			(layer "F.SilkS")
			(effects
				(font
					(size 0.7 0.7)
					(thickness 0.15)
				)
				(justify left bottom)
			)
		)
		(property "Value" "SW_KMR211NGLFS_SMD"
			(at -3 3 0)
			(layer "F.Fab")
			(effects
				(font
					(size 0.7 0.7)
					(thickness 0.15)
				)
				(justify left bottom)
			)
		)
		(property "Footprint" "antmicro-footprints:SW_KMR211NGLFS_SMD"
			(at 0 0 0)
			(layer "F.Fab")
			(hide yes)
			(effects
				(font
					(size 1.27 1.27)
					(thickness 0.15)
				)
			)
		)
		(property "Datasheet" "http://www.farnell.com/datasheets/2631211.pdf"
			(at 0 0 0)
			(layer "F.Fab")
			(hide yes)
			(effects
				(font
					(size 1.27 1.27)
					(thickness 0.15)
				)
			)
		)
		(property "Author" "Antmicro"
			(at 0 0 0)
			(layer "F.Fab")
			(hide yes)
			(effects
				(font
					(size 1 1)
					(thickness 0.15)
				)
			)
		)
		(property "License" "Apache-2.0"
			(at 0 0 0)
			(layer "F.Fab")
			(hide yes)
			(effects
				(font
					(size 1 1)
					(thickness 0.15)
				)
			)
		)
		(property "MPN" "KMR211NGLFS"
			(at 0 0 0)
			(layer "F.Fab")
			(hide yes)
			(effects
				(font
					(size 1 1)
					(thickness 0.15)
				)
			)
		)
		(property "Manufacturer" "C&K"
			(at 0 0 0)
			(layer "F.Fab")
			(hide yes)
			(effects
				(font
					(size 1 1)
					(thickness 0.15)
				)
			)
		)
		(sheetname "Supply")
		(sheetfile "supply.kicad_sch")
		(attr smd)
		(fp_line
			(start -2.1 -1.6)
			(end -2.1 -1.499)
			(stroke
				(width 0.15)
				(type solid)
			)
			(layer "F.SilkS")
		)
		(fp_line
			(start -2.1 1.601)
			(end -2.1 1.48)
			(stroke
				(width 0.15)
				(type solid)
			)
			(layer "F.SilkS")
		)
		(fp_line
			(start 2.101 -1.6)
			(end -2.1 -1.6)
			(stroke
				(width 0.15)
				(type solid)
			)
			(layer "F.SilkS")
		)
		(fp_line
			(start 2.101 -1.58)
			(end 2.101 -1.459)
			(stroke
				(width 0.15)
				(type solid)
			)
			(layer "F.SilkS")
		)
		(fp_line
			(start 2.101 1.601)
			(end -2.1 1.601)
			(stroke
				(width 0.15)
				(type solid)
			)
			(layer "F.SilkS")
		)
		(fp_line
			(start 2.101 1.601)
			(end 2.101 1.48)
			(stroke
				(width 0.15)
				(type solid)
			)
			(layer "F.SilkS")
		)
		(fp_rect
			(start 2.751 1.75)
			(end -2.748 -1.749)
			(stroke
				(width 0.05)
				(type solid)
			)
			(fill none)
			(layer "F.CrtYd")
		)
		(fp_line
			(start -2.1 -1.6)
			(end -2.1 1.601)
			(stroke
				(width 0.15)
				(type solid)
			)
			(layer "F.Fab")
		)
		(fp_line
			(start -2.1 1.601)
			(end 2.101 1.601)
			(stroke
				(width 0.15)
				(type solid)
			)
			(layer "F.Fab")
		)
		(fp_line
			(start -0.248 -0.8)
			(end 0.25 -0.8)
			(stroke
				(width 0.15)
				(type solid)
			)
			(layer "F.Fab")
		)
		(fp_line
			(start 0.25 0.802)
			(end -0.248 0.802)
			(stroke
				(width 0.15)
				(type solid)
			)
			(layer "F.Fab")
		)
		(fp_line
			(start 2.101 -1.6)
			(end -2.1 -1.6)
			(stroke
				(width 0.15)
				(type solid)
			)
			(layer "F.Fab")
		)
		(fp_line
			(start 2.101 1.601)
			(end 2.101 -1.6)
			(stroke
				(width 0.15)
				(type solid)
			)
			(layer "F.Fab")
		)
		(fp_arc
			(start -0.248 0.802)
			(mid -1.050001 0.001)
			(end -0.248 -0.8)
			(stroke
				(width 0.15)
				(type solid)
			)
			(layer "F.Fab")
		)
		(fp_arc
			(start 0.25 -0.8)
			(mid 1.051001 0.001)
			(end 0.25 0.802)
			(stroke
				(width 0.15)
				(type solid)
			)
			(layer "F.Fab")
		)
		(fp_text user "${REFERENCE}"
			(at -3 4.25 0)
			(layer "F.Fab")
			(hide yes)
			(effects
				(font
					(size 0.7 0.7)
					(thickness 0.15)
				)
				(justify left bottom)
			)
		)
		(fp_text user "Author: Antmicro"
			(at -3 5.5 0)
			(layer "F.Fab")
			(hide yes)
			(effects
				(font
					(size 0.7 0.7)
					(thickness 0.15)
				)
				(justify left bottom)
			)
		)
		(fp_text user "License: Apache-2.0"
			(at -3 6.75 0)
			(layer "F.Fab")
			(hide yes)
			(effects
				(font
					(size 0.7 0.7)
					(thickness 0.15)
				)
				(justify left bottom)
			)
		)
		(pad "1" smd rect
			(at -2.048 -0.8 180)
			(size 0.9 1)
			(layers "F.Cu" "F.Paste" "F.Mask")
			(net 137 "Net-(D36-A)")
			(pinfunction "1")
			(pintype "passive")
		)
		(pad "2" smd rect
			(at 2.05 -0.8 180)
			(size 0.9 1)
			(layers "F.Cu" "F.Paste" "F.Mask")
			(net 137 "Net-(D36-A)")
			(pinfunction "2")
			(pintype "passive")
		)
		(pad "3" smd rect
			(at -2.048 0.802 180)
			(size 0.9 1)
			(layers "F.Cu" "F.Paste" "F.Mask")
			(net 1 "GND")
			(pinfunction "3")
			(pintype "passive")
		)
		(pad "4" smd rect
			(at 2.05 0.802 180)
			(size 0.9 1)
			(layers "F.Cu" "F.Paste" "F.Mask")
			(net 1 "GND")
			(pinfunction "4")
			(pintype "passive")
		)
	)
	(footprint "antmicro-footprints:R_0402_1005Metric"
		(layer "F.Cu")
		(at 48.3 105.3 90)
		(descr "Resistor SMD 0402")
		(tags "resistor SMD 0402")
		(property "Reference" "R286"
			(at -13 1.9 -90)
			(layer "F.SilkS")
			(effects
				(font
					(size 0.7 0.7)
					(thickness 0.15)
				)
				(justify left bottom)
			)
		)
		(property "Value" "R_470R_0402"
			(at -1.011843 1.772046 90)
			(layer "F.Fab")
			(effects
				(font
					(size 0.7 0.7)
					(thickness 0.15)
				)
				(justify left bottom)
			)
		)
		(property "Footprint" "antmicro-footprints:R_0402_1005Metric"
			(at 0 0 90)
			(layer "F.Fab")
			(hide yes)
			(effects
				(font
					(size 1.27 1.27)
					(thickness 0.15)
				)
			)
		)
		(property "Datasheet" "https://www.bourns.com/docs/product-datasheets/cr.pdf"
			(at 0 0 90)
			(layer "F.Fab")
			(hide yes)
			(effects
				(font
					(size 1.27 1.27)
					(thickness 0.15)
				)
			)
		)
		(property "Manufacturer" "Bourns"
			(at 0 0 90)
			(unlocked yes)
			(layer "F.Fab")
			(hide yes)
			(effects
				(font
					(size 1 1)
					(thickness 0.15)
				)
			)
		)
		(property "MPN" "CR0402-FX-4700GLF"
			(at 0 0 90)
			(unlocked yes)
			(layer "F.Fab")
			(hide yes)
			(effects
				(font
					(size 1 1)
					(thickness 0.15)
				)
			)
		)
		(property "Val" "470R"
			(at 0 0 90)
			(unlocked yes)
			(layer "F.Fab")
			(hide yes)
			(effects
				(font
					(size 1 1)
					(thickness 0.15)
				)
			)
		)
		(property "License" "Apache-2.0"
			(at 0 0 90)
			(unlocked yes)
			(layer "F.Fab")
			(hide yes)
			(effects
				(font
					(size 1 1)
					(thickness 0.15)
				)
			)
		)
		(property "Author" "Antmicro"
			(at 0 0 90)
			(unlocked yes)
			(layer "F.Fab")
			(hide yes)
			(effects
				(font
					(size 1 1)
					(thickness 0.15)
				)
			)
		)
		(property "Tolerance" "1%"
			(at 0 0 90)
			(unlocked yes)
			(layer "F.Fab")
			(hide yes)
			(effects
				(font
					(size 1 1)
					(thickness 0.15)
				)
			)
		)
		(sheetname "Supply")
		(sheetfile "supply.kicad_sch")
		(attr smd)
		(fp_poly
			(pts
				(xy -0.925 -0.47) (xy 0.925 -0.47) (xy 0.925 0.47) (xy -0.925 0.47)
			)
			(stroke
				(width 0.05)
				(type default)
			)
			(fill none)
			(layer "F.CrtYd")
		)
		(fp_poly
			(pts
				(xy -0.5 -0.25) (xy 0.5 -0.25) (xy 0.5 0.25) (xy -0.5 0.25)
			)
			(stroke
				(width 0.15)
				(type solid)
			)
			(fill none)
			(layer "F.Fab")
		)
		(fp_text user "${REFERENCE}"
			(at -0.95 3.168 90)
			(layer "F.Fab")
			(hide yes)
			(effects
				(font
					(size 0.7 0.7)
					(thickness 0.15)
				)
				(justify left bottom)
			)
		)
		(fp_text user "Author: Antmicro"
			(at -0.95 4.169 90)
			(layer "F.Fab")
			(hide yes)
			(effects
				(font
					(size 0.7 0.7)
					(thickness 0.15)
				)
				(justify left bottom)
			)
		)
		(fp_text user "License: Apache-2.0"
			(at -0.949999 5.169 90)
			(layer "F.Fab")
			(hide yes)
			(effects
				(font
					(size 0.7 0.7)
					(thickness 0.15)
				)
				(justify left bottom)
			)
		)
		(pad "1" smd roundrect
			(at -0.48 0 90)
			(size 0.59 0.64)
			(layers "F.Cu" "F.Paste" "F.Mask")
			(roundrect_rratio 0.25)
			(net 798 "Net-(D62-A)")
			(pintype "passive")
		)
		(pad "2" smd roundrect
			(at 0.48 0 90)
			(size 0.59 0.64)
			(layers "F.Cu" "F.Paste" "F.Mask")
			(roundrect_rratio 0.25)
			(net 787 "+5V_SoM")
			(pintype "passive")
		)
	)
	(footprint "antmicro-footprints:R_0402_1005Metric"
		(layer "F.Cu")
		(at 68.85 124.8 90)
		(descr "Resistor SMD 0402")
		(tags "resistor SMD 0402")
		(property "Reference" "R106"
			(at 0.825 0.425 90)
			(layer "F.SilkS")
			(effects
				(font
					(size 0.7 0.7)
					(thickness 0.15)
				)
				(justify left bottom)
			)
		)
		(property "Value" "R_4k7_0402"
			(at 0 1.4 90)
			(layer "F.Fab")
			(effects
				(font
					(size 0.7 0.7)
					(thickness 0.15)
				)
				(justify left bottom)
			)
		)
		(property "Footprint" "antmicro-footprints:R_0402_1005Metric"
			(at 0 0 90)
			(layer "F.Fab")
			(hide yes)
			(effects
				(font
					(size 1.27 1.27)
					(thickness 0.15)
				)
			)
		)
		(property "Datasheet" "https://www.bourns.com/docs/product-datasheets/cr.pdf"
			(at 0 0 90)
			(layer "F.Fab")
			(hide yes)
			(effects
				(font
					(size 1.27 1.27)
					(thickness 0.15)
				)
			)
		)
		(property "Author" "Antmicro"
			(at 193.65 55.95 0)
			(layer "F.Fab")
			(hide yes)
			(effects
				(font
					(size 1 1)
					(thickness 0.15)
				)
			)
		)
		(property "License" "Apache-2.0"
			(at 193.65 55.95 0)
			(layer "F.Fab")
			(hide yes)
			(effects
				(font
					(size 1 1)
					(thickness 0.15)
				)
			)
		)
		(property "MPN" "CR0402-FX-4701GLF"
			(at 193.65 55.95 0)
			(layer "F.Fab")
			(hide yes)
			(effects
				(font
					(size 1 1)
					(thickness 0.15)
				)
			)
		)
		(property "Manufacturer" "Bourns"
			(at 193.65 55.95 0)
			(layer "F.Fab")
			(hide yes)
			(effects
				(font
					(size 1 1)
					(thickness 0.15)
				)
			)
		)
		(property "Tolerance" "1%"
			(at 193.65 55.95 0)
			(layer "F.Fab")
			(hide yes)
			(effects
				(font
					(size 1 1)
					(thickness 0.15)
				)
			)
		)
		(property "Val" "4k7"
			(at 193.65 55.95 0)
			(layer "F.Fab")
			(hide yes)
			(effects
				(font
					(size 1 1)
					(thickness 0.15)
				)
			)
		)
		(sheetname "USB Debug, DP")
		(sheetfile "usb.kicad_sch")
		(attr smd)
		(fp_rect
			(start -0.925 -0.47)
			(end 0.925 0.47)
			(stroke
				(width 0.05)
				(type default)
			)
			(fill none)
			(layer "F.CrtYd")
		)
		(fp_rect
			(start -0.5 -0.25)
			(end 0.5 0.25)
			(stroke
				(width 0.15)
				(type solid)
			)
			(fill none)
			(layer "F.Fab")
		)
		(fp_text user "License: Apache-2.0"
			(at -0.95 5.169 90)
			(layer "F.Fab")
			(hide yes)
			(effects
				(font
					(size 0.7 0.7)
					(thickness 0.15)
				)
				(justify left bottom)
			)
		)
		(fp_text user "Author: Antmicro"
			(at -0.95 4.169 90)
			(layer "F.Fab")
			(hide yes)
			(effects
				(font
					(size 0.7 0.7)
					(thickness 0.15)
				)
				(justify left bottom)
			)
		)
		(fp_text user "${REFERENCE}"
			(at -0.95 3.168 90)
			(layer "F.Fab")
			(hide yes)
			(effects
				(font
					(size 0.7 0.7)
					(thickness 0.15)
				)
				(justify left bottom)
			)
		)
		(pad "1" smd roundrect
			(at -0.48 0 90)
			(size 0.59 0.64)
			(layers "F.Cu" "F.Paste" "F.Mask")
			(roundrect_rratio 0.25)
			(net 147 "Net-(D9-A)")
			(pintype "passive")
		)
		(pad "2" smd roundrect
			(at 0.48 0 90)
			(size 0.59 0.64)
			(layers "F.Cu" "F.Paste" "F.Mask")
			(roundrect_rratio 0.25)
			(net 261 "/USB Debug, DP/USBC0_VBUS")
			(pintype "passive")
		)
	)
	(footprint "antmicro-footprints:WQFN-40_1EP_6x3mm_Pitch0.4mm_EP4.7x2.7mm"
		(layer "F.Cu")
		(at 74.75 106.867469 180)
		(property "Reference" "U10"
			(at -1.8 2.317469 0)
			(unlocked yes)
			(layer "F.SilkS")
			(effects
				(font
					(size 0.7 0.7)
					(thickness 0.15)
				)
				(justify left bottom)
			)
		)
		(property "Value" "TUSB1046-DCIRNQ"
			(at 0 3.4 180)
			(unlocked yes)
			(layer "F.Fab")
			(effects
				(font
					(size 0.7 0.7)
					(thickness 0.15)
				)
				(justify left bottom)
			)
		)
		(property "Footprint" "antmicro-footprints:WQFN-40_1EP_6x3mm_Pitch0.4mm_EP4.7x2.7mm"
			(at 0 0 180)
			(layer "F.Fab")
			(hide yes)
			(effects
				(font
					(size 1.27 1.27)
					(thickness 0.15)
				)
			)
		)
		(property "Datasheet" "https://www.ti.com/lit/ds/sllsew2d/sllsew2d.pdf?ts=1662107117482&ref_url=https%253A%252F%252Fwww.google.com%252F"
			(at 0 0 180)
			(layer "F.Fab")
			(hide yes)
			(effects
				(font
					(size 1.27 1.27)
					(thickness 0.15)
				)
			)
		)
		(property "Author" "Antmicro"
			(at 149.5 213.734938 0)
			(layer "F.Fab")
			(hide yes)
			(effects
				(font
					(size 1 1)
					(thickness 0.15)
				)
			)
		)
		(property "License" "Apache-2.0"
			(at 149.5 213.734938 0)
			(layer "F.Fab")
			(hide yes)
			(effects
				(font
					(size 1 1)
					(thickness 0.15)
				)
			)
		)
		(property "MPN" "TUSB1046-DCIRNQT"
			(at 149.5 213.734938 0)
			(layer "F.Fab")
			(hide yes)
			(effects
				(font
					(size 1 1)
					(thickness 0.15)
				)
			)
		)
		(property "Manufacturer" "Texas Instruments"
			(at 149.5 213.734938 0)
			(layer "F.Fab")
			(hide yes)
			(effects
				(font
					(size 1 1)
					(thickness 0.15)
				)
			)
		)
		(sheetname "USB Debug, DP")
		(sheetfile "usb.kicad_sch")
		(attr smd)
		(fp_line
			(start 3.1 2.1)
			(end 2.398 2.1)
			(stroke
				(width 0.15)
				(type solid)
			)
			(layer "F.SilkS")
		)
		(fp_line
			(start 3.1 1.6)
			(end 3.1 2.1)
			(stroke
				(width 0.15)
				(type solid)
			)
			(layer "F.SilkS")
		)
		(fp_line
			(start 3.1 -2.101)
			(end 3.1 -1.601)
			(stroke
				(width 0.15)
				(type solid)
			)
			(layer "F.SilkS")
		)
		(fp_line
			(start 3.1 -2.101)
			(end 2.398 -2.101)
			(stroke
				(width 0.15)
				(type solid)
			)
			(layer "F.SilkS")
		)
		(fp_line
			(start -2.4 2.1)
			(end -3.101 2.1)
			(stroke
				(width 0.15)
				(type solid)
			)
			(layer "F.SilkS")
		)
		(fp_line
			(start -2.4 -2.101)
			(end -3.101 -2.101)
			(stroke
				(width 0.15)
				(type solid)
			)
			(layer "F.SilkS")
		)
		(fp_line
			(start -3.101 2.1)
			(end -3.101 1.6)
			(stroke
				(width 0.15)
				(type solid)
			)
			(layer "F.SilkS")
		)
		(fp_circle
			(center -3.8 -1.41)
			(end -3.75 -1.36)
			(stroke
				(width 0.15)
				(type solid)
			)
			(fill solid)
			(layer "F.SilkS")
		)
		(fp_rect
			(start -3.5 -2.5)
			(end 3.499 2.499)
			(stroke
				(width 0.05)
				(type solid)
			)
			(fill none)
			(layer "F.CrtYd")
		)
		(fp_line
			(start 2.898 1.898)
			(end -2.9 1.898)
			(stroke
				(width 0.15)
				(type solid)
			)
			(layer "F.Fab")
		)
		(fp_line
			(start 2.898 -1.901)
			(end 2.898 1.898)
			(stroke
				(width 0.15)
				(type solid)
			)
			(layer "F.Fab")
		)
		(fp_line
			(start -2.2 -1.9)
			(end 2.898 -1.901)
			(stroke
				(width 0.15)
				(type solid)
			)
			(layer "F.Fab")
		)
		(fp_line
			(start -2.9 1.898)
			(end -2.9 -1.2)
			(stroke
				(width 0.15)
				(type solid)
			)
			(layer "F.Fab")
		)
		(fp_line
			(start -2.9 -1.2)
			(end -2.2 -1.9)
			(stroke
				(width 0.15)
				(type solid)
			)
			(layer "F.Fab")
		)
		(fp_text user "Author: Antmicro"
			(at -3.101 5.099 180)
			(layer "F.Fab")
			(hide yes)
			(effects
				(font
					(size 0.7 0.7)
					(thickness 0.15)
				)
				(justify left bottom)
			)
		)
		(fp_text user "${REFERENCE}"
			(at -3.101 4.099 180)
			(layer "F.Fab")
			(hide yes)
			(effects
				(font
					(size 0.7 0.7)
					(thickness 0.15)
				)
				(justify left bottom)
			)
		)
		(fp_text user "License: Apache-2.0"
			(at -3.101 6.099 180)
			(layer "F.Fab")
			(hide yes)
			(effects
				(font
					(size 0.7 0.7)
					(thickness 0.15)
				)
				(justify left bottom)
			)
		)
		(pad "1" smd roundrect
			(at -2.9 -1.401 270)
			(size 0.2 0.6)
			(layers "F.Cu" "F.Paste" "F.Mask")
			(roundrect_rratio 0.25)
			(net 87 "+3V3")
			(pinfunction "VCC")
			(pintype "power_in")
		)
		(pad "2" smd roundrect
			(at -2.9 -1 270)
			(size 0.2 0.6)
			(layers "F.Cu" "F.Paste" "F.Mask")
			(roundrect_rratio 0.25)
			(net 308 "/USB Debug, DP/USBC0_DPEQ1")
			(pinfunction "DPEQ1")
			(pintype "input")
		)
		(pad "3" smd roundrect
			(at -2.9 -0.6 270)
			(size 0.2 0.6)
			(layers "F.Cu" "F.Paste" "F.Mask")
			(roundrect_rratio 0.25)
			(net 306 "/USB Debug, DP/USBC0_SSEQ1")
			(pinfunction "SSEQ1")
			(pintype "input")
		)
		(pad "4" smd roundrect
			(at -2.9 -0.202 270)
			(size 0.2 0.6)
			(layers "F.Cu" "F.Paste" "F.Mask")
			(roundrect_rratio 0.25)
			(net 186 "/USB Debug, DP/USBSS0_RX_C_N")
			(pinfunction "SSRX_N")
			(pintype "output")
		)
		(pad "5" smd roundrect
			(at -2.9 0.2 270)
			(size 0.2 0.6)
			(layers "F.Cu" "F.Paste" "F.Mask")
			(roundrect_rratio 0.25)
			(net 193 "/USB Debug, DP/USBSS0_RX_C_P")
			(pinfunction "SSRX_P")
			(pintype "output")
		)
		(pad "6" smd roundrect
			(at -2.9 0.598 270)
			(size 0.2 0.6)
			(layers "F.Cu" "F.Paste" "F.Mask")
			(roundrect_rratio 0.25)
			(net 87 "+3V3")
			(pinfunction "VCC")
			(pintype "passive")
		)
		(pad "7" smd roundrect
			(at -2.9 0.998 270)
			(size 0.2 0.6)
			(layers "F.Cu" "F.Paste" "F.Mask")
			(roundrect_rratio 0.25)
			(net 187 "/USB Debug, DP/USBSS0_TX_C_N")
			(pinfunction "SSTX_N")
			(pintype "input")
		)
		(pad "8" smd roundrect
			(at -2.9 1.398 270)
			(size 0.2 0.6)
			(layers "F.Cu" "F.Paste" "F.Mask")
			(roundrect_rratio 0.25)
			(net 194 "/USB Debug, DP/USBSS0_TX_C_P")
			(pinfunction "SSTX_P")
			(pintype "input")
		)
		(pad "9" smd roundrect
			(at -2.202 1.898)
			(size 0.2 0.6)
			(layers "F.Cu" "F.Paste" "F.Mask")
			(roundrect_rratio 0.25)
			(net 496 "DP1_TXD0_P")
			(pinfunction "DP0_P")
			(pintype "input")
		)
		(pad "10" smd roundrect
			(at -1.801 1.898)
			(size 0.2 0.6)
			(layers "F.Cu" "F.Paste" "F.Mask")
			(roundrect_rratio 0.25)
			(net 26 "DP1_TXD0_N")
			(pinfunction "DP0_N")
			(pintype "input")
		)
		(pad "11" smd roundrect
			(at -1.401 1.898)
			(size 0.2 0.6)
			(layers "F.Cu" "F.Paste" "F.Mask")
			(roundrect_rratio 0.25)
			(net 305 "/USB Debug, DP/USBC0_SSEQ0")
			(pinfunction "SSEQ0/A0")
			(pintype "input")
		)
		(pad "12" smd roundrect
			(at -1 1.898)
			(size 0.2 0.6)
			(layers "F.Cu" "F.Paste" "F.Mask")
			(roundrect_rratio 0.25)
			(net 27 "DP1_TXD1_P")
			(pinfunction "DP1_P")
			(pintype "input")
		)
		(pad "13" smd roundrect
			(at -0.6 1.898)
			(size 0.2 0.6)
			(layers "F.Cu" "F.Paste" "F.Mask")
			(roundrect_rratio 0.25)
			(net 490 "DP1_TXD1_N")
			(pinfunction "DP1_N")
			(pintype "input")
		)
		(pad "14" smd roundrect
			(at -0.202 1.898)
			(size 0.2 0.6)
			(layers "F.Cu" "F.Paste" "F.Mask")
			(roundrect_rratio 0.25)
			(net 307 "/USB Debug, DP/USBC0_DPEQ0")
			(pinfunction "DPEQ0/A1")
			(pintype "input")
		)
		(pad "15" smd roundrect
			(at 0.2 1.898)
			(size 0.2 0.6)
			(layers "F.Cu" "F.Paste" "F.Mask")
			(roundrect_rratio 0.25)
			(net 497 "DP1_TXD2_P")
			(pinfunction "DP2_P")
			(pintype "input")
		)
		(pad "16" smd roundrect
			(at 0.598 1.898)
			(size 0.2 0.6)
			(layers "F.Cu" "F.Paste" "F.Mask")
			(roundrect_rratio 0.25)
			(net 491 "DP1_TXD2_N")
			(pinfunction "DP2_N")
			(pintype "input")
		)
		(pad "17" smd roundrect
			(at 0.998 1.898)
			(size 0.2 0.6)
			(layers "F.Cu" "F.Paste" "F.Mask")
			(roundrect_rratio 0.25)
			(net 304 "/USB Debug, DP/USBC0_I2C_EN")
			(pinfunction "I2C_EN")
			(pintype "input")
		)
		(pad "18" smd roundrect
			(at 1.398 1.898)
			(size 0.2 0.6)
			(layers "F.Cu" "F.Paste" "F.Mask")
			(roundrect_rratio 0.25)
			(net 29 "DP1_TXD3_P")
			(pinfunction "DP3_P")
			(pintype "input")
		)
		(pad "19" smd roundrect
			(at 1.8 1.898)
			(size 0.2 0.6)
			(layers "F.Cu" "F.Paste" "F.Mask")
			(roundrect_rratio 0.25)
			(net 28 "DP1_TXD3_N")
			(pinfunction "DP3_N")
			(pintype "input")
		)
		(pad "20" smd roundrect
			(at 2.2 1.898)
			(size 0.2 0.6)
			(layers "F.Cu" "F.Paste" "F.Mask")
			(roundrect_rratio 0.25)
			(net 87 "+3V3")
			(pinfunction "VCC")
			(pintype "passive")
		)
		(pad "21" smd roundrect
			(at 2.898 1.398 90)
			(size 0.2 0.6)
			(layers "F.Cu" "F.Paste" "F.Mask")
			(roundrect_rratio 0.25)
			(net 293 "/USB Debug, DP/USBC0_FLIP")
			(pinfunction "FLIP/SCL")
			(pintype "input")
		)
		(pad "22" smd roundrect
			(at 2.898 0.998 90)
			(size 0.2 0.6)
			(layers "F.Cu" "F.Paste" "F.Mask")
			(roundrect_rratio 0.25)
			(net 295 "/USB Debug, DP/USBC0_CTL0")
			(pinfunction "CTL0/SDA")
			(pintype "input")
		)
		(pad "23" smd roundrect
			(at 2.898 0.598 90)
			(size 0.2 0.6)
			(layers "F.Cu" "F.Paste" "F.Mask")
			(roundrect_rratio 0.25)
			(net 297 "/USB Debug, DP/USBC0_CTL1")
			(pinfunction "CTL1/HPDIN")
			(pintype "input")
		)
		(pad "24" smd roundrect
			(at 2.898 0.2 90)
			(size 0.2 0.6)
			(layers "F.Cu" "F.Paste" "F.Mask")
			(roundrect_rratio 0.25)
			(net 36 "DP1_AUX_P")
			(pinfunction "AUX_P")
			(pintype "bidirectional")
		)
		(pad "25" smd roundrect
			(at 2.898 -0.202 90)
			(size 0.2 0.6)
			(layers "F.Cu" "F.Paste" "F.Mask")
			(roundrect_rratio 0.25)
			(net 35 "DP1_AUX_N")
			(pinfunction "AUX_N")
			(pintype "bidirectional")
		)
		(pad "26" smd roundrect
			(at 2.898 -0.6 90)
			(size 0.2 0.6)
			(layers "F.Cu" "F.Paste" "F.Mask")
			(roundrect_rratio 0.25)
			(net 614 "/USB Debug, DP/USBC0_SBU_P")
			(pinfunction "SBU2")
			(pintype "bidirectional")
		)
		(pad "27" smd roundrect
			(at 2.898 -1 90)
			(size 0.2 0.6)
			(layers "F.Cu" "F.Paste" "F.Mask")
			(roundrect_rratio 0.25)
			(net 615 "/USB Debug, DP/USBC0_SBU_N")
			(pinfunction "SBU1")
			(pintype "bidirectional")
		)
		(pad "28" smd roundrect
			(at 2.898 -1.401 90)
			(size 0.2 0.6)
			(layers "F.Cu" "F.Paste" "F.Mask")
			(roundrect_rratio 0.25)
			(net 87 "+3V3")
			(pinfunction "VCC")
			(pintype "passive")
		)
		(pad "29" smd roundrect
			(at 2.2 -1.901 180)
			(size 0.2 0.6)
			(layers "F.Cu" "F.Paste" "F.Mask")
			(roundrect_rratio 0.25)
			(net 692 "Net-(U10-CAD_SNK{slash}RSVD1)")
			(pinfunction "CAD_SNK/RSVD1")
			(pintype "bidirectional")
		)
		(pad "30" smd roundrect
			(at 1.8 -1.901 180)
			(size 0.2 0.6)
			(layers "F.Cu" "F.Paste" "F.Mask")
			(roundrect_rratio 0.25)
			(net 154 "/USB Debug, DP/USBC0_RX1_P")
			(pinfunction "RX1_P")
			(pintype "input")
		)
		(pad "31" smd roundrect
			(at 1.398 -1.901 180)
			(size 0.2 0.6)
			(layers "F.Cu" "F.Paste" "F.Mask")
			(roundrect_rratio 0.25)
			(net 152 "/USB Debug, DP/USBC0_RX1_N")
			(pinfunction "RX1_N")
			(pintype "input")
		)
		(pad "32" smd roundrect
			(at 0.998 -1.901 180)
			(size 0.2 0.6)
			(layers "F.Cu" "F.Paste" "F.Mask")
			(roundrect_rratio 0.25)
			(net 502 "/USB Debug, DP/HPDIN")
			(pinfunction "HPDIN/RSVD2")
			(pintype "bidirectional")
		)
		(pad "33" smd roundrect
			(at 0.598 -1.901 180)
			(size 0.2 0.6)
			(layers "F.Cu" "F.Paste" "F.Mask")
			(roundrect_rratio 0.25)
			(net 257 "/USB Debug, DP/USBC0_TX1_P")
			(pinfunction "TX1_P")
			(pintype "output")
		)
		(pad "34" smd roundrect
			(at 0.2 -1.901 180)
			(size 0.2 0.6)
			(layers "F.Cu" "F.Paste" "F.Mask")
			(roundrect_rratio 0.25)
			(net 197 "/USB Debug, DP/USBC0_TX1_N")
			(pinfunction "TX1_N")
			(pintype "output")
		)
		(pad "35" smd roundrect
			(at -0.202 -1.901 180)
			(size 0.2 0.6)
			(layers "F.Cu" "F.Paste" "F.Mask")
			(roundrect_rratio 0.25)
			(net 310 "/USB Debug, DP/USBC0_EQ1")
			(pinfunction "EQ1")
			(pintype "input")
		)
		(pad "36" smd roundrect
			(at -0.6 -1.901 180)
			(size 0.2 0.6)
			(layers "F.Cu" "F.Paste" "F.Mask")
			(roundrect_rratio 0.25)
			(net 200 "/USB Debug, DP/USBC0_TX2_N")
			(pinfunction "TX2_N")
			(pintype "output")
		)
		(pad "37" smd roundrect
			(at -1 -1.901 180)
			(size 0.2 0.6)
			(layers "F.Cu" "F.Paste" "F.Mask")
			(roundrect_rratio 0.25)
			(net 259 "/USB Debug, DP/USBC0_TX2_P")
			(pinfunction "TX2_P")
			(pintype "output")
		)
		(pad "38" smd roundrect
			(at -1.401 -1.901 180)
			(size 0.2 0.6)
			(layers "F.Cu" "F.Paste" "F.Mask")
			(roundrect_rratio 0.25)
			(net 309 "/USB Debug, DP/USBC0_EQ0")
			(pinfunction "EQ0")
			(pintype "input")
		)
		(pad "39" smd roundrect
			(at -1.801 -1.901 180)
			(size 0.2 0.6)
			(layers "F.Cu" "F.Paste" "F.Mask")
			(roundrect_rratio 0.25)
			(net 125 "/USB Debug, DP/USBC0_RX2_N")
			(pinfunction "RX2_N")
			(pintype "input")
		)
		(pad "40" smd roundrect
			(at -2.202 -1.901 180)
			(size 0.2 0.6)
			(layers "F.Cu" "F.Paste" "F.Mask")
			(roundrect_rratio 0.25)
			(net 151 "/USB Debug, DP/USBC0_RX2_P")
			(pinfunction "RX2_P")
			(pintype "input")
		)
		(pad "41" smd roundrect
			(at -1.5 -0.652)
			(size 1 0.8)
			(layers "F.Cu" "F.Paste" "F.Mask")
			(roundrect_rratio 0.05)
			(net 1 "GND")
			(pinfunction "GND")
			(pintype "power_in")
		)
		(pad "41" smd roundrect
			(at -1.5 0.748)
			(size 1 0.8)
			(layers "F.Cu" "F.Paste" "F.Mask")
			(roundrect_rratio 0.05)
			(net 1 "GND")
			(pinfunction "GND")
			(pintype "power_in")
		)
		(pad "41" smd roundrect
			(at 0 0)
			(size 4.7 2.7)
			(layers "F.Cu" "F.Mask")
			(roundrect_rratio 0.01851851852)
			(net 1 "GND")
			(pinfunction "GND")
			(pintype "power_in")
		)
		(pad "41" smd roundrect
			(at 0.05 -0.652)
			(size 1 0.8)
			(layers "F.Cu" "F.Paste" "F.Mask")
			(roundrect_rratio 0.05)
			(net 1 "GND")
			(pinfunction "GND")
			(pintype "power_in")
		)
		(pad "41" smd roundrect
			(at 0.05 0.748)
			(size 1 0.8)
			(layers "F.Cu" "F.Paste" "F.Mask")
			(roundrect_rratio 0.05)
			(net 1 "GND")
			(pinfunction "GND")
			(pintype "power_in")
		)
		(pad "41" smd roundrect
			(at 1.499 -0.652)
			(size 1 0.8)
			(layers "F.Cu" "F.Paste" "F.Mask")
			(roundrect_rratio 0.05)
			(net 1 "GND")
			(pinfunction "GND")
			(pintype "power_in")
		)
		(pad "41" smd roundrect
			(at 1.499 0.748)
			(size 1 0.8)
			(layers "F.Cu" "F.Paste" "F.Mask")
			(roundrect_rratio 0.05)
			(net 1 "GND")
			(pinfunction "GND")
			(pintype "power_in")
		)
	)
	(footprint "antmicro-footprints:R_0402_1005Metric"
		(layer "F.Cu")
		(at 40.415 104.991 -90)
		(descr "Resistor SMD 0402")
		(tags "resistor SMD 0402")
		(property "Reference" "R241"
			(at 1.409 0.415 -90)
			(layer "F.SilkS")
			(effects
				(font
					(size 0.7 0.7)
					(thickness 0.15)
				)
				(justify left bottom)
			)
		)
		(property "Value" "R_0R_0402"
			(at 0 1.4 -90)
			(layer "F.Fab")
			(effects
				(font
					(size 0.7 0.7)
					(thickness 0.15)
				)
				(justify left bottom)
			)
		)
		(property "Footprint" "antmicro-footprints:R_0402_1005Metric"
			(at 0 0 -90)
			(layer "F.Fab")
			(hide yes)
			(effects
				(font
					(size 1.27 1.27)
					(thickness 0.15)
				)
			)
		)
		(property "Datasheet" "https://industrial.panasonic.com/cdbs/www-data/pdf/RDA0000/AOA0000C301.pdf"
			(at 0 0 -90)
			(layer "F.Fab")
			(hide yes)
			(effects
				(font
					(size 1.27 1.27)
					(thickness 0.15)
				)
			)
		)
		(property "Author" "Antmicro"
			(at -64.576 145.406 0)
			(layer "F.Fab")
			(hide yes)
			(effects
				(font
					(size 1 1)
					(thickness 0.15)
				)
			)
		)
		(property "Current" "1A"
			(at -64.576 145.406 0)
			(layer "F.Fab")
			(hide yes)
			(effects
				(font
					(size 1 1)
					(thickness 0.15)
				)
			)
		)
		(property "License" "Apache-2.0"
			(at -64.576 145.406 0)
			(layer "F.Fab")
			(hide yes)
			(effects
				(font
					(size 1 1)
					(thickness 0.15)
				)
			)
		)
		(property "MPN" "ERJ2GE0R00X"
			(at -64.576 145.406 0)
			(layer "F.Fab")
			(hide yes)
			(effects
				(font
					(size 1 1)
					(thickness 0.15)
				)
			)
		)
		(property "Manufacturer" "Panasonic"
			(at -64.576 145.406 0)
			(layer "F.Fab")
			(hide yes)
			(effects
				(font
					(size 1 1)
					(thickness 0.15)
				)
			)
		)
		(property "Tolerance" ""
			(at -64.576 145.406 0)
			(layer "F.Fab")
			(hide yes)
			(effects
				(font
					(size 1 1)
					(thickness 0.15)
				)
			)
		)
		(property "Val" "0R"
			(at -64.576 145.406 0)
			(layer "F.Fab")
			(hide yes)
			(effects
				(font
					(size 1 1)
					(thickness 0.15)
				)
			)
		)
		(sheetname "Ethernet")
		(sheetfile "ethernet.kicad_sch")
		(attr smd exclude_from_pos_files exclude_from_bom dnp)
		(fp_rect
			(start -0.925 -0.47)
			(end 0.925 0.47)
			(stroke
				(width 0.05)
				(type default)
			)
			(fill none)
			(layer "F.CrtYd")
		)
		(fp_rect
			(start -0.5 -0.25)
			(end 0.5 0.25)
			(stroke
				(width 0.15)
				(type solid)
			)
			(fill none)
			(layer "F.Fab")
		)
		(fp_text user "${REFERENCE}"
			(at -0.95 3.168 -90)
			(layer "F.Fab")
			(hide yes)
			(effects
				(font
					(size 0.7 0.7)
					(thickness 0.15)
				)
				(justify left bottom)
			)
		)
		(fp_text user "Author: Antmicro"
			(at -0.95 4.169 -90)
			(layer "F.Fab")
			(hide yes)
			(effects
				(font
					(size 0.7 0.7)
					(thickness 0.15)
				)
				(justify left bottom)
			)
		)
		(fp_text user "License: Apache-2.0"
			(at -0.95 5.169 -90)
			(layer "F.Fab")
			(hide yes)
			(effects
				(font
					(size 0.7 0.7)
					(thickness 0.15)
				)
				(justify left bottom)
			)
		)
		(pad "1" smd roundrect
			(at -0.48 0 270)
			(size 0.59 0.64)
			(layers "F.Cu" "F.Paste" "F.Mask")
			(roundrect_rratio 0.25)
			(net 650 "/Ethernet/ULS-12_CTRL")
			(pintype "passive")
		)
		(pad "2" smd roundrect
			(at 0.48 0 270)
			(size 0.59 0.64)
			(layers "F.Cu" "F.Paste" "F.Mask")
			(roundrect_rratio 0.25)
			(net 127 "/Ethernet/POE_ACTIVE")
			(pintype "passive")
		)
	)
	(footprint "antmicro-footprints:USON-10_2.5x1mm_P0.5mm"
		(layer "F.Cu")
		(at 110.55 116.178749 90)
		(descr "USON-10 2.5x1mm_ Pitch 0.5mm")
		(tags "USON-10 2.5x1mm Pitch 0.5mm")
		(property "Reference" "U20"
			(at 0.878749 -1.1 180)
			(layer "F.SilkS")
			(effects
				(font
					(size 0.7 0.7)
					(thickness 0.15)
				)
				(justify left bottom)
			)
		)
		(property "Value" "TPD4E05U06QDQARQ1"
			(at 0.018 2.499 90)
			(layer "F.Fab")
			(effects
				(font
					(size 0.7 0.7)
					(thickness 0.15)
				)
				(justify left bottom)
			)
		)
		(property "Footprint" "antmicro-footprints:USON-10_2.5x1mm_P0.5mm"
			(at 0 0 90)
			(layer "F.Fab")
			(hide yes)
			(effects
				(font
					(size 1.27 1.27)
					(thickness 0.15)
				)
			)
		)
		(property "Datasheet" "https://www.ti.com/lit/ds/symlink/tpd4e05u06-q1.pdf?HQS=dis-mous-null-mousermode-dsf-pf-null-wwe&ts=1663591265741&ref_url=https%253A%252F%252Fwww.mouser.com%252F"
			(at 0 0 90)
			(layer "F.Fab")
			(hide yes)
			(effects
				(font
					(size 1.27 1.27)
					(thickness 0.15)
				)
			)
		)
		(property "Author" "Antmicro"
			(at 226.728749 5.628749 0)
			(layer "F.Fab")
			(hide yes)
			(effects
				(font
					(size 1 1)
					(thickness 0.15)
				)
			)
		)
		(property "License" "Apache-2.0"
			(at 226.728749 5.628749 0)
			(layer "F.Fab")
			(hide yes)
			(effects
				(font
					(size 1 1)
					(thickness 0.15)
				)
			)
		)
		(property "MPN" "TPD4E05U06QDQARQ1"
			(at 226.728749 5.628749 0)
			(layer "F.Fab")
			(hide yes)
			(effects
				(font
					(size 1 1)
					(thickness 0.15)
				)
			)
		)
		(property "Manufacturer" "Texas Instruments"
			(at 226.728749 5.628749 0)
			(layer "F.Fab")
			(hide yes)
			(effects
				(font
					(size 1 1)
					(thickness 0.15)
				)
			)
		)
		(sheetname "USB3")
		(sheetfile "usb3.kicad_sch")
		(attr smd)
		(fp_line
			(start 0.498 -1.401)
			(end -0.5 -1.401)
			(stroke
				(width 0.15)
				(type solid)
			)
			(layer "F.SilkS")
		)
		(fp_line
			(start 0.498 1.398)
			(end -0.5 1.398)
			(stroke
				(width 0.15)
				(type solid)
			)
			(layer "F.SilkS")
		)
		(fp_circle
			(center -0.68 -1.27)
			(end -0.63 -1.27)
			(stroke
				(width 0.15)
				(type solid)
			)
			(fill solid)
			(layer "F.SilkS")
		)
		(fp_rect
			(start -0.8 -1.5)
			(end 0.8 1.499)
			(stroke
				(width 0.05)
				(type solid)
			)
			(fill none)
			(layer "F.CrtYd")
		)
		(fp_line
			(start 0.498 -1.25)
			(end -0.25 -1.25)
			(stroke
				(width 0.15)
				(type solid)
			)
			(layer "F.Fab")
		)
		(fp_line
			(start 0.498 -1.25)
			(end 0.498 1.249)
			(stroke
				(width 0.15)
				(type solid)
			)
			(layer "F.Fab")
		)
		(fp_line
			(start -0.25 -1.25)
			(end -0.5 -1)
			(stroke
				(width 0.15)
				(type solid)
			)
			(layer "F.Fab")
		)
		(fp_line
			(start -0.5 -1)
			(end -0.5 1.249)
			(stroke
				(width 0.15)
				(type solid)
			)
			(layer "F.Fab")
		)
		(fp_line
			(start -0.5 1.249)
			(end 0.498 1.249)
			(stroke
				(width 0.15)
				(type solid)
			)
			(layer "F.Fab")
		)
		(fp_text user "${REFERENCE}"
			(at -0.802 4.498 90)
			(layer "F.Fab")
			(hide yes)
			(effects
				(font
					(size 0.7 0.7)
					(thickness 0.15)
				)
				(justify left bottom)
			)
		)
		(fp_text user "License: Apache-2.0"
			(at -0.802 6.9 90)
			(layer "F.Fab")
			(hide yes)
			(effects
				(font
					(size 0.7 0.7)
					(thickness 0.15)
				)
				(justify left bottom)
			)
		)
		(fp_text user "Author: Antmicro"
			(at -0.802 5.7 90)
			(layer "F.Fab")
			(hide yes)
			(effects
				(font
					(size 0.7 0.7)
					(thickness 0.15)
				)
				(justify left bottom)
			)
		)
		(pad "1" smd roundrect
			(at -0.387 -1)
			(size 0.25 0.55)
			(layers "F.Cu" "F.Paste" "F.Mask")
			(roundrect_rratio 0.25)
			(net 366 "/USB3/USBC1_RX1_N")
			(pintype "passive")
		)
		(pad "2" smd roundrect
			(at -0.387 -0.5)
			(size 0.25 0.55)
			(layers "F.Cu" "F.Paste" "F.Mask")
			(roundrect_rratio 0.25)
			(net 368 "/USB3/USBC1_RX1_P")
			(pintype "passive")
		)
		(pad "3" smd roundrect
			(at -0.387 0)
			(size 0.4 0.55)
			(layers "F.Cu" "F.Paste" "F.Mask")
			(roundrect_rratio 0.25)
			(net 1 "GND")
			(pintype "power_in")
		)
		(pad "4" smd roundrect
			(at -0.387 0.498)
			(size 0.25 0.55)
			(layers "F.Cu" "F.Paste" "F.Mask")
			(roundrect_rratio 0.25)
			(net 265 "/USB3/USBC1_CONN_TX1_N")
			(pintype "passive")
		)
		(pad "5" smd roundrect
			(at -0.387 0.998)
			(size 0.25 0.55)
			(layers "F.Cu" "F.Paste" "F.Mask")
			(roundrect_rratio 0.25)
			(net 267 "/USB3/USBC1_CONN_TX1_P")
			(pintype "passive")
		)
		(pad "6" smd roundrect
			(at 0.385 0.998)
			(size 0.25 0.55)
			(layers "F.Cu" "F.Paste" "F.Mask")
			(roundrect_rratio 0.25)
			(net 267 "/USB3/USBC1_CONN_TX1_P")
			(pintype "passive")
		)
		(pad "7" smd roundrect
			(at 0.385 0.498)
			(size 0.25 0.55)
			(layers "F.Cu" "F.Paste" "F.Mask")
			(roundrect_rratio 0.25)
			(net 265 "/USB3/USBC1_CONN_TX1_N")
			(pintype "passive")
		)
		(pad "8" smd roundrect
			(at 0.385 0)
			(size 0.4 0.55)
			(layers "F.Cu" "F.Paste" "F.Mask")
			(roundrect_rratio 0.25)
			(net 1 "GND")
			(pintype "passive")
		)
		(pad "9" smd roundrect
			(at 0.385 -0.5)
			(size 0.25 0.55)
			(layers "F.Cu" "F.Paste" "F.Mask")
			(roundrect_rratio 0.25)
			(net 368 "/USB3/USBC1_RX1_P")
			(pintype "passive")
		)
		(pad "10" smd roundrect
			(at 0.385 -1)
			(size 0.25 0.55)
			(layers "F.Cu" "F.Paste" "F.Mask")
			(roundrect_rratio 0.25)
			(net 366 "/USB3/USBC1_RX1_N")
			(pintype "passive")
		)
	)
	(footprint "antmicro-footprints:C_0402_1005Metric"
		(layer "F.Cu")
		(at 55.54 104.87 -90)
		(descr "Capacitor SMD 0402")
		(tags "capacitor SMD 0402")
		(property "Reference" "C48"
			(at 1.08 0.39 -90)
			(layer "F.SilkS")
			(effects
				(font
					(size 0.7 0.7)
					(thickness 0.15)
				)
				(justify left bottom)
			)
		)
		(property "Value" "C_100n_0402"
			(at 0 1.4 -90)
			(layer "F.Fab")
			(effects
				(font
					(size 0.7 0.7)
					(thickness 0.15)
				)
				(justify left bottom)
			)
		)
		(property "Footprint" "antmicro-footprints:C_0402_1005Metric"
			(at 0 0 -90)
			(layer "F.Fab")
			(hide yes)
			(effects
				(font
					(size 1.27 1.27)
					(thickness 0.15)
				)
			)
		)
		(property "Datasheet" "https://www.murata.com/products/productdetail?partno=GRM155R61H104KE14%23"
			(at 0 0 -90)
			(layer "F.Fab")
			(hide yes)
			(effects
				(font
					(size 1.27 1.27)
					(thickness 0.15)
				)
			)
		)
		(property "Author" "Antmicro"
			(at -49.33 160.41 0)
			(layer "F.Fab")
			(hide yes)
			(effects
				(font
					(size 1 1)
					(thickness 0.15)
				)
			)
		)
		(property "Dielectric" "X5R"
			(at -49.33 160.41 0)
			(layer "F.Fab")
			(hide yes)
			(effects
				(font
					(size 1 1)
					(thickness 0.15)
				)
			)
		)
		(property "License" "Apache-2.0"
			(at -49.33 160.41 0)
			(layer "F.Fab")
			(hide yes)
			(effects
				(font
					(size 1 1)
					(thickness 0.15)
				)
			)
		)
		(property "MPN" "GRM155R61H104KE14D"
			(at -49.33 160.41 0)
			(layer "F.Fab")
			(hide yes)
			(effects
				(font
					(size 1 1)
					(thickness 0.15)
				)
			)
		)
		(property "Manufacturer" "Murata"
			(at -49.33 160.41 0)
			(layer "F.Fab")
			(hide yes)
			(effects
				(font
					(size 1 1)
					(thickness 0.15)
				)
			)
		)
		(property "Val" "100n"
			(at -49.33 160.41 0)
			(layer "F.Fab")
			(hide yes)
			(effects
				(font
					(size 1 1)
					(thickness 0.15)
				)
			)
		)
		(property "Voltage" "50V"
			(at -49.33 160.41 0)
			(layer "F.Fab")
			(hide yes)
			(effects
				(font
					(size 1 1)
					(thickness 0.15)
				)
			)
		)
		(sheetname "Peripherals")
		(sheetfile "peripherals.kicad_sch")
		(attr smd)
		(fp_rect
			(start -0.925 -0.47)
			(end 0.925 0.47)
			(stroke
				(width 0.05)
				(type default)
			)
			(fill none)
			(layer "F.CrtYd")
		)
		(fp_line
			(start -0.494 0.248)
			(end -0.494 -0.25)
			(stroke
				(width 0.15)
				(type solid)
			)
			(layer "F.Fab")
		)
		(fp_line
			(start 0.504 0.248)
			(end -0.494 0.248)
			(stroke
				(width 0.15)
				(type solid)
			)
			(layer "F.Fab")
		)
		(fp_line
			(start -0.494 -0.25)
			(end 0.504 -0.25)
			(stroke
				(width 0.15)
				(type solid)
			)
			(layer "F.Fab")
		)
		(fp_line
			(start 0.504 -0.25)
			(end 0.504 0.248)
			(stroke
				(width 0.15)
				(type solid)
			)
			(layer "F.Fab")
		)
		(fp_text user "Author: Antmicro"
			(at -0.932 4.17 -90)
			(layer "F.Fab")
			(hide yes)
			(effects
				(font
					(size 0.7 0.7)
					(thickness 0.15)
				)
				(justify left bottom)
			)
		)
		(fp_text user "${REFERENCE}"
			(at -0.932 3.168 -90)
			(layer "F.Fab")
			(hide yes)
			(effects
				(font
					(size 0.7 0.7)
					(thickness 0.15)
				)
				(justify left bottom)
			)
		)
		(fp_text user "License: Apache-2.0"
			(at -0.932 5.17 -90)
			(layer "F.Fab")
			(hide yes)
			(effects
				(font
					(size 0.7 0.7)
					(thickness 0.15)
				)
				(justify left bottom)
			)
		)
		(pad "1" smd roundrect
			(at -0.48 0 270)
			(size 0.59 0.64)
			(layers "F.Cu" "F.Paste" "F.Mask")
			(roundrect_rratio 0.25)
			(net 1 "GND")
			(pintype "passive")
		)
		(pad "2" smd roundrect
			(at 0.48 0 270)
			(size 0.59 0.64)
			(layers "F.Cu" "F.Paste" "F.Mask")
			(roundrect_rratio 0.25)
			(net 99 "+5V")
			(pintype "passive")
		)
	)
	(footprint "antmicro-footprints:R_0402_1005Metric"
		(layer "F.Cu")
		(at 96.15 100.4 180)
		(descr "Resistor SMD 0402")
		(tags "resistor SMD 0402")
		(property "Reference" "R161"
			(at -0.8 -0.45 180)
			(layer "F.SilkS")
			(effects
				(font
					(size 0.7 0.7)
					(thickness 0.15)
				)
				(justify left bottom)
			)
		)
		(property "Value" "R_0R_0402"
			(at 0 1.4 180)
			(layer "F.Fab")
			(effects
				(font
					(size 0.7 0.7)
					(thickness 0.15)
				)
				(justify left bottom)
			)
		)
		(property "Footprint" "antmicro-footprints:R_0402_1005Metric"
			(at 0 0 180)
			(layer "F.Fab")
			(hide yes)
			(effects
				(font
					(size 1.27 1.27)
					(thickness 0.15)
				)
			)
		)
		(property "Datasheet" "https://industrial.panasonic.com/cdbs/www-data/pdf/RDA0000/AOA0000C301.pdf"
			(at 0 0 180)
			(layer "F.Fab")
			(hide yes)
			(effects
				(font
					(size 1.27 1.27)
					(thickness 0.15)
				)
			)
		)
		(property "Author" "Antmicro"
			(at 192.3 200.8 0)
			(layer "F.Fab")
			(hide yes)
			(effects
				(font
					(size 1 1)
					(thickness 0.15)
				)
			)
		)
		(property "Current" "1A"
			(at 192.3 200.8 0)
			(layer "F.Fab")
			(hide yes)
			(effects
				(font
					(size 1 1)
					(thickness 0.15)
				)
			)
		)
		(property "License" "Apache-2.0"
			(at 192.3 200.8 0)
			(layer "F.Fab")
			(hide yes)
			(effects
				(font
					(size 1 1)
					(thickness 0.15)
				)
			)
		)
		(property "MPN" "ERJ2GE0R00X"
			(at 192.3 200.8 0)
			(layer "F.Fab")
			(hide yes)
			(effects
				(font
					(size 1 1)
					(thickness 0.15)
				)
			)
		)
		(property "Manufacturer" "Panasonic"
			(at 192.3 200.8 0)
			(layer "F.Fab")
			(hide yes)
			(effects
				(font
					(size 1 1)
					(thickness 0.15)
				)
			)
		)
		(property "Tolerance" ""
			(at 192.3 200.8 0)
			(layer "F.Fab")
			(hide yes)
			(effects
				(font
					(size 1 1)
					(thickness 0.15)
				)
			)
		)
		(property "Val" "0R"
			(at 192.3 200.8 0)
			(layer "F.Fab")
			(hide yes)
			(effects
				(font
					(size 1 1)
					(thickness 0.15)
				)
			)
		)
		(sheetname "CSI")
		(sheetfile "csi.kicad_sch")
		(attr smd)
		(fp_rect
			(start -0.925 -0.47)
			(end 0.925 0.47)
			(stroke
				(width 0.05)
				(type default)
			)
			(fill none)
			(layer "F.CrtYd")
		)
		(fp_rect
			(start -0.5 -0.25)
			(end 0.5 0.25)
			(stroke
				(width 0.15)
				(type solid)
			)
			(fill none)
			(layer "F.Fab")
		)
		(fp_text user "License: Apache-2.0"
			(at -0.95 5.169 180)
			(layer "F.Fab")
			(hide yes)
			(effects
				(font
					(size 0.7 0.7)
					(thickness 0.15)
				)
				(justify left bottom)
			)
		)
		(fp_text user "${REFERENCE}"
			(at -0.95 3.168 180)
			(layer "F.Fab")
			(hide yes)
			(effects
				(font
					(size 0.7 0.7)
					(thickness 0.15)
				)
				(justify left bottom)
			)
		)
		(fp_text user "Author: Antmicro"
			(at -0.95 4.169 180)
			(layer "F.Fab")
			(hide yes)
			(effects
				(font
					(size 0.7 0.7)
					(thickness 0.15)
				)
				(justify left bottom)
			)
		)
		(pad "1" smd roundrect
			(at -0.48 0 180)
			(size 0.59 0.64)
			(layers "F.Cu" "F.Paste" "F.Mask")
			(roundrect_rratio 0.25)
			(net 511 "/CSI/I2C_MUX_SDA")
			(pintype "passive")
		)
		(pad "2" smd roundrect
			(at 0.48 0 180)
			(size 0.59 0.64)
			(layers "F.Cu" "F.Paste" "F.Mask")
			(roundrect_rratio 0.25)
			(net 79 "SDA_CAM")
			(pintype "passive")
		)
	)
	(footprint "antmicro-footprints:C_0402_1005Metric"
		(layer "F.Cu")
		(at 110.8 111.75 90)
		(descr "Capacitor SMD 0402")
		(tags "capacitor SMD 0402")
		(property "Reference" "C70"
			(at 0.8 0.5 90)
			(layer "F.SilkS")
			(effects
				(font
					(size 0.7 0.7)
					(thickness 0.15)
				)
				(justify left bottom)
			)
		)
		(property "Value" "C_100n_0402"
			(at 0 1.4 90)
			(layer "F.Fab")
			(effects
				(font
					(size 0.7 0.7)
					(thickness 0.15)
				)
				(justify left bottom)
			)
		)
		(property "Footprint" "antmicro-footprints:C_0402_1005Metric"
			(at 0 0 90)
			(layer "F.Fab")
			(hide yes)
			(effects
				(font
					(size 1.27 1.27)
					(thickness 0.15)
				)
			)
		)
		(property "Datasheet" "https://www.murata.com/products/productdetail?partno=GRM155R61H104KE14%23"
			(at 0 0 90)
			(layer "F.Fab")
			(hide yes)
			(effects
				(font
					(size 1.27 1.27)
					(thickness 0.15)
				)
			)
		)
		(property "Author" "Antmicro"
			(at 222.55 0.95 0)
			(layer "F.Fab")
			(hide yes)
			(effects
				(font
					(size 1 1)
					(thickness 0.15)
				)
			)
		)
		(property "Dielectric" "X5R"
			(at 222.55 0.95 0)
			(layer "F.Fab")
			(hide yes)
			(effects
				(font
					(size 1 1)
					(thickness 0.15)
				)
			)
		)
		(property "License" "Apache-2.0"
			(at 222.55 0.95 0)
			(layer "F.Fab")
			(hide yes)
			(effects
				(font
					(size 1 1)
					(thickness 0.15)
				)
			)
		)
		(property "MPN" "GRM155R61H104KE14D"
			(at 222.55 0.95 0)
			(layer "F.Fab")
			(hide yes)
			(effects
				(font
					(size 1 1)
					(thickness 0.15)
				)
			)
		)
		(property "Manufacturer" "Murata"
			(at 222.55 0.95 0)
			(layer "F.Fab")
			(hide yes)
			(effects
				(font
					(size 1 1)
					(thickness 0.15)
				)
			)
		)
		(property "Val" "100n"
			(at 222.55 0.95 0)
			(layer "F.Fab")
			(hide yes)
			(effects
				(font
					(size 1 1)
					(thickness 0.15)
				)
			)
		)
		(property "Voltage" "50V"
			(at 222.55 0.95 0)
			(layer "F.Fab")
			(hide yes)
			(effects
				(font
					(size 1 1)
					(thickness 0.15)
				)
			)
		)
		(sheetname "USB3")
		(sheetfile "usb3.kicad_sch")
		(attr smd)
		(fp_rect
			(start -0.925 -0.47)
			(end 0.925 0.47)
			(stroke
				(width 0.05)
				(type default)
			)
			(fill none)
			(layer "F.CrtYd")
		)
		(fp_line
			(start 0.504 -0.25)
			(end 0.504 0.248)
			(stroke
				(width 0.15)
				(type solid)
			)
			(layer "F.Fab")
		)
		(fp_line
			(start -0.494 -0.25)
			(end 0.504 -0.25)
			(stroke
				(width 0.15)
				(type solid)
			)
			(layer "F.Fab")
		)
		(fp_line
			(start 0.504 0.248)
			(end -0.494 0.248)
			(stroke
				(width 0.15)
				(type solid)
			)
			(layer "F.Fab")
		)
		(fp_line
			(start -0.494 0.248)
			(end -0.494 -0.25)
			(stroke
				(width 0.15)
				(type solid)
			)
			(layer "F.Fab")
		)
		(fp_text user "Author: Antmicro"
			(at -0.932 4.17 90)
			(layer "F.Fab")
			(hide yes)
			(effects
				(font
					(size 0.7 0.7)
					(thickness 0.15)
				)
				(justify left bottom)
			)
		)
		(fp_text user "${REFERENCE}"
			(at -0.932 3.168 90)
			(layer "F.Fab")
			(hide yes)
			(effects
				(font
					(size 0.7 0.7)
					(thickness 0.15)
				)
				(justify left bottom)
			)
		)
		(fp_text user "License: Apache-2.0"
			(at -0.932 5.17 90)
			(layer "F.Fab")
			(hide yes)
			(effects
				(font
					(size 0.7 0.7)
					(thickness 0.15)
				)
				(justify left bottom)
			)
		)
		(pad "1" smd roundrect
			(at -0.48 0 90)
			(size 0.59 0.64)
			(layers "F.Cu" "F.Paste" "F.Mask")
			(roundrect_rratio 0.25)
			(net 265 "/USB3/USBC1_CONN_TX1_N")
			(pintype "passive")
		)
		(pad "2" smd roundrect
			(at 0.48 0 90)
			(size 0.59 0.64)
			(layers "F.Cu" "F.Paste" "F.Mask")
			(roundrect_rratio 0.25)
			(net 264 "/USB3/USBC1_TX1_N")
			(pintype "passive")
		)
	)
	(footprint "antmicro-footprints:HDMI-Mini-C_Receptacle_WE_685119136923"
		(layer "F.Cu")
		(at 93.94 125.31)
		(property "Reference" "J13"
			(at 4.06 -3.56 0)
			(layer "F.SilkS")
			(effects
				(font
					(size 0.7 0.7)
					(thickness 0.15)
				)
				(justify left bottom)
			)
		)
		(property "Value" "HDMI-Mini-C_WE_685119136923"
			(at 0 5.251 0)
			(layer "F.Fab")
			(effects
				(font
					(size 0.7 0.7)
					(thickness 0.15)
				)
				(justify left bottom)
			)
		)
		(property "Footprint" "antmicro-footprints:HDMI-Mini-C_Receptacle_WE_685119136923"
			(at 0 0 0)
			(layer "F.Fab")
			(hide yes)
			(effects
				(font
					(size 1.27 1.27)
					(thickness 0.15)
				)
			)
		)
		(property "Datasheet" "https://www.we-online.com/components/products/datasheet/685119136923.pdf"
			(at 0 0 0)
			(layer "F.Fab")
			(hide yes)
			(effects
				(font
					(size 1.27 1.27)
					(thickness 0.15)
				)
			)
		)
		(property "Author" "Antmicro"
			(at 0 0 0)
			(layer "F.Fab")
			(hide yes)
			(effects
				(font
					(size 1 1)
					(thickness 0.15)
				)
			)
		)
		(property "License" "Apache-2.0"
			(at 0 0 0)
			(layer "F.Fab")
			(hide yes)
			(effects
				(font
					(size 1 1)
					(thickness 0.15)
				)
			)
		)
		(property "MPN" "685119136923"
			(at 0 0 0)
			(layer "F.Fab")
			(hide yes)
			(effects
				(font
					(size 1 1)
					(thickness 0.15)
				)
			)
		)
		(property "Manufacturer" "Würth Elektronik"
			(at 0 0 0)
			(layer "F.Fab")
			(hide yes)
			(effects
				(font
					(size 1 1)
					(thickness 0.15)
				)
			)
		)
		(sheetname "HDMI")
		(sheetfile "hdmi.kicad_sch")
		(attr smd)
		(fp_line
			(start -5.702 -1.301)
			(end -5.702 1.2)
			(stroke
				(width 0.15)
				(type solid)
			)
			(layer "F.SilkS")
		)
		(fp_line
			(start -3.9 -3.4)
			(end -5.702 -3.4)
			(stroke
				(width 0.15)
				(type solid)
			)
			(layer "F.SilkS")
		)
		(fp_line
			(start 3.898 -3.4)
			(end 5.7 -3.4)
			(stroke
				(width 0.15)
				(type solid)
			)
			(layer "F.SilkS")
		)
		(fp_line
			(start 5.7 -1.301)
			(end 5.7 1.2)
			(stroke
				(width 0.15)
				(type solid)
			)
			(layer "F.SilkS")
		)
		(fp_circle
			(center 3.9148 -3.7254)
			(end 3.9638 -3.7254)
			(stroke
				(width 0.15)
				(type solid)
			)
			(fill solid)
			(layer "F.SilkS")
		)
		(fp_line
			(start -6 -3.75)
			(end -6 4.3)
			(stroke
				(width 0.05)
				(type solid)
			)
			(layer "F.CrtYd")
		)
		(fp_line
			(start -6 4.3)
			(end 6 4.3)
			(stroke
				(width 0.05)
				(type solid)
			)
			(layer "F.CrtYd")
		)
		(fp_line
			(start -3.9 -4.019)
			(end -3.9 -3.75)
			(stroke
				(width 0.05)
				(type solid)
			)
			(layer "F.CrtYd")
		)
		(fp_line
			(start -3.9 -3.75)
			(end -6 -3.75)
			(stroke
				(width 0.05)
				(type solid)
			)
			(layer "F.CrtYd")
		)
		(fp_line
			(start 3.89 -4.019)
			(end -3.9 -4.019)
			(stroke
				(width 0.05)
				(type solid)
			)
			(layer "F.CrtYd")
		)
		(fp_line
			(start 3.89 -3.75)
			(end 3.89 -4.019)
			(stroke
				(width 0.05)
				(type solid)
			)
			(layer "F.CrtYd")
		)
		(fp_line
			(start 6 -3.75)
			(end 3.9 -3.75)
			(stroke
				(width 0.05)
				(type solid)
			)
			(layer "F.CrtYd")
		)
		(fp_line
			(start 6 4.3)
			(end 6 -3.75)
			(stroke
				(width 0.05)
				(type solid)
			)
			(layer "F.CrtYd")
		)
		(fp_line
			(start 4.8768 -3.579)
			(end 5.588 -2.9186)
			(stroke
				(width 0.15)
				(type solid)
			)
			(layer "F.Fab")
		)
		(fp_rect
			(start -5.6388 -3.579)
			(end 5.588 3.2282)
			(stroke
				(width 0.15)
				(type solid)
			)
			(fill none)
			(layer "F.Fab")
		)
		(fp_text user "Author: Antmicro"
			(at -6.125 13.54 0)
			(layer "F.Fab")
			(hide yes)
			(effects
				(font
					(size 0.7 0.7)
					(thickness 0.15)
				)
				(justify left bottom)
			)
		)
		(fp_text user "${REFERENCE}"
			(at -6.125 12.34 0)
			(layer "F.Fab")
			(hide yes)
			(effects
				(font
					(size 0.7 0.7)
					(thickness 0.15)
				)
				(justify left bottom)
			)
		)
		(fp_text user "License: Apache-2.0"
			(at -6.125 11.14 0)
			(layer "F.Fab")
			(hide yes)
			(effects
				(font
					(size 0.7 0.7)
					(thickness 0.15)
				)
				(justify left bottom)
			)
		)
		(pad "1" smd rect
			(at 3.6 -3.4)
			(size 0.23 1)
			(layers "F.Cu" "F.Paste" "F.Mask")
			(net 1 "GND")
			(pinfunction "D2S")
			(pintype "passive")
		)
		(pad "2" smd rect
			(at 3.2 -3.4)
			(size 0.23 1)
			(layers "F.Cu" "F.Paste" "F.Mask")
			(net 528 "/HDMI/HDMI_D2_CONN_P")
			(pinfunction "D2+")
			(pintype "bidirectional")
		)
		(pad "3" smd rect
			(at 2.798 -3.4)
			(size 0.23 1)
			(layers "F.Cu" "F.Paste" "F.Mask")
			(net 527 "/HDMI/HDMI_D2_CONN_N")
			(pinfunction "D2-")
			(pintype "bidirectional")
		)
		(pad "4" smd rect
			(at 2.398 -3.4)
			(size 0.23 1)
			(layers "F.Cu" "F.Paste" "F.Mask")
			(net 1 "GND")
			(pinfunction "D1S")
			(pintype "passive")
		)
		(pad "5" smd rect
			(at 1.999 -3.4)
			(size 0.23 1)
			(layers "F.Cu" "F.Paste" "F.Mask")
			(net 526 "/HDMI/HDMI_D1_CONN_P")
			(pinfunction "D1+")
			(pintype "bidirectional")
		)
		(pad "6" smd rect
			(at 1.6 -3.4)
			(size 0.23 1)
			(layers "F.Cu" "F.Paste" "F.Mask")
			(net 525 "/HDMI/HDMI_D1_CONN_N")
			(pinfunction "D1-")
			(pintype "bidirectional")
		)
		(pad "7" smd rect
			(at 1.199 -3.4)
			(size 0.23 1)
			(layers "F.Cu" "F.Paste" "F.Mask")
			(net 1 "GND")
			(pinfunction "D0S")
			(pintype "passive")
		)
		(pad "8" smd rect
			(at 0.8 -3.4)
			(size 0.23 1)
			(layers "F.Cu" "F.Paste" "F.Mask")
			(net 524 "/HDMI/HDMI_D0_CONN_P")
			(pinfunction "D0+")
			(pintype "bidirectional")
		)
		(pad "9" smd rect
			(at 0.4 -3.4)
			(size 0.23 1)
			(layers "F.Cu" "F.Paste" "F.Mask")
			(net 523 "/HDMI/HDMI_D0_CONN_N")
			(pinfunction "D0-")
			(pintype "bidirectional")
		)
		(pad "10" smd rect
			(at 0 -3.4)
			(size 0.23 1)
			(layers "F.Cu" "F.Paste" "F.Mask")
			(net 1 "GND")
			(pinfunction "CKS")
			(pintype "passive")
		)
		(pad "11" smd rect
			(at -0.402 -3.4)
			(size 0.23 1)
			(layers "F.Cu" "F.Paste" "F.Mask")
			(net 522 "/HDMI/HDMI_CLK_CONN_P")
			(pinfunction "CK+")
			(pintype "bidirectional")
		)
		(pad "12" smd rect
			(at -0.802 -3.4)
			(size 0.23 1)
			(layers "F.Cu" "F.Paste" "F.Mask")
			(net 521 "/HDMI/HDMI_CLK_CONN_N")
			(pinfunction "CK-")
			(pintype "bidirectional")
		)
		(pad "13" smd rect
			(at -1.2 -3.4)
			(size 0.23 1)
			(layers "F.Cu" "F.Paste" "F.Mask")
			(net 1 "GND")
			(pinfunction "GND")
			(pintype "power_in")
		)
		(pad "14" smd rect
			(at -1.601 -3.4)
			(size 0.23 1)
			(layers "F.Cu" "F.Paste" "F.Mask")
			(net 520 "/HDMI/HDMI_CEC_5V")
			(pinfunction "CEC")
			(pintype "bidirectional")
		)
		(pad "15" smd rect
			(at -2 -3.4)
			(size 0.23 1)
			(layers "F.Cu" "F.Paste" "F.Mask")
			(net 519 "/HDMI/HDMI_SCL_5V")
			(pinfunction "SCL")
			(pintype "bidirectional")
		)
		(pad "16" smd rect
			(at -2.4 -3.4)
			(size 0.23 1)
			(layers "F.Cu" "F.Paste" "F.Mask")
			(net 518 "/HDMI/HDMI_SDA_5V")
			(pinfunction "SDA")
			(pintype "bidirectional")
		)
		(pad "17" smd rect
			(at -2.801 -3.4)
			(size 0.23 1)
			(layers "F.Cu" "F.Paste" "F.Mask")
			(net 620 "unconnected-(J13-UTIL{slash}HEAC+-Pad17)")
			(pinfunction "UTIL/HEAC+")
			(pintype "bidirectional+no_connect")
		)
		(pad "18" smd rect
			(at -3.202 -3.4)
			(size 0.23 1)
			(layers "F.Cu" "F.Paste" "F.Mask")
			(net 498 "/HDMI/5V_HDMI")
			(pinfunction "+5V")
			(pintype "power_in")
		)
		(pad "19" smd rect
			(at -3.601 -3.4)
			(size 0.23 1)
			(layers "F.Cu" "F.Paste" "F.Mask")
			(net 529 "/HDMI/HDMI_HPD_5V")
			(pinfunction "HPD/HEAC-")
			(pintype "bidirectional")
		)
		(pad "SH" thru_hole oval
			(at -5.425 -2.35)
			(size 1.2 1.9)
			(drill oval 0.6 1.3)
			(layers "*.Cu" "*.Mask")
			(remove_unused_layers no)
			(net 1 "GND")
			(pinfunction "SH")
			(pintype "passive")
		)
		(pad "SH" thru_hole oval
			(at -5.425 2.15)
			(size 1.2 1.7)
			(drill oval 0.6 1.3)
			(layers "*.Cu" "*.Mask")
			(remove_unused_layers no)
			(net 1 "GND")
			(pinfunction "SH")
			(pintype "passive")
		)
		(pad "SH" thru_hole oval
			(at 5.424 -2.35)
			(size 1.2 1.9)
			(drill oval 0.6 1.3)
			(layers "*.Cu" "*.Mask")
			(remove_unused_layers no)
			(net 1 "GND")
			(pinfunction "SH")
			(pintype "passive")
		)
		(pad "SH" thru_hole oval
			(at 5.424 2.15)
			(size 1.2 1.7)
			(drill oval 0.6 1.3)
			(layers "*.Cu" "*.Mask")
			(remove_unused_layers no)
			(net 1 "GND")
			(pinfunction "SH")
			(pintype "passive")
		)
	)
	(footprint "antmicro-footprints:C_0402_1005Metric"
		(layer "F.Cu")
		(at 105.154938 108 180)
		(descr "Capacitor SMD 0402")
		(tags "capacitor SMD 0402")
		(property "Reference" "C68"
			(at 3.004938 -0.45 180)
			(layer "F.SilkS")
			(effects
				(font
					(size 0.7 0.7)
					(thickness 0.15)
				)
				(justify left bottom)
			)
		)
		(property "Value" "C_100n_0402"
			(at 0 1.4 180)
			(layer "F.Fab")
			(effects
				(font
					(size 0.7 0.7)
					(thickness 0.15)
				)
				(justify left bottom)
			)
		)
		(property "Footprint" "antmicro-footprints:C_0402_1005Metric"
			(at 0 0 180)
			(layer "F.Fab")
			(hide yes)
			(effects
				(font
					(size 1.27 1.27)
					(thickness 0.15)
				)
			)
		)
		(property "Datasheet" "https://www.murata.com/products/productdetail?partno=GRM155R61H104KE14%23"
			(at 0 0 180)
			(layer "F.Fab")
			(hide yes)
			(effects
				(font
					(size 1.27 1.27)
					(thickness 0.15)
				)
			)
		)
		(property "Author" "Antmicro"
			(at 210.309876 216 0)
			(layer "F.Fab")
			(hide yes)
			(effects
				(font
					(size 1 1)
					(thickness 0.15)
				)
			)
		)
		(property "Dielectric" "X5R"
			(at 210.309876 216 0)
			(layer "F.Fab")
			(hide yes)
			(effects
				(font
					(size 1 1)
					(thickness 0.15)
				)
			)
		)
		(property "License" "Apache-2.0"
			(at 210.309876 216 0)
			(layer "F.Fab")
			(hide yes)
			(effects
				(font
					(size 1 1)
					(thickness 0.15)
				)
			)
		)
		(property "MPN" "GRM155R61H104KE14D"
			(at 210.309876 216 0)
			(layer "F.Fab")
			(hide yes)
			(effects
				(font
					(size 1 1)
					(thickness 0.15)
				)
			)
		)
		(property "Manufacturer" "Murata"
			(at 210.309876 216 0)
			(layer "F.Fab")
			(hide yes)
			(effects
				(font
					(size 1 1)
					(thickness 0.15)
				)
			)
		)
		(property "Val" "100n"
			(at 210.309876 216 0)
			(layer "F.Fab")
			(hide yes)
			(effects
				(font
					(size 1 1)
					(thickness 0.15)
				)
			)
		)
		(property "Voltage" "50V"
			(at 210.309876 216 0)
			(layer "F.Fab")
			(hide yes)
			(effects
				(font
					(size 1 1)
					(thickness 0.15)
				)
			)
		)
		(sheetname "USB3")
		(sheetfile "usb3.kicad_sch")
		(attr smd)
		(fp_rect
			(start -0.925 -0.47)
			(end 0.925 0.47)
			(stroke
				(width 0.05)
				(type default)
			)
			(fill none)
			(layer "F.CrtYd")
		)
		(fp_line
			(start 0.504 0.248)
			(end -0.494 0.248)
			(stroke
				(width 0.15)
				(type solid)
			)
			(layer "F.Fab")
		)
		(fp_line
			(start 0.504 -0.25)
			(end 0.504 0.248)
			(stroke
				(width 0.15)
				(type solid)
			)
			(layer "F.Fab")
		)
		(fp_line
			(start -0.494 0.248)
			(end -0.494 -0.25)
			(stroke
				(width 0.15)
				(type solid)
			)
			(layer "F.Fab")
		)
		(fp_line
			(start -0.494 -0.25)
			(end 0.504 -0.25)
			(stroke
				(width 0.15)
				(type solid)
			)
			(layer "F.Fab")
		)
		(fp_text user "License: Apache-2.0"
			(at -0.932 5.17 180)
			(layer "F.Fab")
			(hide yes)
			(effects
				(font
					(size 0.7 0.7)
					(thickness 0.15)
				)
				(justify left bottom)
			)
		)
		(fp_text user "Author: Antmicro"
			(at -0.932 4.17 180)
			(layer "F.Fab")
			(hide yes)
			(effects
				(font
					(size 0.7 0.7)
					(thickness 0.15)
				)
				(justify left bottom)
			)
		)
		(fp_text user "${REFERENCE}"
			(at -0.932 3.168 180)
			(layer "F.Fab")
			(hide yes)
			(effects
				(font
					(size 0.7 0.7)
					(thickness 0.15)
				)
				(justify left bottom)
			)
		)
		(pad "1" smd roundrect
			(at -0.48 0 180)
			(size 0.59 0.64)
			(layers "F.Cu" "F.Paste" "F.Mask")
			(roundrect_rratio 0.25)
			(net 87 "+3V3")
			(pintype "passive")
		)
		(pad "2" smd roundrect
			(at 0.48 0 180)
			(size 0.59 0.64)
			(layers "F.Cu" "F.Paste" "F.Mask")
			(roundrect_rratio 0.25)
			(net 1 "GND")
			(pintype "passive")
		)
	)
	(footprint "antmicro-footprints:R_0402_1005Metric"
		(layer "F.Cu")
		(at 57.51 92.77)
		(descr "Resistor SMD 0402")
		(tags "resistor SMD 0402")
		(property "Reference" "R272"
			(at 27.89 1.265 180)
			(layer "F.SilkS")
			(effects
				(font
					(size 0.7 0.7)
					(thickness 0.15)
				)
				(justify left bottom)
			)
		)
		(property "Value" "R_470k_0402"
			(at -1.011843 1.772047 0)
			(layer "F.Fab")
			(effects
				(font
					(size 0.7 0.7)
					(thickness 0.15)
				)
				(justify left bottom)
			)
		)
		(property "Footprint" "antmicro-footprints:R_0402_1005Metric"
			(at 0 0 0)
			(layer "F.Fab")
			(hide yes)
			(effects
				(font
					(size 1.27 1.27)
					(thickness 0.15)
				)
			)
		)
		(property "Datasheet" "https://www.bourns.com/docs/product-datasheets/cr.pdf"
			(at 0 0 0)
			(layer "F.Fab")
			(hide yes)
			(effects
				(font
					(size 1.27 1.27)
					(thickness 0.15)
				)
			)
		)
		(property "Description" "SMD Chip Resistor, 470 kohm, ± 1%, 62.5 mW, 0402 [1005 Metric], Thick Film, Sulfur Resistant"
			(at 0 0 0)
			(layer "F.Fab")
			(hide yes)
			(effects
				(font
					(size 1.27 1.27)
					(thickness 0.15)
				)
			)
		)
		(property "MPN" "CR0402-FX-4703GLF"
			(at 0 0 0)
			(unlocked yes)
			(layer "F.Fab")
			(hide yes)
			(effects
				(font
					(size 1 1)
					(thickness 0.15)
				)
			)
		)
		(property "Manufacturer" "Bourns"
			(at 0 0 0)
			(unlocked yes)
			(layer "F.Fab")
			(hide yes)
			(effects
				(font
					(size 1 1)
					(thickness 0.15)
				)
			)
		)
		(property "License" "Apache-2.0"
			(at 0 0 0)
			(unlocked yes)
			(layer "F.Fab")
			(hide yes)
			(effects
				(font
					(size 1 1)
					(thickness 0.15)
				)
			)
		)
		(property "Author" "Antmicro"
			(at 0 0 0)
			(unlocked yes)
			(layer "F.Fab")
			(hide yes)
			(effects
				(font
					(size 1 1)
					(thickness 0.15)
				)
			)
		)
		(property "Val" "470k"
			(at 0 0 0)
			(unlocked yes)
			(layer "F.Fab")
			(hide yes)
			(effects
				(font
					(size 1 1)
					(thickness 0.15)
				)
			)
		)
		(property "Tolerance" "1%"
			(at 0 0 0)
			(unlocked yes)
			(layer "F.Fab")
			(hide yes)
			(effects
				(font
					(size 1 1)
					(thickness 0.15)
				)
			)
		)
		(sheetname "Supply")
		(sheetfile "supply.kicad_sch")
		(attr smd)
		(fp_rect
			(start -0.925 -0.47)
			(end 0.925 0.47)
			(stroke
				(width 0.05)
				(type default)
			)
			(fill none)
			(layer "F.CrtYd")
		)
		(fp_rect
			(start -0.5 -0.25)
			(end 0.5 0.25)
			(stroke
				(width 0.15)
				(type solid)
			)
			(fill none)
			(layer "F.Fab")
		)
		(fp_text user "License: Apache-2.0"
			(at -0.95 5.169 0)
			(layer "F.Fab")
			(hide yes)
			(effects
				(font
					(size 0.7 0.7)
					(thickness 0.15)
				)
				(justify left bottom)
			)
		)
		(fp_text user "Author: Antmicro"
			(at -0.95 4.169 0)
			(layer "F.Fab")
			(hide yes)
			(effects
				(font
					(size 0.7 0.7)
					(thickness 0.15)
				)
				(justify left bottom)
			)
		)
		(fp_text user "${REFERENCE}"
			(at -0.95 3.168 0)
			(layer "F.Fab")
			(hide yes)
			(effects
				(font
					(size 0.7 0.7)
					(thickness 0.15)
				)
				(justify left bottom)
			)
		)
		(pad "1" smd roundrect
			(at -0.48 0)
			(size 0.59 0.64)
			(layers "F.Cu" "F.Paste" "F.Mask")
			(roundrect_rratio 0.25)
			(net 787 "+5V_SoM")
			(pintype "passive")
		)
		(pad "2" smd roundrect
			(at 0.48 0)
			(size 0.59 0.64)
			(layers "F.Cu" "F.Paste" "F.Mask")
			(roundrect_rratio 0.25)
			(net 792 "Net-(U29-PG)")
			(pintype "passive")
		)
	)
	(footprint "antmicro-footprints:R_0402_1005Metric"
		(layer "F.Cu")
		(at 132.085 119.7)
		(descr "Resistor SMD 0402")
		(tags "resistor SMD 0402")
		(property "Reference" "R230"
			(at -1.735 -0.45 0)
			(layer "F.SilkS")
			(effects
				(font
					(size 0.7 0.7)
					(thickness 0.15)
				)
				(justify left bottom)
			)
		)
		(property "Value" "R_100k_0402"
			(at 0 1.4 0)
			(layer "F.Fab")
			(effects
				(font
					(size 0.7 0.7)
					(thickness 0.15)
				)
				(justify left bottom)
			)
		)
		(property "Footprint" "antmicro-footprints:R_0402_1005Metric"
			(at 0 0 0)
			(layer "F.Fab")
			(hide yes)
			(effects
				(font
					(size 1.27 1.27)
					(thickness 0.15)
				)
			)
		)
		(property "Datasheet" "https://www.bourns.com/docs/product-datasheets/cr.pdf"
			(at 0 0 0)
			(layer "F.Fab")
			(hide yes)
			(effects
				(font
					(size 1.27 1.27)
					(thickness 0.15)
				)
			)
		)
		(property "Author" "Antmicro"
			(at 0 0 0)
			(layer "F.Fab")
			(hide yes)
			(effects
				(font
					(size 1 1)
					(thickness 0.15)
				)
			)
		)
		(property "License" "Apache-2.0"
			(at 0 0 0)
			(layer "F.Fab")
			(hide yes)
			(effects
				(font
					(size 1 1)
					(thickness 0.15)
				)
			)
		)
		(property "MPN" "CR0402-FX-1003GLF"
			(at 0 0 0)
			(layer "F.Fab")
			(hide yes)
			(effects
				(font
					(size 1 1)
					(thickness 0.15)
				)
			)
		)
		(property "Manufacturer" "Bourns"
			(at 0 0 0)
			(layer "F.Fab")
			(hide yes)
			(effects
				(font
					(size 1 1)
					(thickness 0.15)
				)
			)
		)
		(property "Tolerance" "1%"
			(at 0 0 0)
			(layer "F.Fab")
			(hide yes)
			(effects
				(font
					(size 1 1)
					(thickness 0.15)
				)
			)
		)
		(property "Val" "100k"
			(at 0 0 0)
			(layer "F.Fab")
			(hide yes)
			(effects
				(font
					(size 1 1)
					(thickness 0.15)
				)
			)
		)
		(sheetname "Peripherals")
		(sheetfile "peripherals.kicad_sch")
		(attr smd)
		(fp_rect
			(start -0.925 -0.47)
			(end 0.925 0.47)
			(stroke
				(width 0.05)
				(type default)
			)
			(fill none)
			(layer "F.CrtYd")
		)
		(fp_rect
			(start -0.5 -0.25)
			(end 0.5 0.25)
			(stroke
				(width 0.15)
				(type solid)
			)
			(fill none)
			(layer "F.Fab")
		)
		(fp_text user "Author: Antmicro"
			(at -0.95 4.169 0)
			(layer "F.Fab")
			(hide yes)
			(effects
				(font
					(size 0.7 0.7)
					(thickness 0.15)
				)
				(justify left bottom)
			)
		)
		(fp_text user "${REFERENCE}"
			(at -0.95 3.168 0)
			(layer "F.Fab")
			(hide yes)
			(effects
				(font
					(size 0.7 0.7)
					(thickness 0.15)
				)
				(justify left bottom)
			)
		)
		(fp_text user "License: Apache-2.0"
			(at -0.95 5.169 0)
			(layer "F.Fab")
			(hide yes)
			(effects
				(font
					(size 0.7 0.7)
					(thickness 0.15)
				)
				(justify left bottom)
			)
		)
		(pad "1" smd roundrect
			(at -0.48 0)
			(size 0.59 0.64)
			(layers "F.Cu" "F.Paste" "F.Mask")
			(roundrect_rratio 0.25)
			(net 1 "GND")
			(pintype "passive")
		)
		(pad "2" smd roundrect
			(at 0.48 0)
			(size 0.59 0.64)
			(layers "F.Cu" "F.Paste" "F.Mask")
			(roundrect_rratio 0.25)
			(net 44 "USER_LED1")
			(pintype "passive")
		)
	)
	(footprint "antmicro-footprints:R_0402_1005Metric"
		(layer "F.Cu")
		(at 80.7 112.8 180)
		(descr "Resistor SMD 0402")
		(tags "resistor SMD 0402")
		(property "Reference" "R131"
			(at -1.7 0.6 0)
			(layer "F.SilkS")
			(effects
				(font
					(size 0.7 0.7)
					(thickness 0.15)
				)
				(justify right bottom)
			)
		)
		(property "Value" "R_10k_0402"
			(at 0 1.4 0)
			(layer "F.Fab")
			(effects
				(font
					(size 0.7 0.7)
					(thickness 0.15)
				)
				(justify right bottom)
			)
		)
		(property "Footprint" "antmicro-footprints:R_0402_1005Metric"
			(at 0 0 180)
			(layer "F.Fab")
			(hide yes)
			(effects
				(font
					(size 1.27 1.27)
					(thickness 0.15)
				)
			)
		)
		(property "Datasheet" "https://www.bourns.com/docs/product-datasheets/cr.pdf"
			(at 0 0 180)
			(layer "F.Fab")
			(hide yes)
			(effects
				(font
					(size 1.27 1.27)
					(thickness 0.15)
				)
			)
		)
		(property "Author" "Antmicro"
			(at 161.4 225.6 0)
			(layer "F.Fab")
			(hide yes)
			(effects
				(font
					(size 1 1)
					(thickness 0.15)
				)
			)
		)
		(property "License" "Apache-2.0"
			(at 161.4 225.6 0)
			(layer "F.Fab")
			(hide yes)
			(effects
				(font
					(size 1 1)
					(thickness 0.15)
				)
			)
		)
		(property "MPN" "CR0402-FX-1002GLF"
			(at 161.4 225.6 0)
			(layer "F.Fab")
			(hide yes)
			(effects
				(font
					(size 1 1)
					(thickness 0.15)
				)
			)
		)
		(property "Manufacturer" "Bourns"
			(at 161.4 225.6 0)
			(layer "F.Fab")
			(hide yes)
			(effects
				(font
					(size 1 1)
					(thickness 0.15)
				)
			)
		)
		(property "Tolerance" "1%"
			(at 161.4 225.6 0)
			(layer "F.Fab")
			(hide yes)
			(effects
				(font
					(size 1 1)
					(thickness 0.15)
				)
			)
		)
		(property "Val" "10k"
			(at 161.4 225.6 0)
			(layer "F.Fab")
			(hide yes)
			(effects
				(font
					(size 1 1)
					(thickness 0.15)
				)
			)
		)
		(sheetname "USB Debug, DP")
		(sheetfile "usb.kicad_sch")
		(attr smd)
		(fp_rect
			(start -0.925 -0.47)
			(end 0.925 0.47)
			(stroke
				(width 0.05)
				(type default)
			)
			(fill none)
			(layer "F.CrtYd")
		)
		(fp_rect
			(start -0.5 -0.25)
			(end 0.5 0.25)
			(stroke
				(width 0.15)
				(type solid)
			)
			(fill none)
			(layer "F.Fab")
		)
		(fp_text user "License: Apache-2.0"
			(at -0.95 5.169 0)
			(layer "F.Fab")
			(hide yes)
			(effects
				(font
					(size 0.7 0.7)
					(thickness 0.15)
				)
				(justify right bottom)
			)
		)
		(fp_text user "${REFERENCE}"
			(at -0.95 3.168 0)
			(layer "F.Fab")
			(hide yes)
			(effects
				(font
					(size 0.7 0.7)
					(thickness 0.15)
				)
				(justify right bottom)
			)
		)
		(fp_text user "Author: Antmicro"
			(at -0.95 4.169 0)
			(layer "F.Fab")
			(hide yes)
			(effects
				(font
					(size 0.7 0.7)
					(thickness 0.15)
				)
				(justify right bottom)
			)
		)
		(pad "1" smd roundrect
			(at -0.48 0 180)
			(size 0.59 0.64)
			(layers "F.Cu" "F.Paste" "F.Mask")
			(roundrect_rratio 0.25)
			(net 255 "PDC_MISO")
			(pintype "passive")
		)
		(pad "2" smd roundrect
			(at 0.48 0 180)
			(size 0.59 0.64)
			(layers "F.Cu" "F.Paste" "F.Mask")
			(roundrect_rratio 0.25)
			(net 98 "EEPROM_PWR")
			(pintype "passive")
		)
	)
	(footprint "antmicro-footprints:Fiducial_1mm_Mask2mm"
		(layer "F.Cu")
		(at 32.3 127.15)
		(descr "Circular Fiducial, 1mm bare copper, 3mm soldermask opening")
		(tags "fiducial")
		(property "Reference" "FID1"
			(at 0 -1.4 0)
			(layer "F.SilkS")
			(hide yes)
			(effects
				(font
					(size 0.7 0.7)
					(thickness 0.15)
				)
				(justify left bottom)
			)
		)
		(property "Value" "Fiducial_1mm_Mask2mm"
			(at 0 2.2 0)
			(layer "F.Fab")
			(effects
				(font
					(size 0.7 0.7)
					(thickness 0.15)
				)
				(justify left bottom)
			)
		)
		(property "Footprint" "antmicro-footprints:Fiducial_1mm_Mask2mm"
			(at 0 0 0)
			(layer "F.Fab")
			(hide yes)
			(effects
				(font
					(size 1.27 1.27)
					(thickness 0.15)
				)
			)
		)
		(attr board_only exclude_from_pos_files exclude_from_bom)
		(fp_circle
			(center 0 0)
			(end 1.24 0)
			(stroke
				(width 0.05)
				(type solid)
			)
			(fill none)
			(layer "F.CrtYd")
		)
		(fp_circle
			(center 0 0)
			(end 0.999 0)
			(stroke
				(width 0.15)
				(type solid)
			)
			(fill none)
			(layer "F.Fab")
		)
		(fp_text user "License: Apache-2.0"
			(at -1.25 7.003 0)
			(layer "F.Fab")
			(hide yes)
			(effects
				(font
					(size 0.7 0.7)
					(thickness 0.15)
				)
				(justify left bottom)
			)
		)
		(fp_text user "Author: Antmicro"
			(at -1.25 5.803 0)
			(layer "F.Fab")
			(hide yes)
			(effects
				(font
					(size 0.7 0.7)
					(thickness 0.15)
				)
				(justify left bottom)
			)
		)
		(fp_text user "${REFERENCE}"
			(at -1.25 4.603 0)
			(layer "F.Fab")
			(hide yes)
			(effects
				(font
					(size 0.7 0.7)
					(thickness 0.15)
				)
				(justify left bottom)
			)
		)
		(pad "" smd circle
			(at 0 0)
			(size 1 1)
			(layers "F.Cu" "F.Mask")
			(solder_mask_margin 0.5)
			(clearance 0.5)
		)
	)
	(footprint "antmicro-footprints:Conn_Socket_Samtec_ERF8_2x40_ERF8-040-05.0-L-DV-K-TR"
		(layer "F.Cu")
		(at 143.75 98.75 -90)
		(property "Reference" "J11"
			(at -4.94 -3.95 90)
			(layer "F.SilkS")
			(effects
				(font
					(size 0.7 0.7)
					(thickness 0.15)
				)
				(justify left bottom)
			)
		)
		(property "Value" "Socket_Samtec_ERF8_2x40_ERF8-040-05.0-L-DV-K-TR"
			(at 0 4 90)
			(layer "F.Fab")
			(effects
				(font
					(size 0.7 0.7)
					(thickness 0.15)
				)
				(justify right bottom)
			)
		)
		(property "Footprint" "antmicro-footprints:Conn_Socket_Samtec_ERF8_2x40_ERF8-040-05.0-L-DV-K-TR"
			(at 0 0 -90)
			(layer "F.Fab")
			(hide yes)
			(effects
				(font
					(size 1.27 1.27)
					(thickness 0.15)
				)
			)
		)
		(property "Datasheet" "https://suddendocs.samtec.com/catalog_english/erf8.pdf"
			(at 0 0 -90)
			(layer "F.Fab")
			(hide yes)
			(effects
				(font
					(size 1.27 1.27)
					(thickness 0.15)
				)
			)
		)
		(property "Author" "Antmicro"
			(at 45 242.5 0)
			(layer "F.Fab")
			(hide yes)
			(effects
				(font
					(size 1 1)
					(thickness 0.15)
				)
			)
		)
		(property "License" "Apache-2.0"
			(at 45 242.5 0)
			(layer "F.Fab")
			(hide yes)
			(effects
				(font
					(size 1 1)
					(thickness 0.15)
				)
			)
		)
		(property "MPN" "ERF8-040-05.0-L-DV-K-TR"
			(at 45 242.5 0)
			(layer "F.Fab")
			(hide yes)
			(effects
				(font
					(size 1 1)
					(thickness 0.15)
				)
			)
		)
		(property "Manufacturer" "Samtec"
			(at 45 242.5 0)
			(layer "F.Fab")
			(hide yes)
			(effects
				(font
					(size 1 1)
					(thickness 0.15)
				)
			)
		)
		(property "Pitch" "0.8 mm"
			(at 45 242.5 0)
			(layer "F.Fab")
			(hide yes)
			(effects
				(font
					(size 1 1)
					(thickness 0.15)
				)
			)
		)
		(sheetname "Peripherals")
		(sheetfile "peripherals.kicad_sch")
		(attr smd)
		(fp_line
			(start -17.499 2.9)
			(end -16.5 2.9)
			(stroke
				(width 0.15)
				(type solid)
			)
			(layer "F.SilkS")
		)
		(fp_line
			(start 19.1 2.9)
			(end 16 2.9)
			(stroke
				(width 0.15)
				(type solid)
			)
			(layer "F.SilkS")
		)
		(fp_line
			(start -19.101 1.301)
			(end -17.499 2.9)
			(stroke
				(width 0.15)
				(type solid)
			)
			(layer "F.SilkS")
		)
		(fp_line
			(start -19.101 -2.899)
			(end -19.101 1.301)
			(stroke
				(width 0.15)
				(type solid)
			)
			(layer "F.SilkS")
		)
		(fp_line
			(start 19.1 -2.899)
			(end 19.1 2.9)
			(stroke
				(width 0.15)
				(type solid)
			)
			(layer "F.SilkS")
		)
		(fp_line
			(start -16 -2.9)
			(end -19.101 -2.899)
			(stroke
				(width 0.15)
				(type solid)
			)
			(layer "F.SilkS")
		)
		(fp_line
			(start 16 -2.9)
			(end 19.1 -2.899)
			(stroke
				(width 0.15)
				(type solid)
			)
			(layer "F.SilkS")
		)
		(fp_circle
			(center -16.05 2.95)
			(end -16.1 2.95)
			(stroke
				(width 0.15)
				(type solid)
			)
			(fill solid)
			(layer "F.SilkS")
		)
		(fp_rect
			(start 19.3 3.1)
			(end -19.3 -3.1)
			(stroke
				(width 0.05)
				(type solid)
			)
			(fill none)
			(layer "F.CrtYd")
		)
		(fp_line
			(start -17.499 2.799)
			(end 0 2.799)
			(stroke
				(width 0.15)
				(type solid)
			)
			(layer "F.Fab")
		)
		(fp_line
			(start 0 2.799)
			(end 15.599 2.799)
			(stroke
				(width 0.15)
				(type solid)
			)
			(layer "F.Fab")
		)
		(fp_line
			(start 15.599 2.799)
			(end 18.999 2.799)
			(stroke
				(width 0.15)
				(type solid)
			)
			(layer "F.Fab")
		)
		(fp_line
			(start 18.999 2.799)
			(end 18.999 -2.799)
			(stroke
				(width 0.15)
				(type solid)
			)
			(layer "F.Fab")
		)
		(fp_line
			(start -18.999 1.301)
			(end -17.499 2.799)
			(stroke
				(width 0.15)
				(type solid)
			)
			(layer "F.Fab")
		)
		(fp_line
			(start -18.999 -2.799)
			(end -18.999 1.301)
			(stroke
				(width 0.15)
				(type solid)
			)
			(layer "F.Fab")
		)
		(fp_line
			(start -14.599 -2.799)
			(end -18.999 -2.799)
			(stroke
				(width 0.15)
				(type solid)
			)
			(layer "F.Fab")
		)
		(fp_line
			(start 0 -2.799)
			(end -15.599 -2.799)
			(stroke
				(width 0.15)
				(type solid)
			)
			(layer "F.Fab")
		)
		(fp_line
			(start 18.999 -2.799)
			(end 0 -2.799)
			(stroke
				(width 0.15)
				(type solid)
			)
			(layer "F.Fab")
		)
		(fp_text user "Author: Antmicro"
			(at -19.2 6.6 90)
			(layer "F.Fab")
			(hide yes)
			(effects
				(font
					(size 0.7 0.7)
					(thickness 0.15)
				)
				(justify right bottom)
			)
		)
		(fp_text user "License: Apache-2.0"
			(at -19.2 7.8 90)
			(layer "F.Fab")
			(hide yes)
			(effects
				(font
					(size 0.7 0.7)
					(thickness 0.15)
				)
				(justify right bottom)
			)
		)
		(fp_text user "${REFERENCE}"
			(at -19.2 5.398 90)
			(layer "F.Fab")
			(hide yes)
			(effects
				(font
					(size 0.7 0.7)
					(thickness 0.15)
				)
				(justify right bottom)
			)
		)
		(pad "" np_thru_hole circle
			(at -17.4 -1.499 90)
			(size 1.45 1.45)
			(drill 1.45)
			(layers "*.Mask")
		)
		(pad "" np_thru_hole circle
			(at 17.399 -1.499 90)
			(size 1.45 1.45)
			(drill 1.45)
			(layers "*.Mask")
		)
		(pad "1" smd rect
			(at -15.599 2.249 90)
			(size 0.5 1.1)
			(layers "F.Cu" "F.Paste" "F.Mask")
			(net 1 "GND")
			(pintype "passive")
		)
		(pad "2" smd rect
			(at -15.599 -2.249 90)
			(size 0.5 1.1)
			(layers "F.Cu" "F.Paste" "F.Mask")
			(net 1 "GND")
			(pintype "passive")
		)
		(pad "3" smd rect
			(at -14.801 2.249 90)
			(size 0.5 1.1)
			(layers "F.Cu" "F.Paste" "F.Mask")
			(net 415 "/Peripherals/PCIE2_TX1_CONN_N")
			(pintype "passive")
		)
		(pad "4" smd rect
			(at -14.801 -2.249 90)
			(size 0.5 1.1)
			(layers "F.Cu" "F.Paste" "F.Mask")
			(net 1 "GND")
			(pintype "passive")
		)
		(pad "5" smd rect
			(at -14 2.249 90)
			(size 0.5 1.1)
			(layers "F.Cu" "F.Paste" "F.Mask")
			(net 413 "/Peripherals/PCIE2_TX1_CONN_P")
			(pintype "passive")
		)
		(pad "6" smd rect
			(at -14 -2.249 90)
			(size 0.5 1.1)
			(layers "F.Cu" "F.Paste" "F.Mask")
			(net 172 "PCIE2_RX1_N")
			(pintype "passive")
		)
		(pad "7" smd rect
			(at -13.199 2.249 90)
			(size 0.5 1.1)
			(layers "F.Cu" "F.Paste" "F.Mask")
			(net 1 "GND")
			(pintype "passive")
		)
		(pad "8" smd rect
			(at -13.199 -2.249 90)
			(size 0.5 1.1)
			(layers "F.Cu" "F.Paste" "F.Mask")
			(net 175 "PCIE2_RX1_P")
			(pintype "passive")
		)
		(pad "9" smd rect
			(at -12.401 2.249 90)
			(size 0.5 1.1)
			(layers "F.Cu" "F.Paste" "F.Mask")
			(net 411 "/Peripherals/PCIE2_TX0_CONN_N")
			(pintype "passive")
		)
		(pad "10" smd rect
			(at -12.401 -2.249 90)
			(size 0.5 1.1)
			(layers "F.Cu" "F.Paste" "F.Mask")
			(net 1 "GND")
			(pintype "passive")
		)
		(pad "11" smd rect
			(at -11.599 2.249 90)
			(size 0.5 1.1)
			(layers "F.Cu" "F.Paste" "F.Mask")
			(net 412 "/Peripherals/PCIE2_TX0_CONN_P")
			(pintype "passive")
		)
		(pad "12" smd rect
			(at -11.599 -2.249 90)
			(size 0.5 1.1)
			(layers "F.Cu" "F.Paste" "F.Mask")
			(net 113 "PCIE2_RX0_N")
			(pintype "passive")
		)
		(pad "13" smd rect
			(at -10.801 2.249 90)
			(size 0.5 1.1)
			(layers "F.Cu" "F.Paste" "F.Mask")
			(net 1 "GND")
			(pintype "passive")
		)
		(pad "14" smd rect
			(at -10.801 -2.249 90)
			(size 0.5 1.1)
			(layers "F.Cu" "F.Paste" "F.Mask")
			(net 131 "PCIE2_RX0_P")
			(pintype "passive")
		)
		(pad "15" smd rect
			(at -10 2.249 90)
			(size 0.5 1.1)
			(layers "F.Cu" "F.Paste" "F.Mask")
			(net 163 "PCIE2_CLK_N")
			(pintype "passive")
		)
		(pad "16" smd rect
			(at -10 -2.249 90)
			(size 0.5 1.1)
			(layers "F.Cu" "F.Paste" "F.Mask")
			(net 1 "GND")
			(pintype "passive")
		)
		(pad "17" smd rect
			(at -9.199 2.249 90)
			(size 0.5 1.1)
			(layers "F.Cu" "F.Paste" "F.Mask")
			(net 166 "PCIE2_CLK_P")
			(pintype "passive")
		)
		(pad "18" smd rect
			(at -9.199 -2.249 90)
			(size 0.5 1.1)
			(layers "F.Cu" "F.Paste" "F.Mask")
			(net 471 "PCIE3_CLK_N")
			(pintype "passive")
		)
		(pad "19" smd rect
			(at -8.401 2.249 90)
			(size 0.5 1.1)
			(layers "F.Cu" "F.Paste" "F.Mask")
			(net 1 "GND")
			(pintype "passive")
		)
		(pad "20" smd rect
			(at -8.401 -2.249 90)
			(size 0.5 1.1)
			(layers "F.Cu" "F.Paste" "F.Mask")
			(net 472 "PCIE3_CLK_P")
			(pintype "passive")
		)
		(pad "21" smd rect
			(at -7.6 2.249 90)
			(size 0.5 1.1)
			(layers "F.Cu" "F.Paste" "F.Mask")
			(net 416 "/Peripherals/USBSS2_TX_CONN_N")
			(pintype "passive")
		)
		(pad "22" smd rect
			(at -7.6 -2.249 90)
			(size 0.5 1.1)
			(layers "F.Cu" "F.Paste" "F.Mask")
			(net 1 "GND")
			(pintype "passive")
		)
		(pad "23" smd rect
			(at -6.8 2.249 90)
			(size 0.5 1.1)
			(layers "F.Cu" "F.Paste" "F.Mask")
			(net 414 "/Peripherals/USBSS2_TX_CONN_P")
			(pintype "passive")
		)
		(pad "24" smd rect
			(at -6.8 -2.249 90)
			(size 0.5 1.1)
			(layers "F.Cu" "F.Paste" "F.Mask")
			(net 107 "USBSS1_RX_N")
			(pintype "passive")
		)
		(pad "25" smd rect
			(at -5.999 2.249 90)
			(size 0.5 1.1)
			(layers "F.Cu" "F.Paste" "F.Mask")
			(net 1 "GND")
			(pintype "passive")
		)
		(pad "26" smd rect
			(at -5.999 -2.249 90)
			(size 0.5 1.1)
			(layers "F.Cu" "F.Paste" "F.Mask")
			(net 114 "USBSS1_RX_P")
			(pintype "passive")
		)
		(pad "27" smd rect
			(at -5.201 2.249 90)
			(size 0.5 1.1)
			(layers "F.Cu" "F.Paste" "F.Mask")
			(net 345 "/Peripherals/PCIE2_RST_CONN*")
			(pintype "passive")
		)
		(pad "28" smd rect
			(at -5.201 -2.249 90)
			(size 0.5 1.1)
			(layers "F.Cu" "F.Paste" "F.Mask")
			(net 1 "GND")
			(pintype "passive")
		)
		(pad "29" smd rect
			(at -4.401 2.249 90)
			(size 0.5 1.1)
			(layers "F.Cu" "F.Paste" "F.Mask")
			(net 346 "/Peripherals/PCIE2_CLKREQ_CONN*")
			(pintype "passive")
		)
		(pad "30" smd rect
			(at -4.401 -2.249 90)
			(size 0.5 1.1)
			(layers "F.Cu" "F.Paste" "F.Mask")
			(net 347 "/Peripherals/PCIE3_RST_CONN*")
			(pintype "passive")
		)
		(pad "31" smd rect
			(at -3.601 2.249 90)
			(size 0.5 1.1)
			(layers "F.Cu" "F.Paste" "F.Mask")
			(net 348 "/Peripherals/GPIO01_CONN")
			(pintype "passive")
		)
		(pad "32" smd rect
			(at -3.601 -2.249 90)
			(size 0.5 1.1)
			(layers "F.Cu" "F.Paste" "F.Mask")
			(net 513 "/Peripherals/PCIE3_CLKREQ_CONN*")
			(pintype "passive")
		)
		(pad "33" smd rect
			(at -2.799 2.249 90)
			(size 0.5 1.1)
			(layers "F.Cu" "F.Paste" "F.Mask")
			(net 515 "/Peripherals/GPIO07_CONN")
			(pintype "passive")
		)
		(pad "34" smd rect
			(at -2.799 -2.249 90)
			(size 0.5 1.1)
			(layers "F.Cu" "F.Paste" "F.Mask")
			(net 578 "/Peripherals/PCIE_WAKE_SEL_EXT_CONN")
			(pintype "passive")
		)
		(pad "35" smd rect
			(at -2 2.249 90)
			(size 0.5 1.1)
			(layers "F.Cu" "F.Paste" "F.Mask")
			(net 579 "/Peripherals/GPIO09_CONN")
			(pintype "passive")
		)
		(pad "36" smd rect
			(at -2 -2.249 90)
			(size 0.5 1.1)
			(layers "F.Cu" "F.Paste" "F.Mask")
			(net 580 "/Peripherals/GPIO13_CONN")
			(pintype "passive")
		)
		(pad "37" smd rect
			(at -1.2 2.249 90)
			(size 0.5 1.1)
			(layers "F.Cu" "F.Paste" "F.Mask")
			(net 1 "GND")
			(pintype "passive")
		)
		(pad "38" smd rect
			(at -1.2 -2.249 90)
			(size 0.5 1.1)
			(layers "F.Cu" "F.Paste" "F.Mask")
			(net 1 "GND")
			(pintype "passive")
		)
		(pad "39" smd rect
			(at -0.401 2.249 90)
			(size 0.5 1.1)
			(layers "F.Cu" "F.Paste" "F.Mask")
			(net 584 "/Peripherals/UART1_RXD_CONN")
			(pintype "passive")
		)
		(pad "40" smd rect
			(at -0.401 -2.249 90)
			(size 0.5 1.1)
			(layers "F.Cu" "F.Paste" "F.Mask")
			(net 581 "/Peripherals/GPIO12_CONN")
			(pintype "passive")
		)
		(pad "41" smd rect
			(at 0.401 2.249 90)
			(size 0.5 1.1)
			(layers "F.Cu" "F.Paste" "F.Mask")
			(net 618 "/Peripherals/USB_CONN_N")
			(pintype "passive")
		)
		(pad "42" smd rect
			(at 0.401 -2.249 90)
			(size 0.5 1.1)
			(layers "F.Cu" "F.Paste" "F.Mask")
			(net 583 "/Peripherals/GPIO11_CONN")
			(pintype "passive")
		)
		(pad "43" smd rect
			(at 1.199 2.249 90)
			(size 0.5 1.1)
			(layers "F.Cu" "F.Paste" "F.Mask")
			(net 619 "/Peripherals/USB_CONN_P")
			(pintype "passive")
		)
		(pad "44" smd rect
			(at 1.199 -2.249 90)
			(size 0.5 1.1)
			(layers "F.Cu" "F.Paste" "F.Mask")
			(net 582 "/Peripherals/UART1_TXD_CONN")
			(pintype "passive")
		)
		(pad "45" smd rect
			(at 1.999 2.249 90)
			(size 0.5 1.1)
			(layers "F.Cu" "F.Paste" "F.Mask")
			(net 585 "/Peripherals/I2S0_SDIN_CONN")
			(pintype "passive")
		)
		(pad "46" smd rect
			(at 1.999 -2.249 90)
			(size 0.5 1.1)
			(layers "F.Cu" "F.Paste" "F.Mask")
			(net 586 "/Peripherals/I2S0_SCLK_CONN")
			(pintype "passive")
		)
		(pad "47" smd rect
			(at 2.799 2.249 90)
			(size 0.5 1.1)
			(layers "F.Cu" "F.Paste" "F.Mask")
			(net 587 "/Peripherals/I2S0_LRCK_CONN")
			(pintype "passive")
		)
		(pad "48" smd rect
			(at 2.799 -2.249 90)
			(size 0.5 1.1)
			(layers "F.Cu" "F.Paste" "F.Mask")
			(net 588 "/Peripherals/I2S0_SDOUT_CONN")
			(pintype "passive")
		)
		(pad "49" smd rect
			(at 3.6 2.249 90)
			(size 0.5 1.1)
			(layers "F.Cu" "F.Paste" "F.Mask")
			(net 1 "GND")
			(pintype "passive")
		)
		(pad "50" smd rect
			(at 3.6 -2.249 90)
			(size 0.5 1.1)
			(layers "F.Cu" "F.Paste" "F.Mask")
			(net 1 "GND")
			(pintype "passive")
		)
		(pad "51" smd rect
			(at 4.4 2.249 90)
			(size 0.5 1.1)
			(layers "F.Cu" "F.Paste" "F.Mask")
			(net 589 "/Peripherals/SPIO_SCK_CONN")
			(pintype "passive")
		)
		(pad "52" smd rect
			(at 4.4 -2.249 90)
			(size 0.5 1.1)
			(layers "F.Cu" "F.Paste" "F.Mask")
			(net 590 "/Peripherals/SPI1_SCK_CONN")
			(pintype "passive")
		)
		(pad "53" smd rect
			(at 5.2 2.249 90)
			(size 0.5 1.1)
			(layers "F.Cu" "F.Paste" "F.Mask")
			(net 591 "/Peripherals/SPIO_MOSI_CONN")
			(pintype "passive")
		)
		(pad "54" smd rect
			(at 5.2 -2.249 90)
			(size 0.5 1.1)
			(layers "F.Cu" "F.Paste" "F.Mask")
			(net 592 "/Peripherals/SPI1_MOSI_CONN")
			(pintype "passive")
		)
		(pad "55" smd rect
			(at 5.999 2.249 90)
			(size 0.5 1.1)
			(layers "F.Cu" "F.Paste" "F.Mask")
			(net 593 "/Peripherals/SPIO_MISO_CONN")
			(pintype "passive")
		)
		(pad "56" smd rect
			(at 5.999 -2.249 90)
			(size 0.5 1.1)
			(layers "F.Cu" "F.Paste" "F.Mask")
			(net 594 "/Peripherals/SPI1_MISO_CONN")
			(pintype "passive")
		)
		(pad "57" smd rect
			(at 6.799 2.249 90)
			(size 0.5 1.1)
			(layers "F.Cu" "F.Paste" "F.Mask")
			(net 595 "/Peripherals/~{SPI0_CS0_CONN}")
			(pintype "passive")
		)
		(pad "58" smd rect
			(at 6.799 -2.249 90)
			(size 0.5 1.1)
			(layers "F.Cu" "F.Paste" "F.Mask")
			(net 606 "/Peripherals/~{SPI1_CS0_CONN}")
			(pintype "passive")
		)
		(pad "59" smd rect
			(at 7.599 2.249 90)
			(size 0.5 1.1)
			(layers "F.Cu" "F.Paste" "F.Mask")
			(net 607 "/Peripherals/~{SPI0_CS1_CONN}")
			(pintype "passive")
		)
		(pad "60" smd rect
			(at 7.599 -2.249 90)
			(size 0.5 1.1)
			(layers "F.Cu" "F.Paste" "F.Mask")
			(net 608 "/Peripherals/~{SPI1_CS1_CONN}")
			(pintype "passive")
		)
		(pad "61" smd rect
			(at 8.4 2.249 90)
			(size 0.5 1.1)
			(layers "F.Cu" "F.Paste" "F.Mask")
			(net 1 "GND")
			(pintype "passive")
		)
		(pad "62" smd rect
			(at 8.4 -2.249 90)
			(size 0.5 1.1)
			(layers "F.Cu" "F.Paste" "F.Mask")
			(net 1 "GND")
			(pintype "passive")
		)
		(pad "63" smd rect
			(at 9.199 2.249 90)
			(size 0.5 1.1)
			(layers "F.Cu" "F.Paste" "F.Mask")
			(net 596 "Net-(J11-Pad63)")
			(pintype "passive")
		)
		(pad "64" smd rect
			(at 9.199 -2.249 90)
			(size 0.5 1.1)
			(layers "F.Cu" "F.Paste" "F.Mask")
			(net 597 "Net-(J11-Pad64)")
			(pintype "passive")
		)
		(pad "65" smd rect
			(at 9.999 2.249 90)
			(size 0.5 1.1)
			(layers "F.Cu" "F.Paste" "F.Mask")
			(net 598 "Net-(J11-Pad65)")
			(pintype "passive")
		)
		(pad "66" smd rect
			(at 9.999 -2.249 90)
			(size 0.5 1.1)
			(layers "F.Cu" "F.Paste" "F.Mask")
			(net 599 "Net-(J11-Pad66)")
			(pintype "passive")
		)
		(pad "67" smd rect
			(at 10.8 2.249 90)
			(size 0.5 1.1)
			(layers "F.Cu" "F.Paste" "F.Mask")
			(net 482 "/Peripherals/3V3_CONN")
			(pintype "passive")
		)
		(pad "68" smd rect
			(at 10.8 -2.249 90)
			(size 0.5 1.1)
			(layers "F.Cu" "F.Paste" "F.Mask")
			(net 600 "Net-(J11-Pad68)")
			(pintype "passive")
		)
		(pad "69" smd rect
			(at 11.599 2.249 90)
			(size 0.5 1.1)
			(layers "F.Cu" "F.Paste" "F.Mask")
			(net 482 "/Peripherals/3V3_CONN")
			(pintype "passive")
		)
		(pad "70" smd rect
			(at 11.599 -2.249 90)
			(size 0.5 1.1)
			(layers "F.Cu" "F.Paste" "F.Mask")
			(net 601 "Net-(J11-Pad70)")
			(pintype "passive")
		)
		(pad "71" smd rect
			(at 12.4 2.249 90)
			(size 0.5 1.1)
			(layers "F.Cu" "F.Paste" "F.Mask")
			(net 1 "GND")
			(pintype "passive")
		)
		(pad "72" smd rect
			(at 12.4 -2.249 90)
			(size 0.5 1.1)
			(layers "F.Cu" "F.Paste" "F.Mask")
			(net 1 "GND")
			(pintype "passive")
		)
		(pad "73" smd rect
			(at 13.199 2.249 90)
			(size 0.5 1.1)
			(layers "F.Cu" "F.Paste" "F.Mask")
			(net 483 "/Peripherals/1V8_CONN")
			(pintype "passive")
		)
		(pad "74" smd rect
			(at 13.199 -2.249 90)
			(size 0.5 1.1)
			(layers "F.Cu" "F.Paste" "F.Mask")
			(net 484 "/Peripherals/3V3_STDB_CONN")
			(pintype "passive")
		)
		(pad "75" smd rect
			(at 13.999 2.249 90)
			(size 0.5 1.1)
			(layers "F.Cu" "F.Paste" "F.Mask")
			(net 1 "GND")
			(pintype "passive")
		)
		(pad "76" smd rect
			(at 13.999 -2.249 90)
			(size 0.5 1.1)
			(layers "F.Cu" "F.Paste" "F.Mask")
			(net 1 "GND")
			(pintype "passive")
		)
		(pad "77" smd rect
			(at 14.8 2.249 90)
			(size 0.5 1.1)
			(layers "F.Cu" "F.Paste" "F.Mask")
			(net 479 "/Peripherals/5V_CONN")
			(pintype "passive")
		)
		(pad "78" smd rect
			(at 14.8 -2.249 90)
			(size 0.5 1.1)
			(layers "F.Cu" "F.Paste" "F.Mask")
			(net 485 "/Peripherals/VCC_CONN")
			(pintype "passive")
		)
		(pad "79" smd rect
			(at 15.599 2.249 90)
			(size 0.5 1.1)
			(layers "F.Cu" "F.Paste" "F.Mask")
			(net 479 "/Peripherals/5V_CONN")
			(pintype "passive")
		)
		(pad "80" smd rect
			(at 15.599 -2.249 90)
			(size 0.5 1.1)
			(layers "F.Cu" "F.Paste" "F.Mask")
			(net 485 "/Peripherals/VCC_CONN")
			(pintype "passive")
		)
	)
	(footprint "antmicro-footprints:LED_0603_1608Metric_G"
		(layer "F.Cu")
		(at 134.7 127.2 -90)
		(descr "LED SMD 0603 Green")
		(tags "LED SMD 0603 Green")
		(property "Reference" "D26"
			(at -1.2 0.5 90)
			(layer "F.SilkS")
			(effects
				(font
					(size 0.7 0.7)
					(thickness 0.15)
				)
				(justify right bottom)
			)
		)
		(property "Value" "LED_G_0603_LTST-C190GKT"
			(at -0.001 1.599 90)
			(layer "F.Fab")
			(effects
				(font
					(size 0.7 0.7)
					(thickness 0.15)
				)
				(justify right bottom)
			)
		)
		(property "Footprint" "antmicro-footprints:LED_0603_1608Metric_G"
			(at 0 0 -90)
			(layer "F.Fab")
			(hide yes)
			(effects
				(font
					(size 1.27 1.27)
					(thickness 0.15)
				)
			)
		)
		(property "Datasheet" "https://media.digikey.com/pdf/Data%20Sheets/Lite-On%20PDFs/LTST-C190GKT.pdf"
			(at 0 0 -90)
			(layer "F.Fab")
			(hide yes)
			(effects
				(font
					(size 1.27 1.27)
					(thickness 0.15)
				)
			)
		)
		(property "Author" "Antmicro"
			(at 7.5 261.9 0)
			(layer "F.Fab")
			(hide yes)
			(effects
				(font
					(size 1 1)
					(thickness 0.15)
				)
			)
		)
		(property "Color" "Green"
			(at 7.5 261.9 0)
			(layer "F.Fab")
			(hide yes)
			(effects
				(font
					(size 1 1)
					(thickness 0.15)
				)
			)
		)
		(property "License" "Apache-2.0"
			(at 7.5 261.9 0)
			(layer "F.Fab")
			(hide yes)
			(effects
				(font
					(size 1 1)
					(thickness 0.15)
				)
			)
		)
		(property "MPN" "LTST-C190GKT"
			(at 7.5 261.9 0)
			(layer "F.Fab")
			(hide yes)
			(effects
				(font
					(size 1 1)
					(thickness 0.15)
				)
			)
		)
		(property "Manufacturer" "Lite-On"
			(at 7.5 261.9 0)
			(layer "F.Fab")
			(hide yes)
			(effects
				(font
					(size 1 1)
					(thickness 0.15)
				)
			)
		)
		(sheetname "Peripherals")
		(sheetfile "peripherals.kicad_sch")
		(attr smd)
		(fp_line
			(start 0.22 0.35)
			(end -0.22 0.35)
			(stroke
				(width 0.15)
				(type solid)
			)
			(layer "F.SilkS")
		)
		(fp_line
			(start -0.094672 0.201008)
			(end -0.094672 -0.198992)
			(stroke
				(width 0.1)
				(type solid)
			)
			(layer "F.SilkS")
		)
		(fp_line
			(start 0.105328 0.201008)
			(end -0.094672 0.001008)
			(stroke
				(width 0.1)
				(type solid)
			)
			(layer "F.SilkS")
		)
		(fp_line
			(start 0.105328 0.201008)
			(end 0.105328 -0.198992)
			(stroke
				(width 0.1)
				(type solid)
			)
			(layer "F.SilkS")
		)
		(fp_line
			(start -0.094672 0.001008)
			(end -0.24 0.001008)
			(stroke
				(width 0.1)
				(type solid)
			)
			(layer "F.SilkS")
		)
		(fp_line
			(start -0.094672 0.001008)
			(end 0.105328 -0.198992)
			(stroke
				(width 0.1)
				(type solid)
			)
			(layer "F.SilkS")
		)
		(fp_line
			(start 0.105328 0.001008)
			(end 0.24 0.001)
			(stroke
				(width 0.1)
				(type solid)
			)
			(layer "F.SilkS")
		)
		(fp_line
			(start -1.18 -0.319)
			(end -1.18 0.321)
			(stroke
				(width 0.15)
				(type solid)
			)
			(layer "F.SilkS")
		)
		(fp_line
			(start 0.22 -0.35)
			(end -0.22 -0.35)
			(stroke
				(width 0.15)
				(type solid)
			)
			(layer "F.SilkS")
		)
		(fp_rect
			(start 1.25 0.65)
			(end -1.25 -0.65)
			(stroke
				(width 0.05)
				(type solid)
			)
			(fill none)
			(layer "F.CrtYd")
		)
		(fp_line
			(start -0.199 0.2)
			(end -0.199 0.1)
			(stroke
				(width 0.15)
				(type solid)
			)
			(layer "F.Fab")
		)
		(fp_line
			(start 0.201 0.2)
			(end 0.201 0)
			(stroke
				(width 0.15)
				(type solid)
			)
			(layer "F.Fab")
		)
		(fp_line
			(start -0.199 0)
			(end -0.597 0)
			(stroke
				(width 0.15)
				(type solid)
			)
			(layer "F.Fab")
		)
		(fp_line
			(start -0.101 0)
			(end 0.201 0.2)
			(stroke
				(width 0.15)
				(type solid)
			)
			(layer "F.Fab")
		)
		(fp_line
			(start 0.201 0)
			(end 0.201 -0.202)
			(stroke
				(width 0.15)
				(type solid)
			)
			(layer "F.Fab")
		)
		(fp_line
			(start 0.599 0)
			(end 0.201 0)
			(stroke
				(width 0.15)
				(type solid)
			)
			(layer "F.Fab")
		)
		(fp_line
			(start -0.199 -0.202)
			(end -0.199 0.1)
			(stroke
				(width 0.15)
				(type solid)
			)
			(layer "F.Fab")
		)
		(fp_line
			(start 0.201 -0.202)
			(end -0.101 0)
			(stroke
				(width 0.15)
				(type solid)
			)
			(layer "F.Fab")
		)
		(fp_rect
			(start 0.848 0.4)
			(end -0.85 -0.402)
			(stroke
				(width 0.15)
				(type solid)
			)
			(fill none)
			(layer "F.Fab")
		)
		(fp_text user "License: Apache-2.0"
			(at -1.4224 3.599 90)
			(layer "F.Fab")
			(hide yes)
			(effects
				(font
					(size 0.7 0.7)
					(thickness 0.15)
				)
				(justify right bottom)
			)
		)
		(fp_text user "Author: Antmicro"
			(at -1.4224 4.799 90)
			(layer "F.Fab")
			(hide yes)
			(effects
				(font
					(size 0.7 0.7)
					(thickness 0.15)
				)
				(justify right bottom)
			)
		)
		(fp_text user "${REFERENCE}"
			(at -1.4224 5.999 90)
			(layer "F.Fab")
			(hide yes)
			(effects
				(font
					(size 0.7 0.7)
					(thickness 0.15)
				)
				(justify right bottom)
			)
		)
		(pad "1" smd roundrect
			(at -0.7 0 90)
			(size 0.8 1)
			(layers "F.Cu" "F.Paste" "F.Mask")
			(roundrect_rratio 0.2)
			(net 164 "Net-(D26-C)")
			(pinfunction "C")
			(pintype "passive")
		)
		(pad "2" smd roundrect
			(at 0.7 0 90)
			(size 0.8 1)
			(layers "F.Cu" "F.Paste" "F.Mask")
			(roundrect_rratio 0.2)
			(net 180 "Net-(D26-A)")
			(pinfunction "A")
			(pintype "passive")
		)
	)
	(footprint "antmicro-footprints:R_Array_4x0201_Panasonic_EXB18V"
		(layer "F.Cu")
		(at 107.87 98.24 -90)
		(property "Reference" "R51"
			(at -0.84 -0.43 90)
			(layer "F.SilkS")
			(effects
				(font
					(size 0.7 0.7)
					(thickness 0.15)
				)
				(justify left bottom)
			)
		)
		(property "Value" "R_4x0R_0201_array"
			(at -1.1 1.8 -90)
			(layer "F.Fab")
			(effects
				(font
					(size 0.7 0.7)
					(thickness 0.15)
				)
				(justify left bottom)
			)
		)
		(property "Footprint" "antmicro-footprints:R_Array_4x0201_Panasonic_EXB18V"
			(at 0 0 -90)
			(layer "F.Fab")
			(hide yes)
			(effects
				(font
					(size 1.27 1.27)
					(thickness 0.15)
				)
			)
		)
		(property "Datasheet" "http://industrial.panasonic.com/cdbs/www-data/pdf/AOC0000/AOC0000C14.pdf"
			(at 0 0 -90)
			(layer "F.Fab")
			(hide yes)
			(effects
				(font
					(size 1.27 1.27)
					(thickness 0.15)
				)
			)
		)
		(property "Author" "Antmicro"
			(at 9.63 206.11 0)
			(layer "F.Fab")
			(hide yes)
			(effects
				(font
					(size 1 1)
					(thickness 0.15)
				)
			)
		)
		(property "License" "Apache-2.0"
			(at 9.63 206.11 0)
			(layer "F.Fab")
			(hide yes)
			(effects
				(font
					(size 1 1)
					(thickness 0.15)
				)
			)
		)
		(property "MPN" "EXB-18VR000X"
			(at 9.63 206.11 0)
			(layer "F.Fab")
			(hide yes)
			(effects
				(font
					(size 1 1)
					(thickness 0.15)
				)
			)
		)
		(property "Manufacturer" "Panasonic"
			(at 9.63 206.11 0)
			(layer "F.Fab")
			(hide yes)
			(effects
				(font
					(size 1 1)
					(thickness 0.15)
				)
			)
		)
		(property "Val" "4x0R_0201"
			(at 9.63 206.11 0)
			(layer "F.Fab")
			(hide yes)
			(effects
				(font
					(size 1 1)
					(thickness 0.15)
				)
			)
		)
		(sheetname "CSI")
		(sheetfile "csi.kicad_sch")
		(attr smd)
		(fp_line
			(start -0.8 -0.45)
			(end -0.8 0.45)
			(stroke
				(width 0.12)
				(type solid)
			)
			(layer "F.SilkS")
		)
		(fp_line
			(start 0.8 -0.45)
			(end 0.8 0.45)
			(stroke
				(width 0.12)
				(type solid)
			)
			(layer "F.SilkS")
		)
		(fp_rect
			(start -0.898 -0.66)
			(end 0.898 0.65)
			(stroke
				(width 0.05)
				(type solid)
			)
			(fill none)
			(layer "F.CrtYd")
		)
		(fp_text user "License: Apache-2.0"
			(at -1.051 6 -90)
			(layer "F.Fab")
			(hide yes)
			(effects
				(font
					(size 0.7 0.7)
					(thickness 0.15)
				)
				(justify left bottom)
			)
		)
		(fp_text user "Author: Antmicro"
			(at -1.051 4.599 -90)
			(layer "F.Fab")
			(hide yes)
			(effects
				(font
					(size 0.7 0.7)
					(thickness 0.15)
				)
				(justify left bottom)
			)
		)
		(fp_text user "${REFERENCE}"
			(at -1.051 3.2 -90)
			(layer "F.Fab")
			(hide yes)
			(effects
				(font
					(size 0.7 0.7)
					(thickness 0.15)
				)
				(justify left bottom)
			)
		)
		(pad "1" smd roundrect
			(at -0.6 0.298 270)
			(size 0.2 0.4)
			(layers "F.Cu" "F.Paste" "F.Mask")
			(roundrect_rratio 0.25)
			(net 331 "/CSI/SDA_CAM2")
			(pinfunction "R1.1")
			(pintype "passive")
		)
		(pad "2" smd roundrect
			(at -0.202 0.298 270)
			(size 0.2 0.4)
			(layers "F.Cu" "F.Paste" "F.Mask")
			(roundrect_rratio 0.25)
			(net 333 "/CSI/SCL_CAM2")
			(pinfunction "R2.1")
			(pintype "passive")
		)
		(pad "3" smd roundrect
			(at 0.2 0.298 270)
			(size 0.2 0.4)
			(layers "F.Cu" "F.Paste" "F.Mask")
			(roundrect_rratio 0.25)
			(net 336 "/CSI/SDA_CAM3")
			(pinfunction "R3.1")
			(pintype "passive")
		)
		(pad "4" smd roundrect
			(at 0.598 0.298 270)
			(size 0.2 0.4)
			(layers "F.Cu" "F.Paste" "F.Mask")
			(roundrect_rratio 0.25)
			(net 337 "/CSI/SCL_CAM3")
			(pinfunction "R4.1")
			(pintype "passive")
		)
		(pad "5" smd roundrect
			(at 0.598 -0.3 270)
			(size 0.2 0.4)
			(layers "F.Cu" "F.Paste" "F.Mask")
			(roundrect_rratio 0.25)
			(net 603 "Net-(R51-R4.2)")
			(pinfunction "R4.2")
			(pintype "passive")
		)
		(pad "6" smd roundrect
			(at 0.2 -0.3 270)
			(size 0.2 0.4)
			(layers "F.Cu" "F.Paste" "F.Mask")
			(roundrect_rratio 0.25)
			(net 602 "Net-(R51-R3.2)")
			(pinfunction "R3.2")
			(pintype "passive")
		)
		(pad "7" smd roundrect
			(at -0.202 -0.3 270)
			(size 0.2 0.4)
			(layers "F.Cu" "F.Paste" "F.Mask")
			(roundrect_rratio 0.25)
			(net 577 "Net-(R51-R2.2)")
			(pinfunction "R2.2")
			(pintype "passive")
		)
		(pad "8" smd roundrect
			(at -0.6 -0.3 270)
			(size 0.2 0.4)
			(layers "F.Cu" "F.Paste" "F.Mask")
			(roundrect_rratio 0.25)
			(net 575 "Net-(R51-R1.2)")
			(pinfunction "R1.2")
			(pintype "passive")
		)
	)
	(footprint "antmicro-footprints:USB-C_Receptacle_WE_632723300011"
		(layer "F.Cu")
		(at 74.75 123.75)
		(property "Reference" "J4"
			(at 3.06 -5.33 0)
			(layer "F.SilkS")
			(effects
				(font
					(size 0.7 0.7)
					(thickness 0.15)
				)
				(justify left bottom)
			)
		)
		(property "Value" "USB-C_WE_632723300011"
			(at 6.03 6.14 90)
			(layer "F.Fab")
			(effects
				(font
					(size 0.7 0.7)
					(thickness 0.15)
				)
				(justify left bottom)
			)
		)
		(property "Footprint" "antmicro-footprints:USB-C_Receptacle_WE_632723300011"
			(at 0 0 0)
			(layer "F.Fab")
			(hide yes)
			(effects
				(font
					(size 1.27 1.27)
					(thickness 0.15)
				)
			)
		)
		(property "Datasheet" "https://www.we-online.com/components/products/datasheet/632723300011.pdf"
			(at 0 0 0)
			(layer "F.Fab")
			(hide yes)
			(effects
				(font
					(size 1.27 1.27)
					(thickness 0.15)
				)
			)
		)
		(property "Author" "Antmicro"
			(at 0 0 0)
			(layer "F.Fab")
			(hide yes)
			(effects
				(font
					(size 1 1)
					(thickness 0.15)
				)
			)
		)
		(property "License" "Apache-2.0"
			(at 0 0 0)
			(layer "F.Fab")
			(hide yes)
			(effects
				(font
					(size 1 1)
					(thickness 0.15)
				)
			)
		)
		(property "MPN" "632723300011"
			(at 0 0 0)
			(layer "F.Fab")
			(hide yes)
			(effects
				(font
					(size 1 1)
					(thickness 0.15)
				)
			)
		)
		(property "Manufacturer" "Würth Elektronik"
			(at 0 0 0)
			(layer "F.Fab")
			(hide yes)
			(effects
				(font
					(size 1 1)
					(thickness 0.15)
				)
			)
		)
		(sheetname "USB Debug, DP")
		(sheetfile "usb.kicad_sch")
		(attr smd)
		(fp_line
			(start -4.4 -4.899)
			(end -4.4 -4.2)
			(stroke
				(width 0.15)
				(type solid)
			)
			(layer "F.SilkS")
		)
		(fp_line
			(start -4.4 -4.899)
			(end -2.999 -4.899)
			(stroke
				(width 0.15)
				(type solid)
			)
			(layer "F.SilkS")
		)
		(fp_line
			(start -4.4 -2.2)
			(end -4.4 0.6)
			(stroke
				(width 0.15)
				(type solid)
			)
			(layer "F.SilkS")
		)
		(fp_line
			(start -4.4 2.4)
			(end -4.4 3.201)
			(stroke
				(width 0.15)
				(type solid)
			)
			(layer "F.SilkS")
		)
		(fp_line
			(start 3 -4.899)
			(end 4.401 -4.899)
			(stroke
				(width 0.15)
				(type solid)
			)
			(layer "F.SilkS")
		)
		(fp_line
			(start 4.401 -4.2)
			(end 4.401 -4.899)
			(stroke
				(width 0.15)
				(type solid)
			)
			(layer "F.SilkS")
		)
		(fp_line
			(start 4.401 -2.2)
			(end 4.401 0.6)
			(stroke
				(width 0.15)
				(type solid)
			)
			(layer "F.SilkS")
		)
		(fp_line
			(start 4.401 2.4)
			(end 4.401 3.201)
			(stroke
				(width 0.15)
				(type solid)
			)
			(layer "F.SilkS")
		)
		(fp_circle
			(center -3.299 -5.598)
			(end -3.249 -5.598)
			(stroke
				(width 0.15)
				(type solid)
			)
			(fill solid)
			(layer "F.SilkS")
		)
		(fp_line
			(start -4.9 -5.4)
			(end -3.4 -5.4)
			(stroke
				(width 0.05)
				(type solid)
			)
			(layer "F.CrtYd")
		)
		(fp_line
			(start -4.9 6.5)
			(end -4.9 -5.4)
			(stroke
				(width 0.05)
				(type solid)
			)
			(layer "F.CrtYd")
		)
		(fp_line
			(start -3.4 -6.6)
			(end 3.4 -6.6)
			(stroke
				(width 0.05)
				(type solid)
			)
			(layer "F.CrtYd")
		)
		(fp_line
			(start -3.4 -5.4)
			(end -3.4 -6.6)
			(stroke
				(width 0.05)
				(type solid)
			)
			(layer "F.CrtYd")
		)
		(fp_line
			(start 3.4 -6.6)
			(end 3.4 -5.4)
			(stroke
				(width 0.05)
				(type solid)
			)
			(layer "F.CrtYd")
		)
		(fp_line
			(start 3.4 -5.4)
			(end 4.9 -5.4)
			(stroke
				(width 0.05)
				(type solid)
			)
			(layer "F.CrtYd")
		)
		(fp_line
			(start 4.9 -5.4)
			(end 4.9 6.5)
			(stroke
				(width 0.05)
				(type solid)
			)
			(layer "F.CrtYd")
		)
		(fp_line
			(start 4.9 6.5)
			(end -4.9 6.5)
			(stroke
				(width 0.05)
				(type solid)
			)
			(layer "F.CrtYd")
		)
		(fp_line
			(start -4.499 -5)
			(end -4.499 6.001)
			(stroke
				(width 0.15)
				(type solid)
			)
			(layer "F.Fab")
		)
		(fp_line
			(start -4.499 6.001)
			(end 4.499 6.001)
			(stroke
				(width 0.15)
				(type solid)
			)
			(layer "F.Fab")
		)
		(fp_line
			(start -2.999 -6.3)
			(end -2.999 -5)
			(stroke
				(width 0.15)
				(type solid)
			)
			(layer "F.Fab")
		)
		(fp_line
			(start -2.999 -5)
			(end -4.499 -5)
			(stroke
				(width 0.15)
				(type solid)
			)
			(layer "F.Fab")
		)
		(fp_line
			(start -2.979 -6.158)
			(end -2.859 -6.278)
			(stroke
				(width 0.15)
				(type solid)
			)
			(layer "F.Fab")
		)
		(fp_line
			(start 3 -6.3)
			(end -2.999 -6.3)
			(stroke
				(width 0.15)
				(type solid)
			)
			(layer "F.Fab")
		)
		(fp_line
			(start 3 -5)
			(end 3 -6.3)
			(stroke
				(width 0.15)
				(type solid)
			)
			(layer "F.Fab")
		)
		(fp_line
			(start 4.499 -5)
			(end 3 -5)
			(stroke
				(width 0.15)
				(type solid)
			)
			(layer "F.Fab")
		)
		(fp_line
			(start 4.499 6.001)
			(end 4.499 -5)
			(stroke
				(width 0.15)
				(type solid)
			)
			(layer "F.Fab")
		)
		(fp_text user "Author: Antmicro"
			(at -5.272 10.895 0)
			(layer "F.Fab")
			(hide yes)
			(effects
				(font
					(size 0.7 0.7)
					(thickness 0.15)
				)
				(justify left bottom)
			)
		)
		(fp_text user "License: Apache-2.0"
			(at -5.272 8.495 0)
			(layer "F.Fab")
			(hide yes)
			(effects
				(font
					(size 0.7 0.7)
					(thickness 0.15)
				)
				(justify left bottom)
			)
		)
		(fp_text user "${REFERENCE}"
			(at -5.272 9.695 0)
			(layer "F.Fab")
			(hide yes)
			(effects
				(font
					(size 0.7 0.7)
					(thickness 0.15)
				)
				(justify left bottom)
			)
		)
		(pad "" smd roundrect
			(at 0 -1.055)
			(size 0.2 1)
			(layers "F.Cu" "F.Paste" "F.Mask")
			(roundrect_rratio 0.25)
		)
		(pad "" smd roundrect
			(at 0 2.045)
			(size 0.2 1)
			(layers "F.Cu" "F.Paste" "F.Mask")
			(roundrect_rratio 0.25)
		)
		(pad "A1" smd roundrect
			(at -2.75 -5.635)
			(size 0.3 1.2)
			(layers "F.Cu" "F.Paste" "F.Mask")
			(roundrect_rratio 0.25)
			(net 1 "GND")
			(pinfunction "GND")
			(pintype "power_in")
		)
		(pad "A2" smd roundrect
			(at -2.25 -5.635)
			(size 0.3 1.2)
			(layers "F.Cu" "F.Paste" "F.Mask")
			(roundrect_rratio 0.25)
			(net 258 "/USB Debug, DP/USBC0_CONN_TX1_P")
			(pinfunction "TX_{1}+")
			(pintype "bidirectional")
		)
		(pad "A3" smd roundrect
			(at -1.75 -5.635)
			(size 0.3 1.2)
			(layers "F.Cu" "F.Paste" "F.Mask")
			(roundrect_rratio 0.25)
			(net 198 "/USB Debug, DP/USBC0_CONN_TX1_N")
			(pinfunction "TX_{1}-")
			(pintype "bidirectional")
		)
		(pad "A4" smd roundrect
			(at -1.25 -5.635)
			(size 0.3 1.2)
			(layers "F.Cu" "F.Paste" "F.Mask")
			(roundrect_rratio 0.25)
			(net 261 "/USB Debug, DP/USBC0_VBUS")
			(pinfunction "VBUS")
			(pintype "passive")
		)
		(pad "A5" smd roundrect
			(at -0.75 -5.635)
			(size 0.3 1.2)
			(layers "F.Cu" "F.Paste" "F.Mask")
			(roundrect_rratio 0.25)
			(net 277 "/USB Debug, DP/USBC0_CC1")
			(pinfunction "CC_{1}")
			(pintype "bidirectional")
		)
		(pad "A6" smd roundrect
			(at -0.25 -5.635)
			(size 0.3 1.2)
			(layers "F.Cu" "F.Paste" "F.Mask")
			(roundrect_rratio 0.25)
			(net 439 "USB2_D_P")
			(pinfunction "D_{A}+")
			(pintype "bidirectional")
		)
		(pad "A7" smd roundrect
			(at 0.25 -5.635)
			(size 0.3 1.2)
			(layers "F.Cu" "F.Paste" "F.Mask")
			(roundrect_rratio 0.25)
			(net 437 "USB2_D_N")
			(pinfunction "D_{A}-")
			(pintype "bidirectional")
		)
		(pad "A8" smd roundrect
			(at 0.75 -5.635)
			(size 0.3 1.2)
			(layers "F.Cu" "F.Paste" "F.Mask")
			(roundrect_rratio 0.25)
			(net 615 "/USB Debug, DP/USBC0_SBU_N")
			(pinfunction "SBU_{1}")
			(pintype "bidirectional")
		)
		(pad "A9" smd roundrect
			(at 1.25 -5.635)
			(size 0.3 1.2)
			(layers "F.Cu" "F.Paste" "F.Mask")
			(roundrect_rratio 0.25)
			(net 261 "/USB Debug, DP/USBC0_VBUS")
			(pinfunction "VBUS")
			(pintype "passive")
		)
		(pad "A10" smd roundrect
			(at 1.75 -5.635)
			(size 0.3 1.2)
			(layers "F.Cu" "F.Paste" "F.Mask")
			(roundrect_rratio 0.25)
			(net 125 "/USB Debug, DP/USBC0_RX2_N")
			(pinfunction "RX_{2}-")
			(pintype "bidirectional")
		)
		(pad "A11" smd roundrect
			(at 2.25 -5.635)
			(size 0.3 1.2)
			(layers "F.Cu" "F.Paste" "F.Mask")
			(roundrect_rratio 0.25)
			(net 151 "/USB Debug, DP/USBC0_RX2_P")
			(pinfunction "RX_{2}+")
			(pintype "bidirectional")
		)
		(pad "A12" smd roundrect
			(at 2.75 -5.635)
			(size 0.3 1.2)
			(layers "F.Cu" "F.Paste" "F.Mask")
			(roundrect_rratio 0.25)
			(net 1 "GND")
			(pinfunction "GND")
			(pintype "passive")
		)
		(pad "B1" thru_hole circle
			(at 2.8 -4.385)
			(size 0.65 0.65)
			(drill 0.3)
			(layers "*.Cu" "*.Mask")
			(remove_unused_layers no)
			(net 1 "GND")
			(pinfunction "GND")
			(pintype "passive")
		)
		(pad "B2" thru_hole circle
			(at 2.4 -3.685)
			(size 0.65 0.65)
			(drill 0.3)
			(layers "*.Cu" "*.Mask")
			(remove_unused_layers no)
			(net 260 "/USB Debug, DP/USBC0_CONN_TX2_P")
			(pinfunction "TX_{2}+")
			(pintype "bidirectional")
		)
		(pad "B3" thru_hole circle
			(at 1.6 -3.685)
			(size 0.65 0.65)
			(drill 0.3)
			(layers "*.Cu" "*.Mask")
			(remove_unused_layers no)
			(net 201 "/USB Debug, DP/USBC0_CONN_TX2_N")
			(pinfunction "TX_{2}-")
			(pintype "bidirectional")
		)
		(pad "B4" thru_hole circle
			(at 1.2 -4.385)
			(size 0.65 0.65)
			(drill 0.3)
			(layers "*.Cu" "*.Mask")
			(remove_unused_layers no)
			(net 261 "/USB Debug, DP/USBC0_VBUS")
			(pinfunction "VBUS")
			(pintype "passive")
		)
		(pad "B5" thru_hole circle
			(at 0.8 -3.685)
			(size 0.65 0.65)
			(drill 0.3)
			(layers "*.Cu" "*.Mask")
			(remove_unused_layers no)
			(net 278 "/USB Debug, DP/USBC0_CC2")
			(pinfunction "CC_{2}")
			(pintype "bidirectional")
		)
		(pad "B6" thru_hole circle
			(at 0.4 -4.385)
			(size 0.65 0.65)
			(drill 0.3)
			(layers "*.Cu" "*.Mask")
			(remove_unused_layers no)
			(net 439 "USB2_D_P")
			(pinfunction "D_{B}+")
			(pintype "bidirectional")
		)
		(pad "B7" thru_hole circle
			(at -0.4 -4.385)
			(size 0.65 0.65)
			(drill 0.3)
			(layers "*.Cu" "*.Mask")
			(remove_unused_layers no)
			(net 437 "USB2_D_N")
			(pinfunction "D_{B}-")
			(pintype "bidirectional")
		)
		(pad "B8" thru_hole circle
			(at -0.8 -3.685)
			(size 0.65 0.65)
			(drill 0.3)
			(layers "*.Cu" "*.Mask")
			(remove_unused_layers no)
			(net 614 "/USB Debug, DP/USBC0_SBU_P")
			(pinfunction "SBU_{2}")
			(pintype "bidirectional")
		)
		(pad "B9" thru_hole circle
			(at -1.2 -4.385)
			(size 0.65 0.65)
			(drill 0.3)
			(layers "*.Cu" "*.Mask")
			(remove_unused_layers no)
			(net 261 "/USB Debug, DP/USBC0_VBUS")
			(pinfunction "VBUS")
			(pintype "passive")
		)
		(pad "B10" thru_hole circle
			(at -1.6 -3.685)
			(size 0.65 0.65)
			(drill 0.3)
			(layers "*.Cu" "*.Mask")
			(remove_unused_layers no)
			(net 152 "/USB Debug, DP/USBC0_RX1_N")
			(pinfunction "RX_{1}-")
			(pintype "bidirectional")
		)
		(pad "B11" thru_hole circle
			(at -2.4 -3.685)
			(size 0.65 0.65)
			(drill 0.3)
			(layers "*.Cu" "*.Mask")
			(remove_unused_layers no)
			(net 154 "/USB Debug, DP/USBC0_RX1_P")
			(pinfunction "RX_{1}+")
			(pintype "bidirectional")
		)
		(pad "B12" thru_hole circle
			(at -2.8 -4.385)
			(size 0.65 0.65)
			(drill 0.3)
			(layers "*.Cu" "*.Mask")
			(remove_unused_layers no)
			(net 1 "GND")
			(pinfunction "GND")
			(pintype "passive")
		)
		(pad "SH" thru_hole oval
			(at -4.27 -3.235)
			(size 1 1.6)
			(drill oval 0.6 1.2)
			(layers "*.Cu" "*.Mask")
			(remove_unused_layers no)
			(net 1 "GND")
			(pinfunction "SH")
			(pintype "passive")
		)
		(pad "SH" thru_hole oval
			(at -4.27 1.495)
			(size 1 1.6)
			(drill oval 0.6 1.2)
			(layers "*.Cu" "*.Mask")
			(remove_unused_layers no)
			(net 1 "GND")
			(pinfunction "SH")
			(pintype "passive")
		)
		(pad "SH" thru_hole circle
			(at -2 -4.385)
			(size 0.65 0.65)
			(drill 0.3)
			(layers "*.Cu" "*.Mask")
			(remove_unused_layers no)
			(net 1 "GND")
			(pinfunction "SH")
			(pintype "passive")
		)
		(pad "SH" thru_hole circle
			(at 2 -4.385)
			(size 0.65 0.65)
			(drill 0.3)
			(layers "*.Cu" "*.Mask")
			(remove_unused_layers no)
			(net 1 "GND")
			(pinfunction "SH")
			(pintype "passive")
		)
		(pad "SH" thru_hole oval
			(at 4.27 -3.235)
			(size 1 1.6)
			(drill oval 0.6 1.2)
			(layers "*.Cu" "*.Mask")
			(remove_unused_layers no)
			(net 1 "GND")
			(pinfunction "SH")
			(pintype "passive")
		)
		(pad "SH" thru_hole oval
			(at 4.27 1.495)
			(size 1 1.6)
			(drill oval 0.6 1.2)
			(layers "*.Cu" "*.Mask")
			(remove_unused_layers no)
			(net 1 "GND")
			(pinfunction "SH")
			(pintype "passive")
		)
	)
	(footprint "antmicro-footprints:C_0402_1005Metric"
		(layer "F.Cu")
		(at 54.81 89.625 90)
		(descr "Capacitor SMD 0402")
		(tags "capacitor SMD 0402")
		(property "Reference" "C161"
			(at -1.135 -0.6 90)
			(layer "F.SilkS")
			(effects
				(font
					(size 0.7 0.7)
					(thickness 0.15)
				)
				(justify left bottom)
			)
		)
		(property "Value" "C_1n_16V_X7R_0402"
			(at -1.022927 2.155213 90)
			(layer "F.Fab")
			(effects
				(font
					(size 0.7 0.7)
					(thickness 0.15)
				)
				(justify left bottom)
			)
		)
		(property "Footprint" "antmicro-footprints:C_0402_1005Metric"
			(at 0 0 90)
			(layer "F.Fab")
			(hide yes)
			(effects
				(font
					(size 1.27 1.27)
					(thickness 0.15)
				)
			)
		)
		(property "Datasheet" "https://www.kemet.com/en/us/capacitors/product/C0402C102J4RACTU.html"
			(at 0 0 90)
			(layer "F.Fab")
			(hide yes)
			(effects
				(font
					(size 1.27 1.27)
					(thickness 0.15)
				)
			)
		)
		(property "Description" "SMD Multilayer Ceramic Capacitor, 1nF, 16V, 0402, ±5%, X7R"
			(at 0 0 90)
			(layer "F.Fab")
			(hide yes)
			(effects
				(font
					(size 1.27 1.27)
					(thickness 0.15)
				)
			)
		)
		(property "MPN" "C0402C102J4RACTU"
			(at 0 0 90)
			(unlocked yes)
			(layer "F.Fab")
			(hide yes)
			(effects
				(font
					(size 1 1)
					(thickness 0.15)
				)
			)
		)
		(property "Val" "1n"
			(at 0 0 90)
			(unlocked yes)
			(layer "F.Fab")
			(hide yes)
			(effects
				(font
					(size 1 1)
					(thickness 0.15)
				)
			)
		)
		(property "Voltage" "16V"
			(at 0 0 90)
			(unlocked yes)
			(layer "F.Fab")
			(hide yes)
			(effects
				(font
					(size 1 1)
					(thickness 0.15)
				)
			)
		)
		(property "Dielectric" "X7R"
			(at 0 0 90)
			(unlocked yes)
			(layer "F.Fab")
			(hide yes)
			(effects
				(font
					(size 1 1)
					(thickness 0.15)
				)
			)
		)
		(property "Manufacturer" "KEMET"
			(at 0 0 90)
			(unlocked yes)
			(layer "F.Fab")
			(hide yes)
			(effects
				(font
					(size 1 1)
					(thickness 0.15)
				)
			)
		)
		(property "License" "Apache-2.0"
			(at 0 0 90)
			(unlocked yes)
			(layer "F.Fab")
			(hide yes)
			(effects
				(font
					(size 1 1)
					(thickness 0.15)
				)
			)
		)
		(property "Author" "Antmicro"
			(at 0 0 90)
			(unlocked yes)
			(layer "F.Fab")
			(hide yes)
			(effects
				(font
					(size 1 1)
					(thickness 0.15)
				)
			)
		)
		(sheetname "Supply")
		(sheetfile "supply.kicad_sch")
		(attr smd)
		(fp_rect
			(start -0.925 -0.47)
			(end 0.925 0.47)
			(stroke
				(width 0.05)
				(type default)
			)
			(fill none)
			(layer "F.CrtYd")
		)
		(fp_line
			(start 0.504 -0.25)
			(end 0.504 0.248)
			(stroke
				(width 0.15)
				(type solid)
			)
			(layer "F.Fab")
		)
		(fp_line
			(start -0.494 -0.25)
			(end 0.504 -0.25)
			(stroke
				(width 0.15)
				(type solid)
			)
			(layer "F.Fab")
		)
		(fp_line
			(start 0.504 0.248)
			(end -0.494 0.248)
			(stroke
				(width 0.15)
				(type solid)
			)
			(layer "F.Fab")
		)
		(fp_line
			(start -0.494 0.248)
			(end -0.494 -0.25)
			(stroke
				(width 0.15)
				(type solid)
			)
			(layer "F.Fab")
		)
		(fp_text user "${REFERENCE}"
			(at -0.939 4.599 90)
			(layer "F.Fab")
			(hide yes)
			(effects
				(font
					(size 0.7 0.7)
					(thickness 0.15)
				)
				(justify left bottom)
			)
		)
		(fp_text user "Author: Antmicro"
			(at -0.939 3.399 90)
			(layer "F.Fab")
			(hide yes)
			(effects
				(font
					(size 0.7 0.7)
					(thickness 0.15)
				)
				(justify left bottom)
			)
		)
		(fp_text user "License: Apache-2.0"
			(at -0.939 5.799 90)
			(layer "F.Fab")
			(hide yes)
			(effects
				(font
					(size 0.7 0.7)
					(thickness 0.15)
				)
				(justify left bottom)
			)
		)
		(pad "1" smd roundrect
			(at -0.48 0 90)
			(size 0.59 0.64)
			(layers "F.Cu" "F.Paste" "F.Mask")
			(roundrect_rratio 0.25)
			(net 1 "GND")
			(pintype "passive")
		)
		(pad "2" smd roundrect
			(at 0.48 0 90)
			(size 0.59 0.64)
			(layers "F.Cu" "F.Paste" "F.Mask")
			(roundrect_rratio 0.25)
			(net 751 "Net-(U29-DVDT)")
			(pintype "passive")
		)
	)
	(footprint "antmicro-footprints:XDFN-2_1x0.60mm"
		(layer "F.Cu")
		(at 67.6 125.95 90)
		(property "Reference" "D60"
			(at 0.598 0.4 -90)
			(layer "F.SilkS")
			(effects
				(font
					(size 0.7 0.7)
					(thickness 0.15)
				)
				(justify left bottom)
			)
		)
		(property "Value" "TPD1E0B04_XDFN-2"
			(at 0 1.5 90)
			(layer "F.Fab")
			(effects
				(font
					(size 0.7 0.7)
					(thickness 0.15)
				)
				(justify left bottom)
			)
		)
		(property "Footprint" "antmicro-footprints:XDFN-2_1x0.60mm"
			(at 0 0 90)
			(layer "F.Fab")
			(hide yes)
			(effects
				(font
					(size 1.27 1.27)
					(thickness 0.15)
				)
			)
		)
		(property "Datasheet" "https://www.ti.com/general/docs/suppproductinfo.tsp?distId=26&gotoUrl=https://www.ti.com/lit/gpn/tpd1e0b04"
			(at 0 0 90)
			(layer "F.Fab")
			(hide yes)
			(effects
				(font
					(size 1.27 1.27)
					(thickness 0.15)
				)
			)
		)
		(property "MPN" "TPD1E0B04DPYR"
			(at 193.55 58.35 0)
			(layer "F.Fab")
			(hide yes)
			(effects
				(font
					(size 1 1)
					(thickness 0.15)
				)
			)
		)
		(property "Manufacturer" "Texas Instruments"
			(at 193.55 58.35 0)
			(layer "F.Fab")
			(hide yes)
			(effects
				(font
					(size 1 1)
					(thickness 0.15)
				)
			)
		)
		(property "Author" "Antmicro"
			(at 193.55 58.35 0)
			(layer "F.Fab")
			(hide yes)
			(effects
				(font
					(size 1 1)
					(thickness 0.15)
				)
			)
		)
		(property "License" "Apache-2.0"
			(at 193.55 58.35 0)
			(layer "F.Fab")
			(hide yes)
			(effects
				(font
					(size 1 1)
					(thickness 0.15)
				)
			)
		)
		(sheetname "Supply")
		(sheetfile "supply.kicad_sch")
		(attr smd)
		(fp_rect
			(start -0.725 -0.475)
			(end 0.725 0.475)
			(stroke
				(width 0.05)
				(type solid)
			)
			(fill none)
			(layer "F.CrtYd")
		)
		(fp_rect
			(start -0.55 -0.35)
			(end 0.55 0.35)
			(stroke
				(width 0.15)
				(type solid)
			)
			(fill none)
			(layer "F.Fab")
		)
		(fp_text user "License: Apache-2.0"
			(at -0.8 5.6 90)
			(layer "F.Fab")
			(hide yes)
			(effects
				(font
					(size 0.7 0.7)
					(thickness 0.15)
				)
				(justify left bottom)
			)
		)
		(fp_text user "Author: Antmicro"
			(at -0.8 4.4 90)
			(layer "F.Fab")
			(hide yes)
			(effects
				(font
					(size 0.7 0.7)
					(thickness 0.15)
				)
				(justify left bottom)
			)
		)
		(fp_text user "${REFERENCE}"
			(at -0.8 3.2 90)
			(layer "F.Fab")
			(hide yes)
			(effects
				(font
					(size 0.7 0.7)
					(thickness 0.15)
				)
				(justify left bottom)
			)
		)
		(pad "1" smd roundrect
			(at -0.351 0 90)
			(size 0.3 0.5)
			(layers "F.Cu" "F.Paste" "F.Mask")
			(roundrect_rratio 0.25)
			(net 1 "GND")
			(pinfunction "C")
			(pintype "passive")
		)
		(pad "2" smd roundrect
			(at 0.349 0 90)
			(size 0.3 0.5)
			(layers "F.Cu" "F.Paste" "F.Mask")
			(roundrect_rratio 0.25)
			(net 137 "Net-(D36-A)")
			(pinfunction "A")
			(pintype "passive")
		)
	)
	(footprint "antmicro-footprints:Conn_Molex_Nano-Fit_1x2_SMD_1054301202"
		(layer "F.Cu")
		(at 53.615 124.2105)
		(descr "Molex Nano-Fit Power Connectors, 105430-xx02, 2 Pins per row")
		(tags "connector Molex Nano-Fit")
		(property "Reference" "J12"
			(at -4.985 -4.8705 0)
			(layer "F.SilkS")
			(effects
				(font
					(size 0.7 0.7)
					(thickness 0.15)
				)
				(justify left bottom)
			)
		)
		(property "Value" "Molex_Nano-Fit_1x2_SMD_1054301202"
			(at -0.471 -30.151 0)
			(layer "F.Fab")
			(effects
				(font
					(size 0.7 0.7)
					(thickness 0.15)
				)
				(justify left bottom)
			)
		)
		(property "Footprint" "antmicro-footprints:Conn_Molex_Nano-Fit_1x2_SMD_1054301202"
			(at 0 0 0)
			(layer "F.Fab")
			(hide yes)
			(effects
				(font
					(size 1.27 1.27)
					(thickness 0.15)
				)
			)
		)
		(property "Datasheet" "https://www.farnell.com/cad/3578051.pdf"
			(at 0 0 0)
			(layer "F.Fab")
			(hide yes)
			(effects
				(font
					(size 1.27 1.27)
					(thickness 0.15)
				)
			)
		)
		(property "Author" "Antmicro"
			(at 0 0 0)
			(layer "F.Fab")
			(hide yes)
			(effects
				(font
					(size 1 1)
					(thickness 0.15)
				)
			)
		)
		(property "License" "Apache-2.0"
			(at 0 0 0)
			(layer "F.Fab")
			(hide yes)
			(effects
				(font
					(size 1 1)
					(thickness 0.15)
				)
			)
		)
		(property "MPN" "105430-1202"
			(at 0 0 0)
			(layer "F.Fab")
			(hide yes)
			(effects
				(font
					(size 1 1)
					(thickness 0.15)
				)
			)
		)
		(property "Manufacturer" "Molex"
			(at 0 0 0)
			(layer "F.Fab")
			(hide yes)
			(effects
				(font
					(size 1 1)
					(thickness 0.15)
				)
			)
		)
		(sheetname "Supply")
		(sheetfile "supply.kicad_sch")
		(attr smd)
		(fp_line
			(start -4.47 -4.5)
			(end -4.47 2.099)
			(stroke
				(width 0.15)
				(type solid)
			)
			(layer "F.SilkS")
		)
		(fp_line
			(start -4.47 2.099)
			(end -4.321 2.499)
			(stroke
				(width 0.15)
				(type solid)
			)
			(layer "F.SilkS")
		)
		(fp_line
			(start -4.321 2.499)
			(end -4.321 4.299)
			(stroke
				(width 0.15)
				(type solid)
			)
			(layer "F.SilkS")
		)
		(fp_line
			(start -4.321 4.299)
			(end 4.28 4.299)
			(stroke
				(width 0.15)
				(type solid)
			)
			(layer "F.SilkS")
		)
		(fp_line
			(start -1.72 -4.5)
			(end -4.47 -4.5)
			(stroke
				(width 0.15)
				(type solid)
			)
			(layer "F.SilkS")
		)
		(fp_line
			(start -0.22 -4.5)
			(end 0.78 -4.5)
			(stroke
				(width 0.15)
				(type solid)
			)
			(layer "F.SilkS")
		)
		(fp_line
			(start 4.28 2.698)
			(end 4.28 4.299)
			(stroke
				(width 0.15)
				(type solid)
			)
			(layer "F.SilkS")
		)
		(fp_line
			(start 4.48 -4.5)
			(end 2.68 -4.5)
			(stroke
				(width 0.15)
				(type solid)
			)
			(layer "F.SilkS")
		)
		(fp_line
			(start 4.48 2.298)
			(end 4.28 2.698)
			(stroke
				(width 0.15)
				(type solid)
			)
			(layer "F.SilkS")
		)
		(fp_line
			(start 4.48 2.298)
			(end 4.48 -4.5)
			(stroke
				(width 0.15)
				(type solid)
			)
			(layer "F.SilkS")
		)
		(fp_circle
			(center 2.428 -4.91)
			(end 2.478 -4.91)
			(stroke
				(width 0.15)
				(type solid)
			)
			(fill solid)
			(layer "F.SilkS")
		)
		(fp_rect
			(start -4.77 -6.21)
			(end 4.77 6.11)
			(stroke
				(width 0.05)
				(type solid)
			)
			(fill none)
			(layer "F.CrtYd")
		)
		(fp_text user "${REFERENCE}"
			(at 0 7.2 0)
			(layer "F.Fab")
			(hide yes)
			(effects
				(font
					(size 0.7 0.7)
					(thickness 0.15)
				)
				(justify left bottom)
			)
		)
		(fp_text user "Author: Antmicro"
			(at 0 9 0)
			(layer "F.Fab")
			(hide yes)
			(effects
				(font
					(size 0.7 0.7)
					(thickness 0.15)
				)
				(justify left bottom)
			)
		)
		(fp_text user "License: Apache-2.0"
			(at 0 10.199 0)
			(layer "F.Fab")
			(hide yes)
			(effects
				(font
					(size 0.7 0.7)
					(thickness 0.15)
				)
				(justify left bottom)
			)
		)
		(pad "1" smd roundrect
			(at 1.528 -4.901 90)
			(size 2.5 1.24)
			(layers "F.Cu" "F.Paste" "F.Mask")
			(roundrect_rratio 0.25)
			(net 189 "Net-(D28-C)")
			(pintype "passive")
		)
		(pad "2" smd roundrect
			(at -0.97 -4.901 90)
			(size 2.5 1.24)
			(layers "F.Cu" "F.Paste" "F.Mask")
			(roundrect_rratio 0.25)
			(net 1 "GND")
			(pintype "passive")
		)
		(pad "MP" smd roundrect
			(at -3.54 0.029)
			(size 1.1 8.2)
			(layers "F.Cu" "F.Paste" "F.Mask")
			(roundrect_rratio 0.25)
			(net 1 "GND")
			(pintype "passive")
		)
		(pad "MP" smd roundrect
			(at 3.499 0.029)
			(size 1.1 8.2)
			(layers "F.Cu" "F.Paste" "F.Mask")
			(roundrect_rratio 0.25)
			(net 1 "GND")
			(pintype "passive")
		)
	)
	(footprint "antmicro-footprints:R_Array_4x0201_Panasonic_EXB18V"
		(layer "F.Cu")
		(at 114.55 94.25 -90)
		(property "Reference" "R22"
			(at 1.02 0.84 90)
			(layer "F.SilkS")
			(effects
				(font
					(size 0.7 0.7)
					(thickness 0.15)
				)
				(justify left bottom)
			)
		)
		(property "Value" "R_4x0R_0201_array"
			(at -1.1 1.8 -90)
			(layer "F.Fab")
			(effects
				(font
					(size 0.7 0.7)
					(thickness 0.15)
				)
				(justify left bottom)
			)
		)
		(property "Footprint" "antmicro-footprints:R_Array_4x0201_Panasonic_EXB18V"
			(at 0 0 -90)
			(layer "F.Fab")
			(hide yes)
			(effects
				(font
					(size 1.27 1.27)
					(thickness 0.15)
				)
			)
		)
		(property "Datasheet" "http://industrial.panasonic.com/cdbs/www-data/pdf/AOC0000/AOC0000C14.pdf"
			(at 0 0 -90)
			(layer "F.Fab")
			(hide yes)
			(effects
				(font
					(size 1.27 1.27)
					(thickness 0.15)
				)
			)
		)
		(property "Author" "Antmicro"
			(at 20.3 208.8 0)
			(layer "F.Fab")
			(hide yes)
			(effects
				(font
					(size 1 1)
					(thickness 0.15)
				)
			)
		)
		(property "License" "Apache-2.0"
			(at 20.3 208.8 0)
			(layer "F.Fab")
			(hide yes)
			(effects
				(font
					(size 1 1)
					(thickness 0.15)
				)
			)
		)
		(property "MPN" "EXB-18VR000X"
			(at 20.3 208.8 0)
			(layer "F.Fab")
			(hide yes)
			(effects
				(font
					(size 1 1)
					(thickness 0.15)
				)
			)
		)
		(property "Manufacturer" "Panasonic"
			(at 20.3 208.8 0)
			(layer "F.Fab")
			(hide yes)
			(effects
				(font
					(size 1 1)
					(thickness 0.15)
				)
			)
		)
		(property "Val" "4x0R_0201"
			(at 20.3 208.8 0)
			(layer "F.Fab")
			(hide yes)
			(effects
				(font
					(size 1 1)
					(thickness 0.15)
				)
			)
		)
		(sheetname "M.2")
		(sheetfile "m-2.kicad_sch")
		(attr smd)
		(fp_line
			(start -0.8 -0.45)
			(end -0.8 0.45)
			(stroke
				(width 0.12)
				(type solid)
			)
			(layer "F.SilkS")
		)
		(fp_line
			(start 0.8 -0.45)
			(end 0.8 0.45)
			(stroke
				(width 0.12)
				(type solid)
			)
			(layer "F.SilkS")
		)
		(fp_rect
			(start -0.898 -0.66)
			(end 0.898 0.65)
			(stroke
				(width 0.05)
				(type solid)
			)
			(fill none)
			(layer "F.CrtYd")
		)
		(fp_text user "${REFERENCE}"
			(at -1.051 3.2 -90)
			(layer "F.Fab")
			(hide yes)
			(effects
				(font
					(size 0.7 0.7)
					(thickness 0.15)
				)
				(justify left bottom)
			)
		)
		(fp_text user "Author: Antmicro"
			(at -1.051 4.599 -90)
			(layer "F.Fab")
			(hide yes)
			(effects
				(font
					(size 0.7 0.7)
					(thickness 0.15)
				)
				(justify left bottom)
			)
		)
		(fp_text user "License: Apache-2.0"
			(at -1.051 6 -90)
			(layer "F.Fab")
			(hide yes)
			(effects
				(font
					(size 0.7 0.7)
					(thickness 0.15)
				)
				(justify left bottom)
			)
		)
		(pad "1" smd roundrect
			(at -0.6 0.298 270)
			(size 0.2 0.4)
			(layers "F.Cu" "F.Paste" "F.Mask")
			(roundrect_rratio 0.25)
			(net 517 "UART0_TXD")
			(pinfunction "R1.1")
			(pintype "passive")
		)
		(pad "2" smd roundrect
			(at -0.202 0.298 270)
			(size 0.2 0.4)
			(layers "F.Cu" "F.Paste" "F.Mask")
			(roundrect_rratio 0.25)
			(net 119 "UART0_CTS")
			(pinfunction "R2.1")
			(pintype "passive")
		)
		(pad "3" smd roundrect
			(at 0.2 0.298 270)
			(size 0.2 0.4)
			(layers "F.Cu" "F.Paste" "F.Mask")
			(roundrect_rratio 0.25)
			(net 118 "UART0_RTS")
			(pinfunction "R3.1")
			(pintype "passive")
		)
		(pad "4" smd roundrect
			(at 0.598 0.298 270)
			(size 0.2 0.4)
			(layers "F.Cu" "F.Paste" "F.Mask")
			(roundrect_rratio 0.25)
			(net 516 "UART0_RXD")
			(pinfunction "R4.1")
			(pintype "passive")
		)
		(pad "5" smd roundrect
			(at 0.598 -0.3 270)
			(size 0.2 0.4)
			(layers "F.Cu" "F.Paste" "F.Mask")
			(roundrect_rratio 0.25)
			(net 192 "/M.2/M2_E_UART_RX")
			(pinfunction "R4.2")
			(pintype "passive")
		)
		(pad "6" smd roundrect
			(at 0.2 -0.3 270)
			(size 0.2 0.4)
			(layers "F.Cu" "F.Paste" "F.Mask")
			(roundrect_rratio 0.25)
			(net 195 "/M.2/M2_E_UART_RTS")
			(pinfunction "R3.2")
			(pintype "passive")
		)
		(pad "7" smd roundrect
			(at -0.202 -0.3 270)
			(size 0.2 0.4)
			(layers "F.Cu" "F.Paste" "F.Mask")
			(roundrect_rratio 0.25)
			(net 199 "/M.2/M2_E_UART_CTS")
			(pinfunction "R2.2")
			(pintype "passive")
		)
		(pad "8" smd roundrect
			(at -0.6 -0.3 270)
			(size 0.2 0.4)
			(layers "F.Cu" "F.Paste" "F.Mask")
			(roundrect_rratio 0.25)
			(net 188 "/M.2/M2_E_UART_TX")
			(pinfunction "R1.2")
			(pintype "passive")
		)
	)
	(footprint "antmicro-footprints:MLP44-24L_4x4x0.75mm"
		(layer "F.Cu")
		(at 77.15 89.415)
		(property "Reference" "U40"
			(at -2.09 3.445 0)
			(layer "F.SilkS")
			(effects
				(font
					(size 0.7 0.7)
					(thickness 0.15)
				)
				(justify left bottom)
			)
		)
		(property "Value" "SIC431AED-T1-GE3"
			(at 0 3.6 0)
			(layer "F.Fab")
			(effects
				(font
					(size 0.7 0.7)
					(thickness 0.15)
				)
				(justify left bottom)
			)
		)
		(property "Footprint" "antmicro-footprints:MLP44-24L_4x4x0.75mm"
			(at 0 0 0)
			(layer "F.Fab")
			(hide yes)
			(effects
				(font
					(size 1.27 1.27)
					(thickness 0.15)
				)
			)
		)
		(property "Datasheet" "https://www.vishay.com/docs/74589/sic431.pdf"
			(at 0 0 0)
			(layer "F.Fab")
			(hide yes)
			(effects
				(font
					(size 1.27 1.27)
					(thickness 0.15)
				)
			)
		)
		(property "Author" "Antmicro"
			(at 0 0 0)
			(layer "F.Fab")
			(hide yes)
			(effects
				(font
					(size 1 1)
					(thickness 0.15)
				)
			)
		)
		(property "License" "Apache-2.0"
			(at 0 0 0)
			(layer "F.Fab")
			(hide yes)
			(effects
				(font
					(size 1 1)
					(thickness 0.15)
				)
			)
		)
		(property "MPN" "SIC431AED-T1-GE3 "
			(at 0 0 0)
			(layer "F.Fab")
			(hide yes)
			(effects
				(font
					(size 1 1)
					(thickness 0.15)
				)
			)
		)
		(property "Manufacturer" "Vishay"
			(at 0 0 0)
			(layer "F.Fab")
			(hide yes)
			(effects
				(font
					(size 1 1)
					(thickness 0.15)
				)
			)
		)
		(sheetname "Supply")
		(sheetfile "supply.kicad_sch")
		(attr smd)
		(net_tie_pad_groups "1,2,26" "3,4,27" "5,6,7,8,9")
		(fp_line
			(start -2.11 -1.38)
			(end -2.11 -2.1)
			(stroke
				(width 0.15)
				(type solid)
			)
			(layer "F.SilkS")
		)
		(fp_line
			(start -2.11 2.11)
			(end -2.11 1.39)
			(stroke
				(width 0.15)
				(type solid)
			)
			(layer "F.SilkS")
		)
		(fp_line
			(start -1.89 -2.1)
			(end -2.11 -2.1)
			(stroke
				(width 0.15)
				(type solid)
			)
			(layer "F.SilkS")
		)
		(fp_line
			(start -1.89 2.11)
			(end -2.11 2.11)
			(stroke
				(width 0.15)
				(type solid)
			)
			(layer "F.SilkS")
		)
		(fp_line
			(start 1.44 2.11)
			(end 2.11 2.11)
			(stroke
				(width 0.15)
				(type solid)
			)
			(layer "F.SilkS")
		)
		(fp_line
			(start 1.89 -2.11)
			(end 2.11 -2.11)
			(stroke
				(width 0.15)
				(type solid)
			)
			(layer "F.SilkS")
		)
		(fp_line
			(start 2.11 -2.11)
			(end 2.11 -1.69)
			(stroke
				(width 0.15)
				(type solid)
			)
			(layer "F.SilkS")
		)
		(fp_line
			(start 2.11 2.11)
			(end 2.11 1.84)
			(stroke
				(width 0.15)
				(type solid)
			)
			(layer "F.SilkS")
		)
		(fp_circle
			(center -2.25 -1.15)
			(end -2.2 -1.15)
			(stroke
				(width 0.15)
				(type solid)
			)
			(fill solid)
			(layer "F.SilkS")
		)
		(fp_line
			(start -2.55 -2.55)
			(end 2.55 -2.55)
			(stroke
				(width 0.05)
				(type solid)
			)
			(layer "F.CrtYd")
		)
		(fp_line
			(start -2.55 2.55)
			(end -2.55 -2.55)
			(stroke
				(width 0.05)
				(type solid)
			)
			(layer "F.CrtYd")
		)
		(fp_line
			(start 2.55 -2.55)
			(end 2.55 2.55)
			(stroke
				(width 0.05)
				(type solid)
			)
			(layer "F.CrtYd")
		)
		(fp_line
			(start 2.55 2.55)
			(end -2.55 2.55)
			(stroke
				(width 0.05)
				(type solid)
			)
			(layer "F.CrtYd")
		)
		(fp_line
			(start -2 -1)
			(end -2 2)
			(stroke
				(width 0.15)
				(type solid)
			)
			(layer "F.Fab")
		)
		(fp_line
			(start -2 2)
			(end 2 2)
			(stroke
				(width 0.15)
				(type solid)
			)
			(layer "F.Fab")
		)
		(fp_line
			(start -1 -2)
			(end -2 -1)
			(stroke
				(width 0.15)
				(type solid)
			)
			(layer "F.Fab")
		)
		(fp_line
			(start 2 -2)
			(end -1 -2)
			(stroke
				(width 0.15)
				(type solid)
			)
			(layer "F.Fab")
		)
		(fp_line
			(start 2 2)
			(end 2 -2)
			(stroke
				(width 0.15)
				(type solid)
			)
			(layer "F.Fab")
		)
		(fp_text user "License: Apache-2.0"
			(at -2.7 5.6 0)
			(layer "F.Fab")
			(hide yes)
			(effects
				(font
					(size 0.7 0.7)
					(thickness 0.15)
				)
				(justify left bottom)
			)
		)
		(fp_text user "License: "
			(at -2.9 5.6 0)
			(layer "F.Fab")
			(hide yes)
			(effects
				(font
					(size 0.7 0.7)
					(thickness 0.15)
				)
				(justify left bottom)
			)
		)
		(fp_text user "Author: Antmicro"
			(at -2.9 8 0)
			(layer "F.Fab")
			(hide yes)
			(effects
				(font
					(size 0.7 0.7)
					(thickness 0.15)
				)
				(justify left bottom)
			)
		)
		(fp_text user "${REFERENCE}"
			(at -2.9 6.8 0)
			(layer "F.Fab")
			(hide yes)
			(effects
				(font
					(size 0.7 0.7)
					(thickness 0.15)
				)
				(justify left bottom)
			)
		)
		(pad "1" smd roundrect
			(at -1.94 -0.825 90)
			(size 0.3 0.725)
			(layers "F.Cu" "F.Paste" "F.Mask")
			(roundrect_rratio 0.25)
			(net 115 "VCC")
			(pinfunction "V_{IN}")
			(pintype "power_in")
		)
		(pad "2" smd roundrect
			(at -1.94 -0.375 90)
			(size 0.3 0.725)
			(layers "F.Cu" "F.Paste" "F.Mask")
			(roundrect_rratio 0.25)
			(net 115 "VCC")
			(pinfunction "V_{IN}")
			(pintype "passive")
		)
		(pad "3" smd roundrect
			(at -1.94 0.525 90)
			(size 0.3 0.725)
			(layers "F.Cu" "F.Paste" "F.Mask")
			(roundrect_rratio 0.25)
			(net 1 "GND")
			(pinfunction "P_{GND}")
			(pintype "passive")
		)
		(pad "4" smd roundrect
			(at -1.94 0.975 90)
			(size 0.3 0.725)
			(layers "F.Cu" "F.Paste" "F.Mask")
			(roundrect_rratio 0.25)
			(net 1 "GND")
			(pinfunction "P_{GND}")
			(pintype "passive")
		)
		(pad "5" smd custom
			(at -1.475 1.94)
			(size 0.3 0.3)
			(layers "F.Cu" "F.Paste" "F.Mask")
			(net 643 "/Supply/3V3_SW")
			(pinfunction "SW")
			(pintype "passive")
			(options
				(clearance outline)
				(anchor circle)
			)
			(primitives
				(gr_poly
					(pts
						(xy -0.15 -0.2875) (xy -0.144291 -0.316201) (xy -0.128033 -0.340533) (xy -0.103701 -0.356791)
						(xy -0.075 -0.3625) (xy 0.075 -0.3625) (xy 0.103701 -0.356791) (xy 0.128033 -0.340533) (xy 0.144291 -0.316201)
						(xy 0.15 -0.2875) (xy 0.15 0.2875) (xy 0.144291 0.316201) (xy 0.128033 0.340533) (xy 0.103701 0.356791)
						(xy 0.075 0.3625) (xy -0.075 0.3625) (xy -0.103701 0.356791) (xy -0.128033 0.340533) (xy -0.144291 0.316201)
						(xy -0.15 0.2875)
					)
					(width 0)
					(fill yes)
				)
				(gr_poly
					(pts
						(xy -0.15 -0.3625) (xy 2.2 -0.3625) (xy 2.2 -0.0875) (xy -0.15 -0.0875)
					)
					(width 0)
					(fill yes)
				)
			)
		)
		(pad "6" smd roundrect
			(at -1.025 1.94)
			(size 0.3 0.725)
			(layers "F.Cu" "F.Paste" "F.Mask")
			(roundrect_rratio 0.25)
			(net 643 "/Supply/3V3_SW")
			(pinfunction "SW")
			(pintype "passive")
		)
		(pad "7" smd roundrect
			(at -0.575 1.94)
			(size 0.3 0.725)
			(layers "F.Cu" "F.Paste" "F.Mask")
			(roundrect_rratio 0.25)
			(net 643 "/Supply/3V3_SW")
			(pinfunction "SW")
			(pintype "passive")
		)
		(pad "8" smd roundrect
			(at 0.125 1.94)
			(size 0.3 0.725)
			(layers "F.Cu" "F.Paste" "F.Mask")
			(roundrect_rratio 0.25)
			(net 643 "/Supply/3V3_SW")
			(pinfunction "SW")
			(pintype "passive")
		)
		(pad "9" smd roundrect
			(at 0.575 1.94)
			(size 0.3 0.725)
			(layers "F.Cu" "F.Paste" "F.Mask")
			(roundrect_rratio 0.25)
			(net 643 "/Supply/3V3_SW")
			(pinfunction "SW")
			(pintype "passive")
		)
		(pad "10" smd roundrect
			(at 1.025 1.935)
			(size 0.3 0.725)
			(layers "F.Cu" "F.Paste" "F.Mask")
			(roundrect_rratio 0.25)
			(net 785 "unconnected-(U40-GL-Pad10)_1")
			(pinfunction "GL")
			(pintype "passive+no_connect")
		)
		(pad "11" smd roundrect
			(at 1.94 1.425 90)
			(size 0.3 0.725)
			(layers "F.Cu" "F.Paste" "F.Mask")
			(roundrect_rratio 0.25)
			(net 756 "unconnected-(U40-GL-Pad10)")
			(pinfunction "GL")
			(pintype "passive+no_connect")
		)
		(pad "12" smd roundrect
			(at 1.94 0.975 90)
			(size 0.3 0.725)
			(layers "F.Cu" "F.Paste" "F.Mask")
			(roundrect_rratio 0.25)
			(net 642 "/Supply/3V3_VDRV")
			(pinfunction "V_{DRV}")
			(pintype "passive")
		)
		(pad "13" smd roundrect
			(at 1.94 0.525 90)
			(size 0.3 0.725)
			(layers "F.Cu" "F.Paste" "F.Mask")
			(roundrect_rratio 0.25)
			(net 1 "GND")
			(pinfunction "P_{GND}")
			(pintype "power_in")
		)
		(pad "14" smd roundrect
			(at 1.94 0.075 90)
			(size 0.3 0.725)
			(layers "F.Cu" "F.Paste" "F.Mask")
			(roundrect_rratio 0.25)
			(net 757 "unconnected-(U40-P_{GOOD}-Pad14)")
			(pinfunction "P_{GOOD}")
			(pintype "output+no_connect")
		)
		(pad "15" smd roundrect
			(at 1.94 -0.375 90)
			(size 0.3 0.725)
			(layers "F.Cu" "F.Paste" "F.Mask")
			(roundrect_rratio 0.25)
			(net 177 "/Supply/3V3_VDD")
			(pinfunction "V_{DD}")
			(pintype "passive")
		)
		(pad "16" smd roundrect
			(at 1.94 -0.825 90)
			(size 0.3 0.725)
			(layers "F.Cu" "F.Paste" "F.Mask")
			(roundrect_rratio 0.25)
			(net 1 "GND")
			(pinfunction "A_{GND}")
			(pintype "power_in")
		)
		(pad "17" smd roundrect
			(at 1.94 -1.275 90)
			(size 0.3 0.725)
			(layers "F.Cu" "F.Paste" "F.Mask")
			(roundrect_rratio 0.25)
			(net 711 "/Supply/3V3_FB")
			(pinfunction "FB")
			(pintype "passive")
		)
		(pad "18" smd roundrect
			(at 1.475 -1.94)
			(size 0.3 0.725)
			(layers "F.Cu" "F.Paste" "F.Mask")
			(roundrect_rratio 0.25)
			(net 641 "/Supply/3V3_OUT")
			(pinfunction "V_{OUT}")
			(pintype "passive")
		)
		(pad "19" smd roundrect
			(at 1.025 -1.94)
			(size 0.3 0.725)
			(layers "F.Cu" "F.Paste" "F.Mask")
			(roundrect_rratio 0.25)
			(net 771 "/Supply/3V3_EN")
			(pinfunction "EN")
			(pintype "input")
		)
		(pad "20" smd roundrect
			(at 0.575 -1.94)
			(size 0.3 0.725)
			(layers "F.Cu" "F.Paste" "F.Mask")
			(roundrect_rratio 0.25)
			(net 684 "/Supply/3V3_MODE2")
			(pinfunction "MODE2")
			(pintype "input")
		)
		(pad "21" smd roundrect
			(at 0.125 -1.94)
			(size 0.3 0.725)
			(layers "F.Cu" "F.Paste" "F.Mask")
			(roundrect_rratio 0.25)
			(net 687 "/Supply/3V3_MODE1")
			(pinfunction "MODE1")
			(pintype "input")
		)
		(pad "22" smd roundrect
			(at -0.575 -1.94)
			(size 0.3 0.725)
			(layers "F.Cu" "F.Paste" "F.Mask")
			(roundrect_rratio 0.25)
			(net 115 "VCC")
			(pinfunction "V_{IN}")
			(pintype "passive")
		)
		(pad "23" smd roundrect
			(at -1.025 -1.94)
			(size 0.3 0.725)
			(layers "F.Cu" "F.Paste" "F.Mask")
			(roundrect_rratio 0.25)
			(net 358 "/Supply/3V3_BOOT")
			(pinfunction "BOOT")
			(pintype "passive")
		)
		(pad "24" smd roundrect
			(at -1.475 -1.94)
			(size 0.3 0.725)
			(layers "F.Cu" "F.Paste" "F.Mask")
			(roundrect_rratio 0.25)
			(net 758 "/Supply/3V3_PHASE")
			(pinfunction "PHASE")
			(pintype "passive")
		)
		(pad "25" smd rect
			(at 0.49 -0.75 180)
			(size 1.575 1.05)
			(layers "F.Cu" "F.Paste" "F.Mask")
			(net 1 "GND")
			(pinfunction "A_{GND}")
			(pintype "passive")
		)
		(pad "26" smd rect
			(at -1.175 -0.75 180)
			(size 1.15 1.05)
			(layers "F.Cu" "F.Paste" "F.Mask")
			(net 115 "VCC")
			(pinfunction "V_{IN}")
			(pintype "passive")
		)
		(pad "27" smd custom
			(at -0.75 0.775)
			(size 1 1)
			(layers "F.Cu" "F.Paste" "F.Mask")
			(net 1 "GND")
			(pinfunction "P_{GND}")
			(pintype "passive")
			(options
				(clearance outline)
				(anchor rect)
			)
			(primitives
				(gr_poly
					(pts
						(xy -1 0.5) (xy -1 -0.7) (xy 1.825 -0.7) (xy 1.825 -0.245) (xy 1.175 -0.245) (xy 1.175 0.5)
					)
					(width 0)
					(fill yes)
				)
			)
		)
		(pad "28" smd rect
			(at 0.985 0.99 180)
			(size 0.58 0.38)
			(layers "F.Cu" "F.Paste" "F.Mask")
			(net 786 "unconnected-(U40-GL-Pad10)_2")
			(pinfunction "GL")
			(pintype "passive+no_connect")
		)
	)
	(footprint "antmicro-footprints:L_Bourns-SRP5030CA"
		(layer "F.Cu")
		(at 73.245 95.97 180)
		(property "Reference" "L1"
			(at -4.135 -2.85 0)
			(layer "F.SilkS")
			(effects
				(font
					(size 0.7 0.7)
					(thickness 0.15)
				)
				(justify right bottom)
			)
		)
		(property "Value" "L_560n_17.7A_Bourns-SRP5030CA"
			(at 0 4.241 0)
			(layer "F.Fab")
			(effects
				(font
					(size 0.7 0.7)
					(thickness 0.15)
				)
				(justify right bottom)
			)
		)
		(property "Footprint" "antmicro-footprints:L_Bourns-SRP5030CA"
			(at 0 0 180)
			(layer "F.Fab")
			(hide yes)
			(effects
				(font
					(size 1.27 1.27)
					(thickness 0.15)
				)
			)
		)
		(property "Datasheet" "https://www.bourns.com/docs/Product-Datasheets/SRP5030CA.pdf"
			(at 0 0 180)
			(layer "F.Fab")
			(hide yes)
			(effects
				(font
					(size 1.27 1.27)
					(thickness 0.15)
				)
			)
		)
		(property "Author" "Antmicro"
			(at 146.49 191.94 0)
			(layer "F.Fab")
			(hide yes)
			(effects
				(font
					(size 1 1)
					(thickness 0.15)
				)
			)
		)
		(property "IMax" "17.7 A"
			(at 146.49 191.94 0)
			(layer "F.Fab")
			(hide yes)
			(effects
				(font
					(size 1 1)
					(thickness 0.15)
				)
			)
		)
		(property "ISat" "22.2 A"
			(at 146.49 191.94 0)
			(layer "F.Fab")
			(hide yes)
			(effects
				(font
					(size 1 1)
					(thickness 0.15)
				)
			)
		)
		(property "License" "Apache-2.0"
			(at 146.49 191.94 0)
			(layer "F.Fab")
			(hide yes)
			(effects
				(font
					(size 1 1)
					(thickness 0.15)
				)
			)
		)
		(property "MPN" "SRP5030CA-R56M"
			(at 146.49 191.94 0)
			(layer "F.Fab")
			(hide yes)
			(effects
				(font
					(size 1 1)
					(thickness 0.15)
				)
			)
		)
		(property "Manufacturer" "Bourns"
			(at 146.49 191.94 0)
			(layer "F.Fab")
			(hide yes)
			(effects
				(font
					(size 1 1)
					(thickness 0.15)
				)
			)
		)
		(property "Size" "5.5x5.3"
			(at 146.49 191.94 0)
			(layer "F.Fab")
			(hide yes)
			(effects
				(font
					(size 1 1)
					(thickness 0.15)
				)
			)
		)
		(property "Val" "560n/17.7A"
			(at 146.49 191.94 0)
			(layer "F.Fab")
			(hide yes)
			(effects
				(font
					(size 1 1)
					(thickness 0.15)
				)
			)
		)
		(sheetname "Supply")
		(sheetfile "supply.kicad_sch")
		(attr smd)
		(fp_line
			(start 2.65 2.75)
			(end 2.65 -2.75)
			(stroke
				(width 0.15)
				(type solid)
			)
			(layer "F.SilkS")
		)
		(fp_line
			(start -2.65 2.75)
			(end 2.65 2.75)
			(stroke
				(width 0.15)
				(type solid)
			)
			(layer "F.SilkS")
		)
		(fp_line
			(start -2.65 2.75)
			(end -2.65 -2.75)
			(stroke
				(width 0.15)
				(type solid)
			)
			(layer "F.SilkS")
		)
		(fp_line
			(start -2.65 -2.75)
			(end 2.65 -2.75)
			(stroke
				(width 0.15)
				(type solid)
			)
			(layer "F.SilkS")
		)
		(fp_rect
			(start -2.89 -2.99)
			(end 2.89 2.99)
			(stroke
				(width 0.05)
				(type solid)
			)
			(fill none)
			(layer "F.CrtYd")
		)
		(fp_line
			(start 2.65 2.75)
			(end -2.65 2.75)
			(stroke
				(width 0.15)
				(type solid)
			)
			(layer "F.Fab")
		)
		(fp_line
			(start 2.65 -2.75)
			(end 2.65 2.75)
			(stroke
				(width 0.15)
				(type solid)
			)
			(layer "F.Fab")
		)
		(fp_line
			(start -2.65 2.75)
			(end -2.65 -2.75)
			(stroke
				(width 0.15)
				(type solid)
			)
			(layer "F.Fab")
		)
		(fp_line
			(start -2.65 -2.75)
			(end 2.65 -2.75)
			(stroke
				(width 0.15)
				(type solid)
			)
			(layer "F.Fab")
		)
		(fp_text user "${REFERENCE}"
			(at -2.89 8.641 0)
			(layer "F.Fab")
			(hide yes)
			(effects
				(font
					(size 0.7 0.7)
					(thickness 0.15)
				)
				(justify right bottom)
			)
		)
		(fp_text user "Author: Antmicro"
			(at -2.89 7.441 0)
			(layer "F.Fab")
			(hide yes)
			(effects
				(font
					(size 0.7 0.7)
					(thickness 0.15)
				)
				(justify right bottom)
			)
		)
		(fp_text user "License: Apache-2.0"
			(at -2.89 6.241 0)
			(layer "F.Fab")
			(hide yes)
			(effects
				(font
					(size 0.7 0.7)
					(thickness 0.15)
				)
				(justify right bottom)
			)
		)
		(pad "1" smd roundrect
			(at -1.625 0 180)
			(size 1.25 4.7)
			(layers "F.Cu" "F.Paste" "F.Mask")
			(roundrect_rratio 0.1)
			(net 643 "/Supply/3V3_SW")
			(pintype "passive")
		)
		(pad "2" smd roundrect
			(at 1.625 0 180)
			(size 1.25 4.7)
			(layers "F.Cu" "F.Paste" "F.Mask")
			(roundrect_rratio 0.1)
			(net 641 "/Supply/3V3_OUT")
			(pintype "passive")
		)
	)
	(footprint "antmicro-footprints:R_Array_4x0402"
		(layer "F.Cu")
		(at 147.85 106.14 -90)
		(property "Reference" "R102"
			(at 1.53 -1.6 -90)
			(layer "F.SilkS")
			(effects
				(font
					(size 0.7 0.7)
					(thickness 0.15)
				)
				(justify left bottom)
			)
		)
		(property "Value" "R_4x330R_0402_array"
			(at -1.5 2 -90)
			(layer "F.Fab")
			(effects
				(font
					(size 0.7 0.7)
					(thickness 0.15)
				)
				(justify left bottom)
			)
		)
		(property "Footprint" "antmicro-footprints:R_Array_4x0402"
			(at 0 0 -90)
			(layer "F.Fab")
			(hide yes)
			(effects
				(font
					(size 1.27 1.27)
					(thickness 0.15)
				)
			)
		)
		(property "Datasheet" "http://industrial.panasonic.com/cdbs/www-data/pdf/AOC0000/AOC0000C14.pdf"
			(at 0 0 -90)
			(layer "F.Fab")
			(hide yes)
			(effects
				(font
					(size 1.27 1.27)
					(thickness 0.15)
				)
			)
		)
		(property "Author" "Antmicro"
			(at 41.71 253.99 0)
			(layer "F.Fab")
			(hide yes)
			(effects
				(font
					(size 1 1)
					(thickness 0.15)
				)
			)
		)
		(property "License" "Apache-2.0"
			(at 41.71 253.99 0)
			(layer "F.Fab")
			(hide yes)
			(effects
				(font
					(size 1 1)
					(thickness 0.15)
				)
			)
		)
		(property "MPN" "EXB-28V331JX"
			(at 41.71 253.99 0)
			(layer "F.Fab")
			(hide yes)
			(effects
				(font
					(size 1 1)
					(thickness 0.15)
				)
			)
		)
		(property "Manufacturer" "Panasonic"
			(at 41.71 253.99 0)
			(layer "F.Fab")
			(hide yes)
			(effects
				(font
					(size 1 1)
					(thickness 0.15)
				)
			)
		)
		(property "Val" "R_4x330R_0402"
			(at 41.71 253.99 0)
			(layer "F.Fab")
			(hide yes)
			(effects
				(font
					(size 1 1)
					(thickness 0.15)
				)
			)
		)
		(sheetname "Peripherals")
		(sheetfile "peripherals.kicad_sch")
		(attr smd)
		(fp_line
			(start 1.167 0.498)
			(end 1.167 -0.5)
			(stroke
				(width 0.15)
				(type solid)
			)
			(layer "F.SilkS")
		)
		(fp_line
			(start -1.17 -0.5)
			(end -1.17 0.498)
			(stroke
				(width 0.15)
				(type solid)
			)
			(layer "F.SilkS")
		)
		(fp_rect
			(start -1.2 -0.9)
			(end 1.2 0.9)
			(stroke
				(width 0.05)
				(type solid)
			)
			(fill none)
			(layer "F.CrtYd")
		)
		(fp_line
			(start -1 0.498)
			(end -1 -0.5)
			(stroke
				(width 0.15)
				(type solid)
			)
			(layer "F.Fab")
		)
		(fp_line
			(start 0.998 0.498)
			(end -1 0.498)
			(stroke
				(width 0.15)
				(type solid)
			)
			(layer "F.Fab")
		)
		(fp_line
			(start -1 -0.5)
			(end 0.998 -0.5)
			(stroke
				(width 0.15)
				(type solid)
			)
			(layer "F.Fab")
		)
		(fp_line
			(start 0.998 -0.5)
			(end 0.998 0.498)
			(stroke
				(width 0.15)
				(type solid)
			)
			(layer "F.Fab")
		)
		(fp_text user "Author: Antmicro"
			(at -1.5 4.5 -90)
			(layer "F.Fab")
			(hide yes)
			(effects
				(font
					(size 0.7 0.7)
					(thickness 0.15)
				)
				(justify left bottom)
			)
		)
		(fp_text user "${REFERENCE}"
			(at -1.5 3.25 -90)
			(layer "F.Fab")
			(hide yes)
			(effects
				(font
					(size 0.7 0.7)
					(thickness 0.15)
				)
				(justify left bottom)
			)
		)
		(fp_text user "License: Apache-2.0"
			(at -1.5 5.75 -90)
			(layer "F.Fab")
			(hide yes)
			(effects
				(font
					(size 0.7 0.7)
					(thickness 0.15)
				)
				(justify left bottom)
			)
		)
		(pad "1" smd roundrect
			(at -0.802 0.45 270)
			(size 0.4 0.5)
			(layers "F.Cu" "F.Paste" "F.Mask")
			(roundrect_rratio 0.25)
			(net 674 "unconnected-(R102-R1.1-Pad1)")
			(pinfunction "R1.1")
			(pintype "passive+no_connect")
		)
		(pad "2" smd roundrect
			(at -0.272 0.45 270)
			(size 0.4 0.5)
			(layers "F.Cu" "F.Paste" "F.Mask")
			(roundrect_rratio 0.25)
			(net 675 "unconnected-(R102-R2.1-Pad2)")
			(pinfunction "R2.1")
			(pintype "passive+no_connect")
		)
		(pad "3" smd roundrect
			(at 0.27 0.45 270)
			(size 0.4 0.5)
			(layers "F.Cu" "F.Paste" "F.Mask")
			(roundrect_rratio 0.25)
			(net 606 "/Peripherals/~{SPI1_CS0_CONN}")
			(pinfunction "R3.1")
			(pintype "passive")
		)
		(pad "4" smd roundrect
			(at 0.8 0.45 270)
			(size 0.4 0.5)
			(layers "F.Cu" "F.Paste" "F.Mask")
			(roundrect_rratio 0.25)
			(net 608 "/Peripherals/~{SPI1_CS1_CONN}")
			(pinfunction "R4.1")
			(pintype "passive")
		)
		(pad "5" smd roundrect
			(at 0.8 -0.452 270)
			(size 0.4 0.5)
			(layers "F.Cu" "F.Paste" "F.Mask")
			(roundrect_rratio 0.25)
			(net 42 "~{SPI1_CS1}")
			(pinfunction "R4.2")
			(pintype "passive")
		)
		(pad "6" smd roundrect
			(at 0.27 -0.452 270)
			(size 0.4 0.5)
			(layers "F.Cu" "F.Paste" "F.Mask")
			(roundrect_rratio 0.25)
			(net 41 "~{SPI1_CS0}")
			(pinfunction "R3.2")
			(pintype "passive")
		)
		(pad "7" smd roundrect
			(at -0.272 -0.452 270)
			(size 0.4 0.5)
			(layers "F.Cu" "F.Paste" "F.Mask")
			(roundrect_rratio 0.25)
			(net 676 "unconnected-(R102-R2.2-Pad7)")
			(pinfunction "R2.2")
			(pintype "passive+no_connect")
		)
		(pad "8" smd roundrect
			(at -0.802 -0.452 270)
			(size 0.4 0.5)
			(layers "F.Cu" "F.Paste" "F.Mask")
			(roundrect_rratio 0.25)
			(net 681 "unconnected-(R102-R1.2-Pad8)")
			(pinfunction "R1.2")
			(pintype "passive+no_connect")
		)
	)
	(footprint "antmicro-footprints:R_0402_1005Metric"
		(layer "F.Cu")
		(at 67.5 119 90)
		(descr "Resistor SMD 0402")
		(tags "resistor SMD 0402")
		(property "Reference" "R104"
			(at -3.65 0.45 90)
			(layer "F.SilkS")
			(effects
				(font
					(size 0.7 0.7)
					(thickness 0.15)
				)
				(justify left bottom)
			)
		)
		(property "Value" "R_2k2_0402"
			(at 0 1.4 90)
			(layer "F.Fab")
			(effects
				(font
					(size 0.7 0.7)
					(thickness 0.15)
				)
				(justify left bottom)
			)
		)
		(property "Footprint" "antmicro-footprints:R_0402_1005Metric"
			(at 0 0 90)
			(layer "F.Fab")
			(hide yes)
			(effects
				(font
					(size 1.27 1.27)
					(thickness 0.15)
				)
			)
		)
		(property "Datasheet" "https://www.bourns.com/docs/product-datasheets/cr.pdf"
			(at 0 0 90)
			(layer "F.Fab")
			(hide yes)
			(effects
				(font
					(size 1.27 1.27)
					(thickness 0.15)
				)
			)
		)
		(property "Author" "Antmicro"
			(at 186.5 51.5 0)
			(layer "F.Fab")
			(hide yes)
			(effects
				(font
					(size 1 1)
					(thickness 0.15)
				)
			)
		)
		(property "License" "Apache-2.0"
			(at 186.5 51.5 0)
			(layer "F.Fab")
			(hide yes)
			(effects
				(font
					(size 1 1)
					(thickness 0.15)
				)
			)
		)
		(property "MPN" "CR0402-FX-2201GLF"
			(at 186.5 51.5 0)
			(layer "F.Fab")
			(hide yes)
			(effects
				(font
					(size 1 1)
					(thickness 0.15)
				)
			)
		)
		(property "Manufacturer" "Bourns"
			(at 186.5 51.5 0)
			(layer "F.Fab")
			(hide yes)
			(effects
				(font
					(size 1 1)
					(thickness 0.15)
				)
			)
		)
		(property "Tolerance" "1%"
			(at 186.5 51.5 0)
			(layer "F.Fab")
			(hide yes)
			(effects
				(font
					(size 1 1)
					(thickness 0.15)
				)
			)
		)
		(property "Val" "2k2"
			(at 186.5 51.5 0)
			(layer "F.Fab")
			(hide yes)
			(effects
				(font
					(size 1 1)
					(thickness 0.15)
				)
			)
		)
		(sheetname "USB Debug, DP")
		(sheetfile "usb.kicad_sch")
		(attr smd)
		(fp_rect
			(start -0.925 -0.47)
			(end 0.925 0.47)
			(stroke
				(width 0.05)
				(type default)
			)
			(fill none)
			(layer "F.CrtYd")
		)
		(fp_rect
			(start -0.5 -0.25)
			(end 0.5 0.25)
			(stroke
				(width 0.15)
				(type solid)
			)
			(fill none)
			(layer "F.Fab")
		)
		(fp_text user "${REFERENCE}"
			(at -0.95 3.168 90)
			(layer "F.Fab")
			(hide yes)
			(effects
				(font
					(size 0.7 0.7)
					(thickness 0.15)
				)
				(justify left bottom)
			)
		)
		(fp_text user "License: Apache-2.0"
			(at -0.95 5.169 90)
			(layer "F.Fab")
			(hide yes)
			(effects
				(font
					(size 0.7 0.7)
					(thickness 0.15)
				)
				(justify left bottom)
			)
		)
		(fp_text user "Author: Antmicro"
			(at -0.95 4.169 90)
			(layer "F.Fab")
			(hide yes)
			(effects
				(font
					(size 0.7 0.7)
					(thickness 0.15)
				)
				(justify left bottom)
			)
		)
		(pad "1" smd roundrect
			(at -0.48 0 90)
			(size 0.59 0.64)
			(layers "F.Cu" "F.Paste" "F.Mask")
			(roundrect_rratio 0.25)
			(net 1 "GND")
			(pintype "passive")
		)
		(pad "2" smd roundrect
			(at 0.48 0 90)
			(size 0.59 0.64)
			(layers "F.Cu" "F.Paste" "F.Mask")
			(roundrect_rratio 0.25)
			(net 682 "Net-(U12-ISET)")
			(pintype "passive")
		)
	)
	(footprint "antmicro-footprints:R_0402_1005Metric"
		(layer "F.Cu")
		(at 89.7 104.6 45)
		(descr "Resistor SMD 0402")
		(tags "resistor SMD 0402")
		(property "Reference" "R214"
			(at -1.909188 -0.636396 45)
			(layer "F.SilkS")
			(effects
				(font
					(size 0.7 0.7)
					(thickness 0.15)
				)
				(justify left bottom)
			)
		)
		(property "Value" "R_499R_0402"
			(at -1.011843 1.772046 45)
			(layer "F.Fab")
			(effects
				(font
					(size 0.7 0.7)
					(thickness 0.15)
				)
				(justify left bottom)
			)
		)
		(property "Footprint" "antmicro-footprints:R_0402_1005Metric"
			(at 0 0 45)
			(layer "F.Fab")
			(hide yes)
			(effects
				(font
					(size 1.27 1.27)
					(thickness 0.15)
				)
			)
		)
		(property "Datasheet" "https://www.mouser.com/datasheet/2/54/cr-1858361.pdf"
			(at 0 0 45)
			(layer "F.Fab")
			(hide yes)
			(effects
				(font
					(size 1.27 1.27)
					(thickness 0.15)
				)
			)
		)
		(property "Author" "Antmicro"
			(at 100.235891 -32.790847 0)
			(layer "F.Fab")
			(hide yes)
			(effects
				(font
					(size 1 1)
					(thickness 0.15)
				)
			)
		)
		(property "License" "Apache-2.0"
			(at 100.235891 -32.790847 0)
			(layer "F.Fab")
			(hide yes)
			(effects
				(font
					(size 1 1)
					(thickness 0.15)
				)
			)
		)
		(property "MPN" "CR0402-FX-4990GLF"
			(at 100.235891 -32.790847 0)
			(layer "F.Fab")
			(hide yes)
			(effects
				(font
					(size 1 1)
					(thickness 0.15)
				)
			)
		)
		(property "Manufacturer" "Bourns"
			(at 100.235891 -32.790847 0)
			(layer "F.Fab")
			(hide yes)
			(effects
				(font
					(size 1 1)
					(thickness 0.15)
				)
			)
		)
		(property "Tolerance" "1%"
			(at 100.235891 -32.790847 0)
			(layer "F.Fab")
			(hide yes)
			(effects
				(font
					(size 1 1)
					(thickness 0.15)
				)
			)
		)
		(property "Val" "499R"
			(at 100.235891 -32.790847 0)
			(layer "F.Fab")
			(hide yes)
			(effects
				(font
					(size 1 1)
					(thickness 0.15)
				)
			)
		)
		(sheetname "HDMI")
		(sheetfile "hdmi.kicad_sch")
		(attr smd)
		(fp_poly
			(pts
				(xy -0.925 -0.47) (xy 0.925 -0.47) (xy 0.925 0.47) (xy -0.925 0.47)
			)
			(stroke
				(width 0.05)
				(type default)
			)
			(fill none)
			(layer "F.CrtYd")
		)
		(fp_poly
			(pts
				(xy -0.5 -0.25) (xy 0.5 -0.25) (xy 0.5 0.25) (xy -0.5 0.25)
			)
			(stroke
				(width 0.15)
				(type solid)
			)
			(fill none)
			(layer "F.Fab")
		)
		(fp_text user "${REFERENCE}"
			(at -0.95 3.168 45)
			(layer "F.Fab")
			(hide yes)
			(effects
				(font
					(size 0.7 0.7)
					(thickness 0.15)
				)
				(justify left bottom)
			)
		)
		(fp_text user "License: Apache-2.0"
			(at -0.949999 5.169 45)
			(layer "F.Fab")
			(hide yes)
			(effects
				(font
					(size 0.7 0.7)
					(thickness 0.15)
				)
				(justify left bottom)
			)
		)
		(fp_text user "Author: Antmicro"
			(at -0.95 4.169 45)
			(layer "F.Fab")
			(hide yes)
			(effects
				(font
					(size 0.7 0.7)
					(thickness 0.15)
				)
				(justify left bottom)
			)
		)
		(pad "1" smd roundrect
			(at -0.48 0 45)
			(size 0.59 0.64)
			(layers "F.Cu" "F.Paste" "F.Mask")
			(roundrect_rratio 0.25)
			(net 623 "Net-(Q2-D)")
			(pintype "passive")
		)
		(pad "2" smd roundrect
			(at 0.48 0 45)
			(size 0.59 0.64)
			(layers "F.Cu" "F.Paste" "F.Mask")
			(roundrect_rratio 0.25)
			(net 488 "/HDMI/HDMI_D0_N")
			(pintype "passive")
		)
	)
	(footprint "antmicro-footprints:R_0402_1005Metric"
		(layer "F.Cu")
		(at 128.9 107.9 -90)
		(descr "Resistor SMD 0402")
		(tags "resistor SMD 0402")
		(property "Reference" "R187"
			(at 3.85 -0.37 -90)
			(layer "F.SilkS")
			(effects
				(font
					(size 0.7 0.7)
					(thickness 0.15)
				)
				(justify left bottom)
			)
		)
		(property "Value" "R_200R_0402"
			(at 0 1.4 -90)
			(layer "F.Fab")
			(effects
				(font
					(size 0.7 0.7)
					(thickness 0.15)
				)
				(justify left bottom)
			)
		)
		(property "Footprint" "antmicro-footprints:R_0402_1005Metric"
			(at 0 0 -90)
			(layer "F.Fab")
			(hide yes)
			(effects
				(font
					(size 1.27 1.27)
					(thickness 0.15)
				)
			)
		)
		(property "Datasheet" "https://www.bourns.com/docs/product-datasheets/cr.pdf"
			(at 0 0 -90)
			(layer "F.Fab")
			(hide yes)
			(effects
				(font
					(size 1.27 1.27)
					(thickness 0.15)
				)
			)
		)
		(property "Author" "Antmicro"
			(at 21 236.8 0)
			(layer "F.Fab")
			(hide yes)
			(effects
				(font
					(size 1 1)
					(thickness 0.15)
				)
			)
		)
		(property "License" "Apache-2.0"
			(at 21 236.8 0)
			(layer "F.Fab")
			(hide yes)
			(effects
				(font
					(size 1 1)
					(thickness 0.15)
				)
			)
		)
		(property "MPN" "CR0402-FX-2000GLF"
			(at 21 236.8 0)
			(layer "F.Fab")
			(hide yes)
			(effects
				(font
					(size 1 1)
					(thickness 0.15)
				)
			)
		)
		(property "Manufacturer" "Bourns"
			(at 21 236.8 0)
			(layer "F.Fab")
			(hide yes)
			(effects
				(font
					(size 1 1)
					(thickness 0.15)
				)
			)
		)
		(property "Tolerance" "1%"
			(at 21 236.8 0)
			(layer "F.Fab")
			(hide yes)
			(effects
				(font
					(size 1 1)
					(thickness 0.15)
				)
			)
		)
		(property "Val" "200R"
			(at 21 236.8 0)
			(layer "F.Fab")
			(hide yes)
			(effects
				(font
					(size 1 1)
					(thickness 0.15)
				)
			)
		)
		(sheetname "M.2")
		(sheetfile "m-2.kicad_sch")
		(attr smd)
		(fp_rect
			(start -0.925 -0.47)
			(end 0.925 0.47)
			(stroke
				(width 0.05)
				(type default)
			)
			(fill none)
			(layer "F.CrtYd")
		)
		(fp_rect
			(start -0.5 -0.25)
			(end 0.5 0.25)
			(stroke
				(width 0.15)
				(type solid)
			)
			(fill none)
			(layer "F.Fab")
		)
		(fp_text user "License: Apache-2.0"
			(at -0.95 5.169 -90)
			(layer "F.Fab")
			(hide yes)
			(effects
				(font
					(size 0.7 0.7)
					(thickness 0.15)
				)
				(justify left bottom)
			)
		)
		(fp_text user "Author: Antmicro"
			(at -0.95 4.169 -90)
			(layer "F.Fab")
			(hide yes)
			(effects
				(font
					(size 0.7 0.7)
					(thickness 0.15)
				)
				(justify left bottom)
			)
		)
		(fp_text user "${REFERENCE}"
			(at -0.95 3.168 -90)
			(layer "F.Fab")
			(hide yes)
			(effects
				(font
					(size 0.7 0.7)
					(thickness 0.15)
				)
				(justify left bottom)
			)
		)
		(pad "1" smd roundrect
			(at -0.48 0 270)
			(size 0.59 0.64)
			(layers "F.Cu" "F.Paste" "F.Mask")
			(roundrect_rratio 0.25)
			(net 653 "Net-(D52-A)")
			(pintype "passive")
		)
		(pad "2" smd roundrect
			(at 0.48 0 270)
			(size 0.59 0.64)
			(layers "F.Cu" "F.Paste" "F.Mask")
			(roundrect_rratio 0.25)
			(net 87 "+3V3")
			(pintype "passive")
		)
	)
	(footprint "antmicro-footprints:R_0402_1005Metric"
		(layer "F.Cu")
		(at 127.05 98.6 180)
		(descr "Resistor SMD 0402")
		(tags "resistor SMD 0402")
		(property "Reference" "R28"
			(at 1.05 0.45 180)
			(layer "F.SilkS")
			(effects
				(font
					(size 0.7 0.7)
					(thickness 0.15)
				)
				(justify left bottom)
			)
		)
		(property "Value" "R_47k_0402"
			(at 0 1.4 180)
			(layer "F.Fab")
			(effects
				(font
					(size 0.7 0.7)
					(thickness 0.15)
				)
				(justify left bottom)
			)
		)
		(property "Footprint" "antmicro-footprints:R_0402_1005Metric"
			(at 0 0 180)
			(layer "F.Fab")
			(hide yes)
			(effects
				(font
					(size 1.27 1.27)
					(thickness 0.15)
				)
			)
		)
		(property "Datasheet" "https://www.bourns.com/docs/product-datasheets/cr.pdf"
			(at 0 0 180)
			(layer "F.Fab")
			(hide yes)
			(effects
				(font
					(size 1.27 1.27)
					(thickness 0.15)
				)
			)
		)
		(property "Author" "Antmicro"
			(at 254.1 197.2 0)
			(layer "F.Fab")
			(hide yes)
			(effects
				(font
					(size 1 1)
					(thickness 0.15)
				)
			)
		)
		(property "License" "Apache-2.0"
			(at 254.1 197.2 0)
			(layer "F.Fab")
			(hide yes)
			(effects
				(font
					(size 1 1)
					(thickness 0.15)
				)
			)
		)
		(property "MPN" "CR0402-FX-4702GLF"
			(at 254.1 197.2 0)
			(layer "F.Fab")
			(hide yes)
			(effects
				(font
					(size 1 1)
					(thickness 0.15)
				)
			)
		)
		(property "Manufacturer" "Bourns"
			(at 254.1 197.2 0)
			(layer "F.Fab")
			(hide yes)
			(effects
				(font
					(size 1 1)
					(thickness 0.15)
				)
			)
		)
		(property "Tolerance" "1%"
			(at 254.1 197.2 0)
			(layer "F.Fab")
			(hide yes)
			(effects
				(font
					(size 1 1)
					(thickness 0.15)
				)
			)
		)
		(property "Val" "47k"
			(at 254.1 197.2 0)
			(layer "F.Fab")
			(hide yes)
			(effects
				(font
					(size 1 1)
					(thickness 0.15)
				)
			)
		)
		(sheetname "M.2")
		(sheetfile "m-2.kicad_sch")
		(attr smd exclude_from_pos_files exclude_from_bom dnp)
		(fp_rect
			(start -0.925 -0.47)
			(end 0.925 0.47)
			(stroke
				(width 0.05)
				(type default)
			)
			(fill none)
			(layer "F.CrtYd")
		)
		(fp_rect
			(start -0.5 -0.25)
			(end 0.5 0.25)
			(stroke
				(width 0.15)
				(type solid)
			)
			(fill none)
			(layer "F.Fab")
		)
		(fp_text user "License: Apache-2.0"
			(at -0.95 5.169 180)
			(layer "F.Fab")
			(hide yes)
			(effects
				(font
					(size 0.7 0.7)
					(thickness 0.15)
				)
				(justify left bottom)
			)
		)
		(fp_text user "Author: Antmicro"
			(at -0.95 4.169 180)
			(layer "F.Fab")
			(hide yes)
			(effects
				(font
					(size 0.7 0.7)
					(thickness 0.15)
				)
				(justify left bottom)
			)
		)
		(fp_text user "${REFERENCE}"
			(at -0.95 3.168 180)
			(layer "F.Fab")
			(hide yes)
			(effects
				(font
					(size 0.7 0.7)
					(thickness 0.15)
				)
				(justify left bottom)
			)
		)
		(pad "1" smd roundrect
			(at -0.48 0 180)
			(size 0.59 0.64)
			(layers "F.Cu" "F.Paste" "F.Mask")
			(roundrect_rratio 0.25)
			(net 87 "+3V3")
			(pintype "passive")
		)
		(pad "2" smd roundrect
			(at 0.48 0 180)
			(size 0.59 0.64)
			(layers "F.Cu" "F.Paste" "F.Mask")
			(roundrect_rratio 0.25)
			(net 64 "PCIE1_CLKREQ*")
			(pintype "passive")
		)
	)
	(footprint "antmicro-footprints:R_0402_1005Metric"
		(layer "F.Cu")
		(at 68.27 86.47 180)
		(descr "Resistor SMD 0402")
		(tags "resistor SMD 0402")
		(property "Reference" "R3"
			(at -4.11 3.79 0)
			(layer "F.SilkS")
			(effects
				(font
					(size 0.7 0.7)
					(thickness 0.15)
				)
				(justify right top)
			)
		)
		(property "Value" "R_0R_0402"
			(at 0 1.4 0)
			(layer "F.Fab")
			(effects
				(font
					(size 0.7 0.7)
					(thickness 0.15)
				)
				(justify right top)
			)
		)
		(property "Footprint" "antmicro-footprints:R_0402_1005Metric"
			(at 0 0 0)
			(layer "F.Fab")
			(hide yes)
			(effects
				(font
					(size 1.27 1.27)
					(thickness 0.15)
				)
			)
		)
		(property "Datasheet" "https://industrial.panasonic.com/cdbs/www-data/pdf/RDA0000/AOA0000C301.pdf"
			(at 0 0 0)
			(layer "F.Fab")
			(hide yes)
			(effects
				(font
					(size 1.27 1.27)
					(thickness 0.15)
				)
			)
		)
		(property "Author" "Antmicro"
			(at -15.45 150.35 90)
			(layer "F.Fab")
			(hide yes)
			(effects
				(font
					(size 1 1)
					(thickness 0.15)
				)
			)
		)
		(property "Current" "1A"
			(at -15.45 150.35 90)
			(layer "F.Fab")
			(hide yes)
			(effects
				(font
					(size 1 1)
					(thickness 0.15)
				)
			)
		)
		(property "License" "Apache-2.0"
			(at -15.45 150.35 90)
			(layer "F.Fab")
			(hide yes)
			(effects
				(font
					(size 1 1)
					(thickness 0.15)
				)
			)
		)
		(property "MPN" "ERJ2GE0R00X"
			(at -15.45 150.35 90)
			(layer "F.Fab")
			(hide yes)
			(effects
				(font
					(size 1 1)
					(thickness 0.15)
				)
			)
		)
		(property "Manufacturer" "Panasonic"
			(at -15.45 150.35 90)
			(layer "F.Fab")
			(hide yes)
			(effects
				(font
					(size 1 1)
					(thickness 0.15)
				)
			)
		)
		(property "Tolerance" ""
			(at -15.45 150.35 90)
			(layer "F.Fab")
			(hide yes)
			(effects
				(font
					(size 1 1)
					(thickness 0.15)
				)
			)
		)
		(property "Val" "0R"
			(at -15.45 150.35 90)
			(layer "F.Fab")
			(hide yes)
			(effects
				(font
					(size 1 1)
					(thickness 0.15)
				)
			)
		)
		(sheetname "SoM")
		(sheetfile "som.kicad_sch")
		(attr smd)
		(fp_rect
			(start -0.925 -0.47)
			(end 0.925 0.47)
			(stroke
				(width 0.05)
				(type default)
			)
			(fill none)
			(layer "F.CrtYd")
		)
		(fp_rect
			(start -0.5 -0.25)
			(end 0.5 0.25)
			(stroke
				(width 0.15)
				(type solid)
			)
			(fill none)
			(layer "F.Fab")
		)
		(fp_text user "Author: Antmicro"
			(at -0.95 4.169 0)
			(layer "F.Fab")
			(hide yes)
			(effects
				(font
					(size 0.7 0.7)
					(thickness 0.15)
				)
				(justify right top)
			)
		)
		(fp_text user "${REFERENCE}"
			(at -0.95 3.168 0)
			(layer "F.Fab")
			(hide yes)
			(effects
				(font
					(size 0.7 0.7)
					(thickness 0.15)
				)
				(justify right top)
			)
		)
		(fp_text user "License: Apache-2.0"
			(at -0.95 5.169 0)
			(layer "F.Fab")
			(hide yes)
			(effects
				(font
					(size 0.7 0.7)
					(thickness 0.15)
				)
				(justify right top)
			)
		)
		(pad "1" smd roundrect
			(at -0.48 0 180)
			(size 0.59 0.64)
			(layers "F.Cu" "F.Paste" "F.Mask")
			(roundrect_rratio 0.25)
			(net 753 "Net-(J15H-GPIO13{slash}PWM)")
			(pintype "passive")
		)
		(pad "2" smd roundrect
			(at 0.48 0 180)
			(size 0.59 0.64)
			(layers "F.Cu" "F.Paste" "F.Mask")
			(roundrect_rratio 0.25)
			(net 84 "GPIO13")
			(pintype "passive")
		)
	)
	(footprint "antmicro-footprints:R_Array_4x0402"
		(layer "F.Cu")
		(at 147.8 95.5 -90)
		(property "Reference" "R64"
			(at 1.13 -1.63 -90)
			(layer "F.SilkS")
			(effects
				(font
					(size 0.7 0.7)
					(thickness 0.15)
				)
				(justify left bottom)
			)
		)
		(property "Value" "R_4x330R_0402_array"
			(at -1.5 2 -90)
			(layer "F.Fab")
			(effects
				(font
					(size 0.7 0.7)
					(thickness 0.15)
				)
				(justify left bottom)
			)
		)
		(property "Footprint" "antmicro-footprints:R_Array_4x0402"
			(at 0 0 -90)
			(layer "F.Fab")
			(hide yes)
			(effects
				(font
					(size 1.27 1.27)
					(thickness 0.15)
				)
			)
		)
		(property "Datasheet" "http://industrial.panasonic.com/cdbs/www-data/pdf/AOC0000/AOC0000C14.pdf"
			(at 0 0 -90)
			(layer "F.Fab")
			(hide yes)
			(effects
				(font
					(size 1.27 1.27)
					(thickness 0.15)
				)
			)
		)
		(property "Author" "Antmicro"
			(at 52.3 243.3 0)
			(layer "F.Fab")
			(hide yes)
			(effects
				(font
					(size 1 1)
					(thickness 0.15)
				)
			)
		)
		(property "License" "Apache-2.0"
			(at 52.3 243.3 0)
			(layer "F.Fab")
			(hide yes)
			(effects
				(font
					(size 1 1)
					(thickness 0.15)
				)
			)
		)
		(property "MPN" "EXB-28V331JX"
			(at 52.3 243.3 0)
			(layer "F.Fab")
			(hide yes)
			(effects
				(font
					(size 1 1)
					(thickness 0.15)
				)
			)
		)
		(property "Manufacturer" "Panasonic"
			(at 52.3 243.3 0)
			(layer "F.Fab")
			(hide yes)
			(effects
				(font
					(size 1 1)
					(thickness 0.15)
				)
			)
		)
		(property "Val" "R_4x330R_0402"
			(at 52.3 243.3 0)
			(layer "F.Fab")
			(hide yes)
			(effects
				(font
					(size 1 1)
					(thickness 0.15)
				)
			)
		)
		(sheetname "Peripherals")
		(sheetfile "peripherals.kicad_sch")
		(attr smd)
		(fp_line
			(start 1.167 0.498)
			(end 1.167 -0.5)
			(stroke
				(width 0.15)
				(type solid)
			)
			(layer "F.SilkS")
		)
		(fp_line
			(start -1.17 -0.5)
			(end -1.17 0.498)
			(stroke
				(width 0.15)
				(type solid)
			)
			(layer "F.SilkS")
		)
		(fp_rect
			(start -1.2 -0.9)
			(end 1.2 0.9)
			(stroke
				(width 0.05)
				(type solid)
			)
			(fill none)
			(layer "F.CrtYd")
		)
		(fp_line
			(start -1 0.498)
			(end -1 -0.5)
			(stroke
				(width 0.15)
				(type solid)
			)
			(layer "F.Fab")
		)
		(fp_line
			(start 0.998 0.498)
			(end -1 0.498)
			(stroke
				(width 0.15)
				(type solid)
			)
			(layer "F.Fab")
		)
		(fp_line
			(start -1 -0.5)
			(end 0.998 -0.5)
			(stroke
				(width 0.15)
				(type solid)
			)
			(layer "F.Fab")
		)
		(fp_line
			(start 0.998 -0.5)
			(end 0.998 0.498)
			(stroke
				(width 0.15)
				(type solid)
			)
			(layer "F.Fab")
		)
		(fp_text user "Author: Antmicro"
			(at -1.5 4.5 -90)
			(layer "F.Fab")
			(hide yes)
			(effects
				(font
					(size 0.7 0.7)
					(thickness 0.15)
				)
				(justify left bottom)
			)
		)
		(fp_text user "License: Apache-2.0"
			(at -1.5 5.75 -90)
			(layer "F.Fab")
			(hide yes)
			(effects
				(font
					(size 0.7 0.7)
					(thickness 0.15)
				)
				(justify left bottom)
			)
		)
		(fp_text user "${REFERENCE}"
			(at -1.5 3.25 -90)
			(layer "F.Fab")
			(hide yes)
			(effects
				(font
					(size 0.7 0.7)
					(thickness 0.15)
				)
				(justify left bottom)
			)
		)
		(pad "1" smd roundrect
			(at -0.802 0.45 270)
			(size 0.4 0.5)
			(layers "F.Cu" "F.Paste" "F.Mask")
			(roundrect_rratio 0.25)
			(net 347 "/Peripherals/PCIE3_RST_CONN*")
			(pinfunction "R1.1")
			(pintype "passive")
		)
		(pad "2" smd roundrect
			(at -0.272 0.45 270)
			(size 0.4 0.5)
			(layers "F.Cu" "F.Paste" "F.Mask")
			(roundrect_rratio 0.25)
			(net 513 "/Peripherals/PCIE3_CLKREQ_CONN*")
			(pinfunction "R2.1")
			(pintype "passive")
		)
		(pad "3" smd roundrect
			(at 0.27 0.45 270)
			(size 0.4 0.5)
			(layers "F.Cu" "F.Paste" "F.Mask")
			(roundrect_rratio 0.25)
			(net 578 "/Peripherals/PCIE_WAKE_SEL_EXT_CONN")
			(pinfunction "R3.1")
			(pintype "passive")
		)
		(pad "4" smd roundrect
			(at 0.8 0.45 270)
			(size 0.4 0.5)
			(layers "F.Cu" "F.Paste" "F.Mask")
			(roundrect_rratio 0.25)
			(net 580 "/Peripherals/GPIO13_CONN")
			(pinfunction "R4.1")
			(pintype "passive")
		)
		(pad "5" smd roundrect
			(at 0.8 -0.452 270)
			(size 0.4 0.5)
			(layers "F.Cu" "F.Paste" "F.Mask")
			(roundrect_rratio 0.25)
			(net 84 "GPIO13")
			(pinfunction "R4.2")
			(pintype "passive")
		)
		(pad "6" smd roundrect
			(at 0.27 -0.452 270)
			(size 0.4 0.5)
			(layers "F.Cu" "F.Paste" "F.Mask")
			(roundrect_rratio 0.25)
			(net 427 "PCIE_WAKE_SEL_EXT")
			(pinfunction "R3.2")
			(pintype "passive")
		)
		(pad "7" smd roundrect
			(at -0.272 -0.452 270)
			(size 0.4 0.5)
			(layers "F.Cu" "F.Paste" "F.Mask")
			(roundrect_rratio 0.25)
			(net 128 "PCIE3_CLKREQ*")
			(pinfunction "R2.2")
			(pintype "passive")
		)
		(pad "8" smd roundrect
			(at -0.802 -0.452 270)
			(size 0.4 0.5)
			(layers "F.Cu" "F.Paste" "F.Mask")
			(roundrect_rratio 0.25)
			(net 120 "PCIE3_RST*")
			(pinfunction "R1.2")
			(pintype "passive")
		)
	)
	(footprint "antmicro-footprints:R_0402_1005Metric"
		(layer "F.Cu")
		(at 114.4 99.8 180)
		(descr "Resistor SMD 0402")
		(tags "resistor SMD 0402")
		(property "Reference" "R30"
			(at 3.05 -0.55 180)
			(layer "F.SilkS")
			(effects
				(font
					(size 0.7 0.7)
					(thickness 0.15)
				)
				(justify left bottom)
			)
		)
		(property "Value" "R_0R_0402"
			(at 0 1.4 180)
			(layer "F.Fab")
			(effects
				(font
					(size 0.7 0.7)
					(thickness 0.15)
				)
				(justify left bottom)
			)
		)
		(property "Footprint" "antmicro-footprints:R_0402_1005Metric"
			(at 0 0 180)
			(layer "F.Fab")
			(hide yes)
			(effects
				(font
					(size 1.27 1.27)
					(thickness 0.15)
				)
			)
		)
		(property "Datasheet" "https://industrial.panasonic.com/cdbs/www-data/pdf/RDA0000/AOA0000C301.pdf"
			(at 0 0 180)
			(layer "F.Fab")
			(hide yes)
			(effects
				(font
					(size 1.27 1.27)
					(thickness 0.15)
				)
			)
		)
		(property "Author" "Antmicro"
			(at 228.8 199.6 0)
			(layer "F.Fab")
			(hide yes)
			(effects
				(font
					(size 1 1)
					(thickness 0.15)
				)
			)
		)
		(property "Current" "1A"
			(at 228.8 199.6 0)
			(layer "F.Fab")
			(hide yes)
			(effects
				(font
					(size 1 1)
					(thickness 0.15)
				)
			)
		)
		(property "License" "Apache-2.0"
			(at 228.8 199.6 0)
			(layer "F.Fab")
			(hide yes)
			(effects
				(font
					(size 1 1)
					(thickness 0.15)
				)
			)
		)
		(property "MPN" "ERJ2GE0R00X"
			(at 228.8 199.6 0)
			(layer "F.Fab")
			(hide yes)
			(effects
				(font
					(size 1 1)
					(thickness 0.15)
				)
			)
		)
		(property "Manufacturer" "Panasonic"
			(at 228.8 199.6 0)
			(layer "F.Fab")
			(hide yes)
			(effects
				(font
					(size 1 1)
					(thickness 0.15)
				)
			)
		)
		(property "Tolerance" ""
			(at 228.8 199.6 0)
			(layer "F.Fab")
			(hide yes)
			(effects
				(font
					(size 1 1)
					(thickness 0.15)
				)
			)
		)
		(property "Val" "0R"
			(at 228.8 199.6 0)
			(layer "F.Fab")
			(hide yes)
			(effects
				(font
					(size 1 1)
					(thickness 0.15)
				)
			)
		)
		(sheetname "M.2")
		(sheetfile "m-2.kicad_sch")
		(attr smd exclude_from_pos_files exclude_from_bom dnp)
		(fp_rect
			(start -0.925 -0.47)
			(end 0.925 0.47)
			(stroke
				(width 0.05)
				(type default)
			)
			(fill none)
			(layer "F.CrtYd")
		)
		(fp_rect
			(start -0.5 -0.25)
			(end 0.5 0.25)
			(stroke
				(width 0.15)
				(type solid)
			)
			(fill none)
			(layer "F.Fab")
		)
		(fp_text user "${REFERENCE}"
			(at -0.95 3.168 180)
			(layer "F.Fab")
			(hide yes)
			(effects
				(font
					(size 0.7 0.7)
					(thickness 0.15)
				)
				(justify left bottom)
			)
		)
		(fp_text user "Author: Antmicro"
			(at -0.95 4.169 180)
			(layer "F.Fab")
			(hide yes)
			(effects
				(font
					(size 0.7 0.7)
					(thickness 0.15)
				)
				(justify left bottom)
			)
		)
		(fp_text user "License: Apache-2.0"
			(at -0.95 5.169 180)
			(layer "F.Fab")
			(hide yes)
			(effects
				(font
					(size 0.7 0.7)
					(thickness 0.15)
				)
				(justify left bottom)
			)
		)
		(pad "1" smd roundrect
			(at -0.48 0 180)
			(size 0.59 0.64)
			(layers "F.Cu" "F.Paste" "F.Mask")
			(roundrect_rratio 0.25)
			(net 221 "/M.2/M2_E_I2C_DAT")
			(pintype "passive")
		)
		(pad "2" smd roundrect
			(at 0.48 0 180)
			(size 0.59 0.64)
			(layers "F.Cu" "F.Paste" "F.Mask")
			(roundrect_rratio 0.25)
			(net 251 "SYS_SDA")
			(pintype "passive")
		)
	)
	(footprint "antmicro-footprints:TP_SMD_0.75mm"
		(layer "F.Cu")
		(at 95.55 82.2 180)
		(property "Reference" "TP4"
			(at -0.25 -0.4 180)
			(layer "F.SilkS")
			(effects
				(font
					(size 0.7 0.7)
					(thickness 0.15)
				)
				(justify left bottom)
			)
		)
		(property "Value" "TP_0.75mm_SMD"
			(at 0 1.2 180)
			(layer "F.Fab")
			(effects
				(font
					(size 0.7 0.7)
					(thickness 0.15)
				)
				(justify left bottom)
			)
		)
		(property "Footprint" "antmicro-footprints:TP_SMD_0.75mm"
			(at 0 0 180)
			(layer "F.Fab")
			(hide yes)
			(effects
				(font
					(size 1.27 1.27)
					(thickness 0.15)
				)
			)
		)
		(property "Author" "Antmicro"
			(at 191.1 164.4 0)
			(layer "F.Fab")
			(hide yes)
			(effects
				(font
					(size 1 1)
					(thickness 0.15)
				)
			)
		)
		(property "License" "Apache-2.0"
			(at 191.1 164.4 0)
			(layer "F.Fab")
			(hide yes)
			(effects
				(font
					(size 1 1)
					(thickness 0.15)
				)
			)
		)
		(property "MPN" ""
			(at 191.1 164.4 0)
			(layer "F.Fab")
			(hide yes)
			(effects
				(font
					(size 1 1)
					(thickness 0.15)
				)
			)
		)
		(property "Manufacturer" ""
			(at 191.1 164.4 0)
			(layer "F.Fab")
			(hide yes)
			(effects
				(font
					(size 1 1)
					(thickness 0.15)
				)
			)
		)
		(sheetname "SoM")
		(sheetfile "som.kicad_sch")
		(attr exclude_from_pos_files exclude_from_bom)
		(fp_circle
			(center 0 0)
			(end 0.475 0)
			(stroke
				(width 0.05)
				(type default)
			)
			(fill none)
			(layer "F.CrtYd")
		)
		(fp_text user "${REFERENCE}"
			(at -0.4 2.7 180)
			(layer "F.Fab")
			(hide yes)
			(effects
				(font
					(size 0.7 0.7)
					(thickness 0.15)
				)
				(justify left bottom)
			)
		)
		(fp_text user "License: Apache-2.0"
			(at -0.4 5.101 180)
			(layer "F.Fab")
			(hide yes)
			(effects
				(font
					(size 0.7 0.7)
					(thickness 0.15)
				)
				(justify left bottom)
			)
		)
		(fp_text user "Author: Antmicro"
			(at -0.4 3.901 180)
			(layer "F.Fab")
			(hide yes)
			(effects
				(font
					(size 0.7 0.7)
					(thickness 0.15)
				)
				(justify left bottom)
			)
		)
		(pad "1" smd circle
			(at 0 0 180)
			(size 0.75 0.75)
			(layers "F.Cu" "F.Mask")
			(net 746 "Net-(J15B-CAM1_MCLK)")
			(pinfunction "1")
			(pintype "passive")
		)
	)
	(footprint "antmicro-footprints:C_0402_1005Metric"
		(layer "F.Cu")
		(at 67.2 108.2 90)
		(descr "Capacitor SMD 0402")
		(tags "capacitor SMD 0402")
		(property "Reference" "C49"
			(at -1.1 1.35 90)
			(layer "F.SilkS")
			(effects
				(font
					(size 0.7 0.7)
					(thickness 0.15)
				)
				(justify left bottom)
			)
		)
		(property "Value" "C_10u_0402"
			(at -1.022927 2.155213 90)
			(layer "F.Fab")
			(effects
				(font
					(size 0.7 0.7)
					(thickness 0.15)
				)
				(justify left bottom)
			)
		)
		(property "Footprint" "antmicro-footprints:C_0402_1005Metric"
			(at 0 0 90)
			(layer "F.Fab")
			(hide yes)
			(effects
				(font
					(size 1.27 1.27)
					(thickness 0.15)
				)
			)
		)
		(property "Datasheet" "https://www.yageo.com/en/Chart/Download/pdf/CC0402MRX5R5BB106"
			(at 0 0 90)
			(layer "F.Fab")
			(hide yes)
			(effects
				(font
					(size 1.27 1.27)
					(thickness 0.15)
				)
			)
		)
		(property "Author" "Antmicro"
			(at 175.4 41 0)
			(layer "F.Fab")
			(hide yes)
			(effects
				(font
					(size 1 1)
					(thickness 0.15)
				)
			)
		)
		(property "Dielectric" ""
			(at 175.4 41 0)
			(layer "F.Fab")
			(hide yes)
			(effects
				(font
					(size 1 1)
					(thickness 0.15)
				)
			)
		)
		(property "License" "Apache-2.0"
			(at 175.4 41 0)
			(layer "F.Fab")
			(hide yes)
			(effects
				(font
					(size 1 1)
					(thickness 0.15)
				)
			)
		)
		(property "MPN" "CC0402MRX5R5BB106"
			(at 175.4 41 0)
			(layer "F.Fab")
			(hide yes)
			(effects
				(font
					(size 1 1)
					(thickness 0.15)
				)
			)
		)
		(property "Manufacturer" "YAGEO"
			(at 175.4 41 0)
			(layer "F.Fab")
			(hide yes)
			(effects
				(font
					(size 1 1)
					(thickness 0.15)
				)
			)
		)
		(property "Val" "10u"
			(at 175.4 41 0)
			(layer "F.Fab")
			(hide yes)
			(effects
				(font
					(size 1 1)
					(thickness 0.15)
				)
			)
		)
		(property "Voltage" ""
			(at 175.4 41 0)
			(layer "F.Fab")
			(hide yes)
			(effects
				(font
					(size 1 1)
					(thickness 0.15)
				)
			)
		)
		(sheetname "USB Debug, DP")
		(sheetfile "usb.kicad_sch")
		(attr smd)
		(fp_rect
			(start -0.925 -0.47)
			(end 0.925 0.47)
			(stroke
				(width 0.05)
				(type default)
			)
			(fill none)
			(layer "F.CrtYd")
		)
		(fp_line
			(start 0.504 -0.25)
			(end 0.504 0.248)
			(stroke
				(width 0.15)
				(type solid)
			)
			(layer "F.Fab")
		)
		(fp_line
			(start -0.494 -0.25)
			(end 0.504 -0.25)
			(stroke
				(width 0.15)
				(type solid)
			)
			(layer "F.Fab")
		)
		(fp_line
			(start 0.504 0.248)
			(end -0.494 0.248)
			(stroke
				(width 0.15)
				(type solid)
			)
			(layer "F.Fab")
		)
		(fp_line
			(start -0.494 0.248)
			(end -0.494 -0.25)
			(stroke
				(width 0.15)
				(type solid)
			)
			(layer "F.Fab")
		)
		(fp_text user "License: Apache-2.0"
			(at -0.939 5.799 90)
			(layer "F.Fab")
			(hide yes)
			(effects
				(font
					(size 0.7 0.7)
					(thickness 0.15)
				)
				(justify left bottom)
			)
		)
		(fp_text user "Author: Antmicro"
			(at -0.939 3.399 90)
			(layer "F.Fab")
			(hide yes)
			(effects
				(font
					(size 0.7 0.7)
					(thickness 0.15)
				)
				(justify left bottom)
			)
		)
		(fp_text user "${REFERENCE}"
			(at -0.939 4.599 90)
			(layer "F.Fab")
			(hide yes)
			(effects
				(font
					(size 0.7 0.7)
					(thickness 0.15)
				)
				(justify left bottom)
			)
		)
		(pad "1" smd roundrect
			(at -0.48 0 90)
			(size 0.59 0.64)
			(layers "F.Cu" "F.Paste" "F.Mask")
			(roundrect_rratio 0.25)
			(net 1 "GND")
			(pintype "passive")
		)
		(pad "2" smd roundrect
			(at 0.48 0 90)
			(size 0.59 0.64)
			(layers "F.Cu" "F.Paste" "F.Mask")
			(roundrect_rratio 0.25)
			(net 87 "+3V3")
			(pintype "passive")
		)
	)
	(footprint "antmicro-footprints:C_0402_1005Metric"
		(layer "F.Cu")
		(at 80.08 115.31 -90)
		(descr "Capacitor SMD 0402")
		(tags "capacitor SMD 0402")
		(property "Reference" "C33"
			(at -1.73 0.47 -90)
			(layer "F.SilkS")
			(effects
				(font
					(size 0.7 0.7)
					(thickness 0.15)
				)
				(justify left bottom)
			)
		)
		(property "Value" "C_100n_0402"
			(at 0 1.4 -90)
			(layer "F.Fab")
			(effects
				(font
					(size 0.7 0.7)
					(thickness 0.15)
				)
				(justify left bottom)
			)
		)
		(property "Footprint" "antmicro-footprints:C_0402_1005Metric"
			(at 0 0 -90)
			(layer "F.Fab")
			(hide yes)
			(effects
				(font
					(size 1.27 1.27)
					(thickness 0.15)
				)
			)
		)
		(property "Datasheet" "https://www.murata.com/products/productdetail?partno=GRM155R61H104KE14%23"
			(at 0 0 -90)
			(layer "F.Fab")
			(hide yes)
			(effects
				(font
					(size 1.27 1.27)
					(thickness 0.15)
				)
			)
		)
		(property "Author" "Antmicro"
			(at -35.23 195.39 0)
			(layer "F.Fab")
			(hide yes)
			(effects
				(font
					(size 1 1)
					(thickness 0.15)
				)
			)
		)
		(property "Dielectric" "X5R"
			(at -35.23 195.39 0)
			(layer "F.Fab")
			(hide yes)
			(effects
				(font
					(size 1 1)
					(thickness 0.15)
				)
			)
		)
		(property "License" "Apache-2.0"
			(at -35.23 195.39 0)
			(layer "F.Fab")
			(hide yes)
			(effects
				(font
					(size 1 1)
					(thickness 0.15)
				)
			)
		)
		(property "MPN" "GRM155R61H104KE14D"
			(at -35.23 195.39 0)
			(layer "F.Fab")
			(hide yes)
			(effects
				(font
					(size 1 1)
					(thickness 0.15)
				)
			)
		)
		(property "Manufacturer" "Murata"
			(at -35.23 195.39 0)
			(layer "F.Fab")
			(hide yes)
			(effects
				(font
					(size 1 1)
					(thickness 0.15)
				)
			)
		)
		(property "Val" "100n"
			(at -35.23 195.39 0)
			(layer "F.Fab")
			(hide yes)
			(effects
				(font
					(size 1 1)
					(thickness 0.15)
				)
			)
		)
		(property "Voltage" "50V"
			(at -35.23 195.39 0)
			(layer "F.Fab")
			(hide yes)
			(effects
				(font
					(size 1 1)
					(thickness 0.15)
				)
			)
		)
		(sheetname "USB Debug, DP")
		(sheetfile "usb.kicad_sch")
		(attr smd)
		(fp_rect
			(start -0.925 -0.47)
			(end 0.925 0.47)
			(stroke
				(width 0.05)
				(type default)
			)
			(fill none)
			(layer "F.CrtYd")
		)
		(fp_line
			(start -0.494 0.248)
			(end -0.494 -0.25)
			(stroke
				(width 0.15)
				(type solid)
			)
			(layer "F.Fab")
		)
		(fp_line
			(start 0.504 0.248)
			(end -0.494 0.248)
			(stroke
				(width 0.15)
				(type solid)
			)
			(layer "F.Fab")
		)
		(fp_line
			(start -0.494 -0.25)
			(end 0.504 -0.25)
			(stroke
				(width 0.15)
				(type solid)
			)
			(layer "F.Fab")
		)
		(fp_line
			(start 0.504 -0.25)
			(end 0.504 0.248)
			(stroke
				(width 0.15)
				(type solid)
			)
			(layer "F.Fab")
		)
		(fp_text user "${REFERENCE}"
			(at -0.932 3.168 -90)
			(layer "F.Fab")
			(hide yes)
			(effects
				(font
					(size 0.7 0.7)
					(thickness 0.15)
				)
				(justify left bottom)
			)
		)
		(fp_text user "License: Apache-2.0"
			(at -0.932 5.17 -90)
			(layer "F.Fab")
			(hide yes)
			(effects
				(font
					(size 0.7 0.7)
					(thickness 0.15)
				)
				(justify left bottom)
			)
		)
		(fp_text user "Author: Antmicro"
			(at -0.932 4.17 -90)
			(layer "F.Fab")
			(hide yes)
			(effects
				(font
					(size 0.7 0.7)
					(thickness 0.15)
				)
				(justify left bottom)
			)
		)
		(pad "1" smd roundrect
			(at -0.48 0 270)
			(size 0.59 0.64)
			(layers "F.Cu" "F.Paste" "F.Mask")
			(roundrect_rratio 0.25)
			(net 1 "GND")
			(pintype "passive")
		)
		(pad "2" smd roundrect
			(at 0.48 0 270)
			(size 0.59 0.64)
			(layers "F.Cu" "F.Paste" "F.Mask")
			(roundrect_rratio 0.25)
			(net 98 "EEPROM_PWR")
			(pintype "passive")
		)
	)
	(footprint "antmicro-footprints:R_0402_1005Metric"
		(layer "F.Cu")
		(at 64.05 113.115 -90)
		(descr "Resistor SMD 0402")
		(tags "resistor SMD 0402")
		(property "Reference" "R74"
			(at -1.065 0.4 90)
			(layer "F.SilkS")
			(effects
				(font
					(size 0.7 0.7)
					(thickness 0.15)
				)
				(justify right bottom)
			)
		)
		(property "Value" "R_10k_0402"
			(at 0 1.4 90)
			(layer "F.Fab")
			(effects
				(font
					(size 0.7 0.7)
					(thickness 0.15)
				)
				(justify right bottom)
			)
		)
		(property "Footprint" "antmicro-footprints:R_0402_1005Metric"
			(at 0 0 -90)
			(layer "F.Fab")
			(hide yes)
			(effects
				(font
					(size 1.27 1.27)
					(thickness 0.15)
				)
			)
		)
		(property "Datasheet" "https://www.bourns.com/docs/product-datasheets/cr.pdf"
			(at 0 0 -90)
			(layer "F.Fab")
			(hide yes)
			(effects
				(font
					(size 1.27 1.27)
					(thickness 0.15)
				)
			)
		)
		(property "Author" "Antmicro"
			(at -49.065 177.165 0)
			(layer "F.Fab")
			(hide yes)
			(effects
				(font
					(size 1 1)
					(thickness 0.15)
				)
			)
		)
		(property "License" "Apache-2.0"
			(at -49.065 177.165 0)
			(layer "F.Fab")
			(hide yes)
			(effects
				(font
					(size 1 1)
					(thickness 0.15)
				)
			)
		)
		(property "MPN" "CR0402-FX-1002GLF"
			(at -49.065 177.165 0)
			(layer "F.Fab")
			(hide yes)
			(effects
				(font
					(size 1 1)
					(thickness 0.15)
				)
			)
		)
		(property "Manufacturer" "Bourns"
			(at -49.065 177.165 0)
			(layer "F.Fab")
			(hide yes)
			(effects
				(font
					(size 1 1)
					(thickness 0.15)
				)
			)
		)
		(property "Tolerance" "1%"
			(at -49.065 177.165 0)
			(layer "F.Fab")
			(hide yes)
			(effects
				(font
					(size 1 1)
					(thickness 0.15)
				)
			)
		)
		(property "Val" "10k"
			(at -49.065 177.165 0)
			(layer "F.Fab")
			(hide yes)
			(effects
				(font
					(size 1 1)
					(thickness 0.15)
				)
			)
		)
		(sheetname "USB Debug, DP")
		(sheetfile "usb.kicad_sch")
		(attr smd)
		(fp_rect
			(start -0.925 -0.47)
			(end 0.925 0.47)
			(stroke
				(width 0.05)
				(type default)
			)
			(fill none)
			(layer "F.CrtYd")
		)
		(fp_rect
			(start -0.5 -0.25)
			(end 0.5 0.25)
			(stroke
				(width 0.15)
				(type solid)
			)
			(fill none)
			(layer "F.Fab")
		)
		(fp_text user "${REFERENCE}"
			(at -0.95 3.168 90)
			(layer "F.Fab")
			(hide yes)
			(effects
				(font
					(size 0.7 0.7)
					(thickness 0.15)
				)
				(justify right bottom)
			)
		)
		(fp_text user "Author: Antmicro"
			(at -0.95 4.169 90)
			(layer "F.Fab")
			(hide yes)
			(effects
				(font
					(size 0.7 0.7)
					(thickness 0.15)
				)
				(justify right bottom)
			)
		)
		(fp_text user "License: Apache-2.0"
			(at -0.95 5.169 90)
			(layer "F.Fab")
			(hide yes)
			(effects
				(font
					(size 0.7 0.7)
					(thickness 0.15)
				)
				(justify right bottom)
			)
		)
		(pad "1" smd roundrect
			(at -0.48 0 270)
			(size 0.59 0.64)
			(layers "F.Cu" "F.Paste" "F.Mask")
			(roundrect_rratio 0.25)
			(net 501 "/USB Debug, DP/USBC3_FLG")
			(pintype "passive")
		)
		(pad "2" smd roundrect
			(at 0.48 0 270)
			(size 0.59 0.64)
			(layers "F.Cu" "F.Paste" "F.Mask")
			(roundrect_rratio 0.25)
			(net 99 "+5V")
			(pintype "passive")
		)
	)
	(footprint "antmicro-footprints:R_0402_1005Metric"
		(layer "F.Cu")
		(at 65.91 93.35)
		(descr "Resistor SMD 0402")
		(tags "resistor SMD 0402")
		(property "Reference" "R239"
			(at -1.11 -1.4 0)
			(layer "F.SilkS")
			(effects
				(font
					(size 0.7 0.7)
					(thickness 0.15)
				)
				(justify left bottom)
			)
		)
		(property "Value" "R_499k_0402"
			(at -1.011843 1.772047 0)
			(layer "F.Fab")
			(effects
				(font
					(size 0.7 0.7)
					(thickness 0.15)
				)
				(justify left bottom)
			)
		)
		(property "Footprint" "antmicro-footprints:R_0402_1005Metric"
			(at 0 0 0)
			(layer "F.Fab")
			(hide yes)
			(effects
				(font
					(size 1.27 1.27)
					(thickness 0.15)
				)
			)
		)
		(property "Datasheet" "https://www.mouser.com/datasheet/2/54/cr-1858361.pdf"
			(at 0 0 0)
			(layer "F.Fab")
			(hide yes)
			(effects
				(font
					(size 1.27 1.27)
					(thickness 0.15)
				)
			)
		)
		(property "Author" "Antmicro"
			(at 0 0 0)
			(layer "F.Fab")
			(hide yes)
			(effects
				(font
					(size 1 1)
					(thickness 0.15)
				)
			)
		)
		(property "License" "Apache-2.0"
			(at 0 0 0)
			(layer "F.Fab")
			(hide yes)
			(effects
				(font
					(size 1 1)
					(thickness 0.15)
				)
			)
		)
		(property "MPN" "CR0402-FX-4993GLF"
			(at 0 0 0)
			(layer "F.Fab")
			(hide yes)
			(effects
				(font
					(size 1 1)
					(thickness 0.15)
				)
			)
		)
		(property "Manufacturer" "Bourns"
			(at 0 0 0)
			(layer "F.Fab")
			(hide yes)
			(effects
				(font
					(size 1 1)
					(thickness 0.15)
				)
			)
		)
		(property "Tolerance" "1%"
			(at 0 0 0)
			(layer "F.Fab")
			(hide yes)
			(effects
				(font
					(size 1 1)
					(thickness 0.15)
				)
			)
		)
		(property "Val" "499k"
			(at 0 0 0)
			(layer "F.Fab")
			(hide yes)
			(effects
				(font
					(size 1 1)
					(thickness 0.15)
				)
			)
		)
		(sheetname "Supply")
		(sheetfile "supply.kicad_sch")
		(attr smd)
		(fp_rect
			(start -0.925 -0.47)
			(end 0.925 0.47)
			(stroke
				(width 0.05)
				(type default)
			)
			(fill none)
			(layer "F.CrtYd")
		)
		(fp_rect
			(start -0.5 -0.25)
			(end 0.5 0.25)
			(stroke
				(width 0.15)
				(type solid)
			)
			(fill none)
			(layer "F.Fab")
		)
		(fp_text user "${REFERENCE}"
			(at -0.95 3.168 0)
			(layer "F.Fab")
			(hide yes)
			(effects
				(font
					(size 0.7 0.7)
					(thickness 0.15)
				)
				(justify left bottom)
			)
		)
		(fp_text user "License: Apache-2.0"
			(at -0.95 5.169 0)
			(layer "F.Fab")
			(hide yes)
			(effects
				(font
					(size 0.7 0.7)
					(thickness 0.15)
				)
				(justify left bottom)
			)
		)
		(fp_text user "Author: Antmicro"
			(at -0.95 4.169 0)
			(layer "F.Fab")
			(hide yes)
			(effects
				(font
					(size 0.7 0.7)
					(thickness 0.15)
				)
				(justify left bottom)
			)
		)
		(pad "1" smd roundrect
			(at -0.48 0)
			(size 0.59 0.64)
			(layers "F.Cu" "F.Paste" "F.Mask")
			(roundrect_rratio 0.25)
			(net 1 "GND")
			(pintype "passive")
		)
		(pad "2" smd roundrect
			(at 0.48 0)
			(size 0.59 0.64)
			(layers "F.Cu" "F.Paste" "F.Mask")
			(roundrect_rratio 0.25)
			(net 767 "/Supply/5V_MODE2")
			(pintype "passive")
		)
	)
	(footprint "antmicro-footprints:R_0402_1005Metric"
		(layer "F.Cu")
		(at 65.535 116.3 -90)
		(descr "Resistor SMD 0402")
		(tags "resistor SMD 0402")
		(property "Reference" "R84"
			(at 1.075 0.485 -90)
			(layer "F.SilkS")
			(effects
				(font
					(size 0.7 0.7)
					(thickness 0.15)
				)
				(justify left bottom)
			)
		)
		(property "Value" "R_0R_0402"
			(at 0 1.4 -90)
			(layer "F.Fab")
			(effects
				(font
					(size 0.7 0.7)
					(thickness 0.15)
				)
				(justify left bottom)
			)
		)
		(property "Footprint" "antmicro-footprints:R_0402_1005Metric"
			(at 0 0 -90)
			(layer "F.Fab")
			(hide yes)
			(effects
				(font
					(size 1.27 1.27)
					(thickness 0.15)
				)
			)
		)
		(property "Datasheet" "https://industrial.panasonic.com/cdbs/www-data/pdf/RDA0000/AOA0000C301.pdf"
			(at 0 0 -90)
			(layer "F.Fab")
			(hide yes)
			(effects
				(font
					(size 1.27 1.27)
					(thickness 0.15)
				)
			)
		)
		(property "Author" "Antmicro"
			(at -50.765 181.835 0)
			(layer "F.Fab")
			(hide yes)
			(effects
				(font
					(size 1 1)
					(thickness 0.15)
				)
			)
		)
		(property "Current" "1A"
			(at -50.765 181.835 0)
			(layer "F.Fab")
			(hide yes)
			(effects
				(font
					(size 1 1)
					(thickness 0.15)
				)
			)
		)
		(property "License" "Apache-2.0"
			(at -50.765 181.835 0)
			(layer "F.Fab")
			(hide yes)
			(effects
				(font
					(size 1 1)
					(thickness 0.15)
				)
			)
		)
		(property "MPN" "ERJ2GE0R00X"
			(at -50.765 181.835 0)
			(layer "F.Fab")
			(hide yes)
			(effects
				(font
					(size 1 1)
					(thickness 0.15)
				)
			)
		)
		(property "Manufacturer" "Panasonic"
			(at -50.765 181.835 0)
			(layer "F.Fab")
			(hide yes)
			(effects
				(font
					(size 1 1)
					(thickness 0.15)
				)
			)
		)
		(property "Tolerance" ""
			(at -50.765 181.835 0)
			(layer "F.Fab")
			(hide yes)
			(effects
				(font
					(size 1 1)
					(thickness 0.15)
				)
			)
		)
		(property "Val" "0R"
			(at -50.765 181.835 0)
			(layer "F.Fab")
			(hide yes)
			(effects
				(font
					(size 1 1)
					(thickness 0.15)
				)
			)
		)
		(sheetname "USB Debug, DP")
		(sheetfile "usb.kicad_sch")
		(attr smd)
		(fp_rect
			(start -0.925 -0.47)
			(end 0.925 0.47)
			(stroke
				(width 0.05)
				(type default)
			)
			(fill none)
			(layer "F.CrtYd")
		)
		(fp_rect
			(start -0.5 -0.25)
			(end 0.5 0.25)
			(stroke
				(width 0.15)
				(type solid)
			)
			(fill none)
			(layer "F.Fab")
		)
		(fp_text user "${REFERENCE}"
			(at -0.95 3.168 -90)
			(layer "F.Fab")
			(hide yes)
			(effects
				(font
					(size 0.7 0.7)
					(thickness 0.15)
				)
				(justify left bottom)
			)
		)
		(fp_text user "License: Apache-2.0"
			(at -0.95 5.169 -90)
			(layer "F.Fab")
			(hide yes)
			(effects
				(font
					(size 0.7 0.7)
					(thickness 0.15)
				)
				(justify left bottom)
			)
		)
		(fp_text user "Author: Antmicro"
			(at -0.95 4.169 -90)
			(layer "F.Fab")
			(hide yes)
			(effects
				(font
					(size 0.7 0.7)
					(thickness 0.15)
				)
				(justify left bottom)
			)
		)
		(pad "1" smd roundrect
			(at -0.48 0 270)
			(size 0.59 0.64)
			(layers "F.Cu" "F.Paste" "F.Mask")
			(roundrect_rratio 0.25)
			(net 553 "/USB Debug, DP/USBC0_5V_PEN")
			(pintype "passive")
		)
		(pad "2" smd roundrect
			(at 0.48 0 270)
			(size 0.59 0.64)
			(layers "F.Cu" "F.Paste" "F.Mask")
			(roundrect_rratio 0.25)
			(net 673 "Net-(U12-EN)")
			(pintype "passive")
		)
	)
	(footprint "antmicro-footprints:C_0402_1005Metric"
		(layer "F.Cu")
		(at 62.69 94.35 180)
		(descr "Capacitor SMD 0402")
		(tags "capacitor SMD 0402")
		(property "Reference" "C6"
			(at -2.32 -0.37 0)
			(layer "F.SilkS")
			(effects
				(font
					(size 0.7 0.7)
					(thickness 0.15)
				)
				(justify right bottom)
			)
		)
		(property "Value" "C_100n_0402"
			(at -1.022927 2.155213 0)
			(layer "F.Fab")
			(effects
				(font
					(size 0.7 0.7)
					(thickness 0.15)
				)
				(justify right bottom)
			)
		)
		(property "Footprint" "antmicro-footprints:C_0402_1005Metric"
			(at 0 0 180)
			(layer "F.Fab")
			(hide yes)
			(effects
				(font
					(size 1.27 1.27)
					(thickness 0.15)
				)
			)
		)
		(property "Datasheet" "https://www.murata.com/products/productdetail?partno=GRM155R61H104KE14%23"
			(at 0 0 180)
			(layer "F.Fab")
			(hide yes)
			(effects
				(font
					(size 1.27 1.27)
					(thickness 0.15)
				)
			)
		)
		(property "Author" "Antmicro"
			(at 125.38 188.72 0)
			(layer "F.Fab")
			(hide yes)
			(effects
				(font
					(size 1 1)
					(thickness 0.15)
				)
			)
		)
		(property "Dielectric" "X5R"
			(at 125.38 188.72 0)
			(layer "F.Fab")
			(hide yes)
			(effects
				(font
					(size 1 1)
					(thickness 0.15)
				)
			)
		)
		(property "License" "Apache-2.0"
			(at 125.38 188.72 0)
			(layer "F.Fab")
			(hide yes)
			(effects
				(font
					(size 1 1)
					(thickness 0.15)
				)
			)
		)
		(property "MPN" "GRM155R61H104KE14D"
			(at 125.38 188.72 0)
			(layer "F.Fab")
			(hide yes)
			(effects
				(font
					(size 1 1)
					(thickness 0.15)
				)
			)
		)
		(property "Manufacturer" "Murata"
			(at 125.38 188.72 0)
			(layer "F.Fab")
			(hide yes)
			(effects
				(font
					(size 1 1)
					(thickness 0.15)
				)
			)
		)
		(property "Val" "100n"
			(at 125.38 188.72 0)
			(layer "F.Fab")
			(hide yes)
			(effects
				(font
					(size 1 1)
					(thickness 0.15)
				)
			)
		)
		(property "Voltage" "50V"
			(at 125.38 188.72 0)
			(layer "F.Fab")
			(hide yes)
			(effects
				(font
					(size 1 1)
					(thickness 0.15)
				)
			)
		)
		(sheetname "Supply")
		(sheetfile "supply.kicad_sch")
		(attr smd)
		(fp_rect
			(start -0.925 -0.47)
			(end 0.925 0.47)
			(stroke
				(width 0.05)
				(type default)
			)
			(fill none)
			(layer "F.CrtYd")
		)
		(fp_line
			(start 0.504 0.248)
			(end -0.494 0.248)
			(stroke
				(width 0.15)
				(type solid)
			)
			(layer "F.Fab")
		)
		(fp_line
			(start 0.504 -0.25)
			(end 0.504 0.248)
			(stroke
				(width 0.15)
				(type solid)
			)
			(layer "F.Fab")
		)
		(fp_line
			(start -0.494 0.248)
			(end -0.494 -0.25)
			(stroke
				(width 0.15)
				(type solid)
			)
			(layer "F.Fab")
		)
		(fp_line
			(start -0.494 -0.25)
			(end 0.504 -0.25)
			(stroke
				(width 0.15)
				(type solid)
			)
			(layer "F.Fab")
		)
		(fp_text user "${REFERENCE}"
			(at -0.939 4.599 0)
			(layer "F.Fab")
			(hide yes)
			(effects
				(font
					(size 0.7 0.7)
					(thickness 0.15)
				)
				(justify right bottom)
			)
		)
		(fp_text user "License: Apache-2.0"
			(at -0.939 5.799 0)
			(layer "F.Fab")
			(hide yes)
			(effects
				(font
					(size 0.7 0.7)
					(thickness 0.15)
				)
				(justify right bottom)
			)
		)
		(fp_text user "Author: Antmicro"
			(at -0.939 3.399 0)
			(layer "F.Fab")
			(hide yes)
			(effects
				(font
					(size 0.7 0.7)
					(thickness 0.15)
				)
				(justify right bottom)
			)
		)
		(pad "1" smd roundrect
			(at -0.48 0 180)
			(size 0.59 0.64)
			(layers "F.Cu" "F.Paste" "F.Mask")
			(roundrect_rratio 0.25)
			(net 115 "VCC")
			(pintype "passive")
		)
		(pad "2" smd roundrect
			(at 0.48 0 180)
			(size 0.59 0.64)
			(layers "F.Cu" "F.Paste" "F.Mask")
			(roundrect_rratio 0.25)
			(net 1 "GND")
			(pintype "passive")
		)
	)
	(footprint "antmicro-footprints:C_0402_1005Metric"
		(layer "F.Cu")
		(at 134.71 92.3 180)
		(descr "Capacitor SMD 0402")
		(tags "capacitor SMD 0402")
		(property "Reference" "C111"
			(at 3.76 -0.5 180)
			(layer "F.SilkS")
			(effects
				(font
					(size 0.7 0.7)
					(thickness 0.15)
				)
				(justify left bottom)
			)
		)
		(property "Value" "C_100n_0402"
			(at 0 1.4 180)
			(layer "F.Fab")
			(effects
				(font
					(size 0.7 0.7)
					(thickness 0.15)
				)
				(justify left bottom)
			)
		)
		(property "Footprint" "antmicro-footprints:C_0402_1005Metric"
			(at 0 0 180)
			(layer "F.Fab")
			(hide yes)
			(effects
				(font
					(size 1.27 1.27)
					(thickness 0.15)
				)
			)
		)
		(property "Datasheet" "https://www.murata.com/products/productdetail?partno=GRM155R61H104KE14%23"
			(at 0 0 180)
			(layer "F.Fab")
			(hide yes)
			(effects
				(font
					(size 1.27 1.27)
					(thickness 0.15)
				)
			)
		)
		(property "Author" "Antmicro"
			(at 269.42 184.6 0)
			(layer "F.Fab")
			(hide yes)
			(effects
				(font
					(size 1 1)
					(thickness 0.15)
				)
			)
		)
		(property "Dielectric" "X5R"
			(at 269.42 184.6 0)
			(layer "F.Fab")
			(hide yes)
			(effects
				(font
					(size 1 1)
					(thickness 0.15)
				)
			)
		)
		(property "License" "Apache-2.0"
			(at 269.42 184.6 0)
			(layer "F.Fab")
			(hide yes)
			(effects
				(font
					(size 1 1)
					(thickness 0.15)
				)
			)
		)
		(property "MPN" "GRM155R61H104KE14D"
			(at 269.42 184.6 0)
			(layer "F.Fab")
			(hide yes)
			(effects
				(font
					(size 1 1)
					(thickness 0.15)
				)
			)
		)
		(property "Manufacturer" "Murata"
			(at 269.42 184.6 0)
			(layer "F.Fab")
			(hide yes)
			(effects
				(font
					(size 1 1)
					(thickness 0.15)
				)
			)
		)
		(property "Val" "100n"
			(at 269.42 184.6 0)
			(layer "F.Fab")
			(hide yes)
			(effects
				(font
					(size 1 1)
					(thickness 0.15)
				)
			)
		)
		(property "Voltage" "50V"
			(at 269.42 184.6 0)
			(layer "F.Fab")
			(hide yes)
			(effects
				(font
					(size 1 1)
					(thickness 0.15)
				)
			)
		)
		(sheetname "Peripherals")
		(sheetfile "peripherals.kicad_sch")
		(attr smd)
		(fp_rect
			(start -0.925 -0.47)
			(end 0.925 0.47)
			(stroke
				(width 0.05)
				(type default)
			)
			(fill none)
			(layer "F.CrtYd")
		)
		(fp_line
			(start 0.504 0.248)
			(end -0.494 0.248)
			(stroke
				(width 0.15)
				(type solid)
			)
			(layer "F.Fab")
		)
		(fp_line
			(start 0.504 -0.25)
			(end 0.504 0.248)
			(stroke
				(width 0.15)
				(type solid)
			)
			(layer "F.Fab")
		)
		(fp_line
			(start -0.494 0.248)
			(end -0.494 -0.25)
			(stroke
				(width 0.15)
				(type solid)
			)
			(layer "F.Fab")
		)
		(fp_line
			(start -0.494 -0.25)
			(end 0.504 -0.25)
			(stroke
				(width 0.15)
				(type solid)
			)
			(layer "F.Fab")
		)
		(fp_text user "License: Apache-2.0"
			(at -0.932 5.17 180)
			(layer "F.Fab")
			(hide yes)
			(effects
				(font
					(size 0.7 0.7)
					(thickness 0.15)
				)
				(justify left bottom)
			)
		)
		(fp_text user "${REFERENCE}"
			(at -0.932 3.168 180)
			(layer "F.Fab")
			(hide yes)
			(effects
				(font
					(size 0.7 0.7)
					(thickness 0.15)
				)
				(justify left bottom)
			)
		)
		(fp_text user "Author: Antmicro"
			(at -0.932 4.17 180)
			(layer "F.Fab")
			(hide yes)
			(effects
				(font
					(size 0.7 0.7)
					(thickness 0.15)
				)
				(justify left bottom)
			)
		)
		(pad "1" smd roundrect
			(at -0.48 0 180)
			(size 0.59 0.64)
			(layers "F.Cu" "F.Paste" "F.Mask")
			(roundrect_rratio 0.25)
			(net 414 "/Peripherals/USBSS2_TX_CONN_P")
			(pintype "passive")
		)
		(pad "2" smd roundrect
			(at 0.48 0 180)
			(size 0.59 0.64)
			(layers "F.Cu" "F.Paste" "F.Mask")
			(roundrect_rratio 0.25)
			(net 157 "USBSS1_TX_P")
			(pintype "passive")
		)
	)
	(footprint "antmicro-footprints:C_0603_1608Metric_EIA"
		(layer "F.Cu")
		(at 69.925 91.67 -90)
		(descr "Capacitor SMD 0603, IPC-7351 Density Level A")
		(tags "Capacitor 0603")
		(property "Reference" "C127"
			(at -6.406396 -14.62 -90)
			(layer "F.SilkS")
			(effects
				(font
					(size 0.7 0.7)
					(thickness 0.15)
				)
				(justify left bottom)
			)
		)
		(property "Value" "C_22u_16V_0603"
			(at -1.42757 1.770288 -90)
			(layer "F.Fab")
			(effects
				(font
					(size 0.7 0.7)
					(thickness 0.15)
				)
				(justify left bottom)
			)
		)
		(property "Footprint" "antmicro-footprints:C_0603_1608Metric_EIA"
			(at 0 0 -90)
			(layer "F.Fab")
			(hide yes)
			(effects
				(font
					(size 1.27 1.27)
					(thickness 0.15)
				)
			)
		)
		(property "Datasheet" "https://product.samsungsem.com/mlcc/CL10A226MO7JZN.do"
			(at 0 0 -90)
			(layer "F.Fab")
			(hide yes)
			(effects
				(font
					(size 1.27 1.27)
					(thickness 0.15)
				)
			)
		)
		(property "Description" "SMD Multilayer Ceramic Capacitor"
			(at 0 0 -90)
			(layer "F.Fab")
			(hide yes)
			(effects
				(font
					(size 1.27 1.27)
					(thickness 0.15)
				)
			)
		)
		(property "Manufacturer" "Samsung Electro-Mechanics"
			(at 0 0 -90)
			(unlocked yes)
			(layer "F.Fab")
			(hide yes)
			(effects
				(font
					(size 1 1)
					(thickness 0.15)
				)
			)
		)
		(property "MPN" "CL10A226MO7JZNC"
			(at 0 0 -90)
			(unlocked yes)
			(layer "F.Fab")
			(hide yes)
			(effects
				(font
					(size 1 1)
					(thickness 0.15)
				)
			)
		)
		(property "Val" "22u"
			(at 0 0 -90)
			(unlocked yes)
			(layer "F.Fab")
			(hide yes)
			(effects
				(font
					(size 1 1)
					(thickness 0.15)
				)
			)
		)
		(property "License" "Apache-2.0"
			(at 0 0 -90)
			(unlocked yes)
			(layer "F.Fab")
			(hide yes)
			(effects
				(font
					(size 1 1)
					(thickness 0.15)
				)
			)
		)
		(property "Author" "Antmicro"
			(at 0 0 -90)
			(unlocked yes)
			(layer "F.Fab")
			(hide yes)
			(effects
				(font
					(size 1 1)
					(thickness 0.15)
				)
			)
		)
		(property "Voltage" "16V"
			(at 0 0 -90)
			(unlocked yes)
			(layer "F.Fab")
			(hide yes)
			(effects
				(font
					(size 1 1)
					(thickness 0.15)
				)
			)
		)
		(property "Dielectric" ""
			(at 0 0 -90)
			(unlocked yes)
			(layer "F.Fab")
			(hide yes)
			(effects
				(font
					(size 1 1)
					(thickness 0.15)
				)
			)
		)
		(sheetname "Supply")
		(sheetfile "supply.kicad_sch")
		(attr smd)
		(fp_line
			(start -0.15 0.55)
			(end 0.15 0.55)
			(stroke
				(width 0.15)
				(type solid)
			)
			(layer "F.SilkS")
		)
		(fp_line
			(start -0.15 -0.55)
			(end 0.15 -0.55)
			(stroke
				(width 0.15)
				(type solid)
			)
			(layer "F.SilkS")
		)
		(fp_rect
			(start -1.25 -0.65)
			(end 1.25 0.65)
			(stroke
				(width 0.05)
				(type solid)
			)
			(fill none)
			(layer "F.CrtYd")
		)
		(fp_rect
			(start -0.8 -0.45)
			(end 0.8 0.45)
			(stroke
				(width 0.15)
				(type solid)
			)
			(fill none)
			(layer "F.Fab")
		)
		(fp_text user "License: Apache-2.0"
			(at -1.682 5.895 -90)
			(layer "F.Fab")
			(hide yes)
			(effects
				(font
					(size 0.7 0.7)
					(thickness 0.15)
				)
				(justify left bottom)
			)
		)
		(fp_text user "${REFERENCE}"
			(at -1.682 3.895 -90)
			(layer "F.Fab")
			(hide yes)
			(effects
				(font
					(size 0.7 0.7)
					(thickness 0.15)
				)
				(justify left bottom)
			)
		)
		(fp_text user "Author: Antmicro"
			(at -1.682 4.894 -90)
			(layer "F.Fab")
			(hide yes)
			(effects
				(font
					(size 0.7 0.7)
					(thickness 0.15)
				)
				(justify left bottom)
			)
		)
		(pad "1" smd roundrect
			(at -0.7 0 270)
			(size 0.8 1.1)
			(layers "F.Cu" "F.Paste" "F.Mask")
			(roundrect_rratio 0.2)
			(net 1 "GND")
			(pintype "passive")
		)
		(pad "2" smd roundrect
			(at 0.7 0 270)
			(size 0.8 1.1)
			(layers "F.Cu" "F.Paste" "F.Mask")
			(roundrect_rratio 0.2)
			(net 641 "/Supply/3V3_OUT")
			(pintype "passive")
		)
	)
	(footprint "antmicro-footprints:C_0402_1005Metric"
		(layer "F.Cu")
		(at 127.05 95.2 180)
		(descr "Capacitor SMD 0402")
		(tags "capacitor SMD 0402")
		(property "Reference" "C10"
			(at 1 -1.3 180)
			(layer "F.SilkS")
			(effects
				(font
					(size 0.7 0.7)
					(thickness 0.15)
				)
				(justify left bottom)
			)
		)
		(property "Value" "C_220n_0402"
			(at 0 1.4 180)
			(layer "F.Fab")
			(effects
				(font
					(size 0.7 0.7)
					(thickness 0.15)
				)
				(justify left bottom)
			)
		)
		(property "Footprint" "antmicro-footprints:C_0402_1005Metric"
			(at 0 0 180)
			(layer "F.Fab")
			(hide yes)
			(effects
				(font
					(size 1.27 1.27)
					(thickness 0.15)
				)
			)
		)
		(property "Datasheet" "https://www.yageo.com/en/Chart/Download/pdf/CC0402KRX5R6BB224"
			(at 0 0 180)
			(layer "F.Fab")
			(hide yes)
			(effects
				(font
					(size 1.27 1.27)
					(thickness 0.15)
				)
			)
		)
		(property "Author" "Antmicro"
			(at 254.1 190.4 0)
			(layer "F.Fab")
			(hide yes)
			(effects
				(font
					(size 1 1)
					(thickness 0.15)
				)
			)
		)
		(property "Dielectric" ""
			(at 254.1 190.4 0)
			(layer "F.Fab")
			(hide yes)
			(effects
				(font
					(size 1 1)
					(thickness 0.15)
				)
			)
		)
		(property "License" "Apache-2.0"
			(at 254.1 190.4 0)
			(layer "F.Fab")
			(hide yes)
			(effects
				(font
					(size 1 1)
					(thickness 0.15)
				)
			)
		)
		(property "MPN" "CC0402KRX5R6BB224"
			(at 254.1 190.4 0)
			(layer "F.Fab")
			(hide yes)
			(effects
				(font
					(size 1 1)
					(thickness 0.15)
				)
			)
		)
		(property "Manufacturer" "YAGEO"
			(at 254.1 190.4 0)
			(layer "F.Fab")
			(hide yes)
			(effects
				(font
					(size 1 1)
					(thickness 0.15)
				)
			)
		)
		(property "Val" "220n"
			(at 254.1 190.4 0)
			(layer "F.Fab")
			(hide yes)
			(effects
				(font
					(size 1 1)
					(thickness 0.15)
				)
			)
		)
		(property "Voltage" ""
			(at 254.1 190.4 0)
			(layer "F.Fab")
			(hide yes)
			(effects
				(font
					(size 1 1)
					(thickness 0.15)
				)
			)
		)
		(sheetname "M.2")
		(sheetfile "m-2.kicad_sch")
		(attr smd)
		(fp_rect
			(start -0.925 -0.47)
			(end 0.925 0.47)
			(stroke
				(width 0.05)
				(type default)
			)
			(fill none)
			(layer "F.CrtYd")
		)
		(fp_line
			(start 0.504 0.248)
			(end -0.494 0.248)
			(stroke
				(width 0.15)
				(type solid)
			)
			(layer "F.Fab")
		)
		(fp_line
			(start 0.504 -0.25)
			(end 0.504 0.248)
			(stroke
				(width 0.15)
				(type solid)
			)
			(layer "F.Fab")
		)
		(fp_line
			(start -0.494 0.248)
			(end -0.494 -0.25)
			(stroke
				(width 0.15)
				(type solid)
			)
			(layer "F.Fab")
		)
		(fp_line
			(start -0.494 -0.25)
			(end 0.504 -0.25)
			(stroke
				(width 0.15)
				(type solid)
			)
			(layer "F.Fab")
		)
		(fp_text user "Author: Antmicro"
			(at -0.932 4.17 180)
			(layer "F.Fab")
			(hide yes)
			(effects
				(font
					(size 0.7 0.7)
					(thickness 0.15)
				)
				(justify left bottom)
			)
		)
		(fp_text user "License: Apache-2.0"
			(at -0.932 5.17 180)
			(layer "F.Fab")
			(hide yes)
			(effects
				(font
					(size 0.7 0.7)
					(thickness 0.15)
				)
				(justify left bottom)
			)
		)
		(fp_text user "${REFERENCE}"
			(at -0.932 3.168 180)
			(layer "F.Fab")
			(hide yes)
			(effects
				(font
					(size 0.7 0.7)
					(thickness 0.15)
				)
				(justify left bottom)
			)
		)
		(pad "1" smd roundrect
			(at -0.48 0 180)
			(size 0.59 0.64)
			(layers "F.Cu" "F.Paste" "F.Mask")
			(roundrect_rratio 0.25)
			(net 450 "PCIE1_TX0_N")
			(pintype "passive")
		)
		(pad "2" smd roundrect
			(at 0.48 0 180)
			(size 0.59 0.64)
			(layers "F.Cu" "F.Paste" "F.Mask")
			(roundrect_rratio 0.25)
			(net 97 "/M.2/C_PCIE1_TX0_N")
			(pintype "passive")
		)
	)
	(footprint "antmicro-footprints:Bus_M.2_Socket_Key_E_TE_2199230-6"
		(locked yes)
		(layer "F.Cu")
		(at 120.73 95.12 -90)
		(property "Reference" "J1"
			(at -2 -1.2 90)
			(layer "F.SilkS")
			(effects
				(font
					(size 0.7 0.7)
					(thickness 0.15)
				)
				(justify right bottom)
			)
		)
		(property "Value" "Bus_M.2_2199230-6"
			(at -1.75 9.5 90)
			(layer "F.Fab")
			(effects
				(font
					(size 0.7 0.7)
					(thickness 0.15)
				)
				(justify right bottom)
			)
		)
		(property "Footprint" "antmicro-footprints:Bus_M.2_Socket_Key_E_TE_2199230-6"
			(at 0 0 -90)
			(layer "F.Fab")
			(hide yes)
			(effects
				(font
					(size 1.27 1.27)
					(thickness 0.15)
				)
			)
		)
		(property "Datasheet" "https://www.te.com/usa-en/product-2199230-6.datasheet.pdf"
			(at 0 0 -90)
			(layer "F.Fab")
			(hide yes)
			(effects
				(font
					(size 1.27 1.27)
					(thickness 0.15)
				)
			)
		)
		(property "Author" "Antmicro"
			(at 25.61 215.85 0)
			(layer "F.Fab")
			(hide yes)
			(effects
				(font
					(size 1 1)
					(thickness 0.15)
				)
			)
		)
		(property "License" "Apache-2.0"
			(at 25.61 215.85 0)
			(layer "F.Fab")
			(hide yes)
			(effects
				(font
					(size 1 1)
					(thickness 0.15)
				)
			)
		)
		(property "MPN" "2199230-6 "
			(at 25.61 215.85 0)
			(layer "F.Fab")
			(hide yes)
			(effects
				(font
					(size 1 1)
					(thickness 0.15)
				)
			)
		)
		(property "Manufacturer" "TE Connectivity"
			(at 25.61 215.85 0)
			(layer "F.Fab")
			(hide yes)
			(effects
				(font
					(size 1 1)
					(thickness 0.15)
				)
			)
		)
		(sheetname "M.2")
		(sheetfile "m-2.kicad_sch")
		(attr smd)
		(fp_line
			(start -9.599 4.1)
			(end -9.249 4.1)
			(stroke
				(width 0.15)
				(type solid)
			)
			(layer "F.SilkS")
		)
		(fp_line
			(start -3.75 4.1)
			(end -1.75 4.1)
			(stroke
				(width 0.15)
				(type solid)
			)
			(layer "F.SilkS")
		)
		(fp_line
			(start 9.251 4.1)
			(end 9.601 4.1)
			(stroke
				(width 0.15)
				(type solid)
			)
			(layer "F.SilkS")
		)
		(fp_line
			(start 9.601 4.1)
			(end 9.601 2.85)
			(stroke
				(width 0.15)
				(type solid)
			)
			(layer "F.SilkS")
		)
		(fp_line
			(start -10.999 2.85)
			(end -10.999 -1.5)
			(stroke
				(width 0.15)
				(type solid)
			)
			(layer "F.SilkS")
		)
		(fp_line
			(start -9.599 2.85)
			(end -9.599 4.1)
			(stroke
				(width 0.15)
				(type solid)
			)
			(layer "F.SilkS")
		)
		(fp_line
			(start -9.599 2.85)
			(end -10.999 2.85)
			(stroke
				(width 0.15)
				(type solid)
			)
			(layer "F.SilkS")
		)
		(fp_line
			(start 10.999 2.85)
			(end 9.601 2.85)
			(stroke
				(width 0.15)
				(type solid)
			)
			(layer "F.SilkS")
		)
		(fp_line
			(start 10.999 -1.5)
			(end 10.999 2.85)
			(stroke
				(width 0.15)
				(type solid)
			)
			(layer "F.SilkS")
		)
		(fp_line
			(start -3.499 -3.899)
			(end -1.499 -3.899)
			(stroke
				(width 0.15)
				(type solid)
			)
			(layer "F.SilkS")
		)
		(fp_circle
			(center -9.249 -5.64)
			(end -9.199 -5.64)
			(stroke
				(width 0.15)
				(type solid)
			)
			(fill solid)
			(layer "F.SilkS")
		)
		(fp_rect
			(start -11.94 -5.34)
			(end 11.95 5.35)
			(stroke
				(width 0.05)
				(type solid)
			)
			(fill none)
			(layer "F.CrtYd")
		)
		(fp_line
			(start -9.999 -0.25)
			(end 9.999 -0.25)
			(stroke
				(width 0.15)
				(type solid)
			)
			(layer "F.Fab")
		)
		(fp_text user "${REFERENCE}"
			(at -1.8 10.8 90)
			(layer "F.Fab")
			(hide yes)
			(effects
				(font
					(size 0.7 0.7)
					(thickness 0.15)
				)
				(justify right bottom)
			)
		)
		(fp_text user "License: Apache-2.0"
			(at -1.8 13.55 90)
			(layer "F.Fab")
			(hide yes)
			(effects
				(font
					(size 0.7 0.7)
					(thickness 0.15)
				)
				(justify right bottom)
			)
		)
		(fp_text user "Author: Antmicro"
			(at -1.8 12.1 90)
			(layer "F.Fab")
			(hide yes)
			(effects
				(font
					(size 0.7 0.7)
					(thickness 0.15)
				)
				(justify right bottom)
			)
		)
		(pad "" np_thru_hole circle
			(at -9.999 1.499 270)
			(size 1.1 1.1)
			(drill 1.1)
			(layers "*.Cu" "*.Mask")
		)
		(pad "" np_thru_hole circle
			(at 9.999 1.499 270)
			(size 1.6 1.6)
			(drill 1.6)
			(layers "*.Cu" "*.Mask")
		)
		(pad "1" smd rect
			(at -9.249 -3.749 270)
			(size 0.3 1.55)
			(layers "F.Cu" "F.Paste" "F.Mask")
			(net 1 "GND")
			(pinfunction "GND")
			(pintype "power_in")
		)
		(pad "2" smd rect
			(at -9.001 3.749 270)
			(size 0.3 1.55)
			(layers "F.Cu" "F.Paste" "F.Mask")
			(net 87 "+3V3")
			(pinfunction "3.3V")
			(pintype "power_in")
		)
		(pad "3" smd rect
			(at -8.751 -3.749 270)
			(size 0.3 1.55)
			(layers "F.Cu" "F.Paste" "F.Mask")
			(net 616 "/M.2/USB_E_P")
			(pinfunction "USB_D_P")
			(pintype "bidirectional")
		)
		(pad "4" smd rect
			(at -8.501 3.749 270)
			(size 0.3 1.55)
			(layers "F.Cu" "F.Paste" "F.Mask")
			(net 87 "+3V3")
			(pinfunction "3.3V")
			(pintype "passive")
		)
		(pad "5" smd rect
			(at -8.251 -3.749 270)
			(size 0.3 1.55)
			(layers "F.Cu" "F.Paste" "F.Mask")
			(net 617 "/M.2/USB_E_N")
			(pinfunction "USB_D_N")
			(pintype "bidirectional")
		)
		(pad "6" smd rect
			(at -8 3.749 270)
			(size 0.3 1.55)
			(layers "F.Cu" "F.Paste" "F.Mask")
			(net 169 "/M.2/~{LED1}")
			(pinfunction "~{LED_1}")
			(pintype "output")
		)
		(pad "7" smd rect
			(at -7.75 -3.749 270)
			(size 0.3 1.55)
			(layers "F.Cu" "F.Paste" "F.Mask")
			(net 1 "GND")
			(pinfunction "GND")
			(pintype "passive")
		)
		(pad "8" smd rect
			(at -7.5 3.749 270)
			(size 0.3 1.55)
			(layers "F.Cu" "F.Paste" "F.Mask")
			(net 170 "/M.2/M2_E_PCM_CLK")
			(pinfunction "PCM_CLK")
			(pintype "bidirectional")
		)
		(pad "9" smd rect
			(at -7.25 -3.749 270)
			(size 0.3 1.55)
			(layers "F.Cu" "F.Paste" "F.Mask")
			(net 190 "unconnected-(J1-SDIO_CLK-Pad9)")
			(pinfunction "SDIO_CLK")
			(pintype "input+no_connect")
		)
		(pad "10" smd rect
			(at -7 3.749 270)
			(size 0.3 1.55)
			(layers "F.Cu" "F.Paste" "F.Mask")
			(net 176 "/M.2/M2_E_PCM_SYNC")
			(pinfunction "PCM_SYNC")
			(pintype "bidirectional")
		)
		(pad "11" smd rect
			(at -6.75 -3.749 270)
			(size 0.3 1.55)
			(layers "F.Cu" "F.Paste" "F.Mask")
			(net 191 "unconnected-(J1-SDIO_CMD-Pad11)")
			(pinfunction "SDIO_CMD")
			(pintype "bidirectional+no_connect")
		)
		(pad "12" smd rect
			(at -6.5 3.749 270)
			(size 0.3 1.55)
			(layers "F.Cu" "F.Paste" "F.Mask")
			(net 651 "/M.2/M2_E_PCM_IN")
			(pinfunction "PCM_IN")
			(pintype "bidirectional")
		)
		(pad "13" smd rect
			(at -6.25 -3.749 270)
			(size 0.3 1.55)
			(layers "F.Cu" "F.Paste" "F.Mask")
			(net 202 "unconnected-(J1-SDIO_D0-Pad13)")
			(pinfunction "SDIO_D0")
			(pintype "bidirectional+no_connect")
		)
		(pad "14" smd rect
			(at -6 3.749 270)
			(size 0.3 1.55)
			(layers "F.Cu" "F.Paste" "F.Mask")
			(net 178 "/M.2/M2_E_PCM_OUT")
			(pinfunction "PCM_OUT")
			(pintype "bidirectional")
		)
		(pad "15" smd rect
			(at -5.75 -3.749 270)
			(size 0.3 1.55)
			(layers "F.Cu" "F.Paste" "F.Mask")
			(net 203 "unconnected-(J1-SDIO_D1-Pad15)")
			(pinfunction "SDIO_D1")
			(pintype "bidirectional+no_connect")
		)
		(pad "16" smd rect
			(at -5.5 3.749 270)
			(size 0.3 1.55)
			(layers "F.Cu" "F.Paste" "F.Mask")
			(net 652 "/M.2/~{LED2}")
			(pinfunction "~{LED_2}")
			(pintype "output")
		)
		(pad "17" smd rect
			(at -5.25 -3.749 270)
			(size 0.3 1.55)
			(layers "F.Cu" "F.Paste" "F.Mask")
			(net 208 "unconnected-(J1-SDIO_D2-Pad17)")
			(pinfunction "SDIO_D2")
			(pintype "bidirectional+no_connect")
		)
		(pad "18" smd rect
			(at -5.001 3.749 270)
			(size 0.3 1.55)
			(layers "F.Cu" "F.Paste" "F.Mask")
			(net 1 "GND")
			(pinfunction "GND")
			(pintype "passive")
		)
		(pad "19" smd rect
			(at -4.751 -3.749 270)
			(size 0.3 1.55)
			(layers "F.Cu" "F.Paste" "F.Mask")
			(net 209 "unconnected-(J1-SDIO_D3-Pad19)")
			(pinfunction "SDIO_D3")
			(pintype "bidirectional+no_connect")
		)
		(pad "20" smd rect
			(at -4.501 3.749 270)
			(size 0.3 1.55)
			(layers "F.Cu" "F.Paste" "F.Mask")
			(net 183 "/M.2/~{M2_E_UART_WAKE}")
			(pinfunction "~{UART_WAKE}")
			(pintype "output")
		)
		(pad "21" smd rect
			(at -4.251 -3.749 270)
			(size 0.3 1.55)
			(layers "F.Cu" "F.Paste" "F.Mask")
			(net 210 "unconnected-(J1-SDIO_~{WAKE}-Pad21)")
			(pinfunction "SDIO_~{WAKE}")
			(pintype "bidirectional+no_connect")
		)
		(pad "22" smd rect
			(at -4.001 3.749 270)
			(size 0.3 1.55)
			(layers "F.Cu" "F.Paste" "F.Mask")
			(net 192 "/M.2/M2_E_UART_RX")
			(pinfunction "UART_RXD")
			(pintype "bidirectional")
		)
		(pad "23" smd rect
			(at -3.75 -3.749 270)
			(size 0.3 1.55)
			(layers "F.Cu" "F.Paste" "F.Mask")
			(net 211 "unconnected-(J1-SDIO_~{RESET}-Pad23)")
			(pinfunction "SDIO_~{RESET}")
			(pintype "input+no_connect")
		)
		(pad "32" smd rect
			(at -1.5 3.749 270)
			(size 0.3 1.55)
			(layers "F.Cu" "F.Paste" "F.Mask")
			(net 188 "/M.2/M2_E_UART_TX")
			(pinfunction "UART_TXD")
			(pintype "bidirectional")
		)
		(pad "33" smd rect
			(at -1.25 -3.749 270)
			(size 0.3 1.55)
			(layers "F.Cu" "F.Paste" "F.Mask")
			(net 1 "GND")
			(pinfunction "GND")
			(pintype "passive")
		)
		(pad "34" smd rect
			(at -1 3.749 270)
			(size 0.3 1.55)
			(layers "F.Cu" "F.Paste" "F.Mask")
			(net 199 "/M.2/M2_E_UART_CTS")
			(pinfunction "UART_CTS")
			(pintype "bidirectional")
		)
		(pad "35" smd rect
			(at -0.75 -3.749 270)
			(size 0.3 1.55)
			(layers "F.Cu" "F.Paste" "F.Mask")
			(net 96 "/M.2/C_PCIE1_TX0_P")
			(pinfunction "PET0_P")
			(pintype "input")
		)
		(pad "36" smd rect
			(at -0.5 3.749 270)
			(size 0.3 1.55)
			(layers "F.Cu" "F.Paste" "F.Mask")
			(net 195 "/M.2/M2_E_UART_RTS")
			(pinfunction "UART_RTS")
			(pintype "bidirectional")
		)
		(pad "37" smd rect
			(at -0.25 -3.749 270)
			(size 0.3 1.55)
			(layers "F.Cu" "F.Paste" "F.Mask")
			(net 97 "/M.2/C_PCIE1_TX0_N")
			(pinfunction "PET0_N")
			(pintype "input")
		)
		(pad "38" smd rect
			(at 0 3.749 270)
			(size 0.3 1.55)
			(layers "F.Cu" "F.Paste" "F.Mask")
			(net 222 "unconnected-(J1-VENDOR_1-Pad38)")
			(pinfunction "VENDOR_1")
			(pintype "bidirectional+no_connect")
		)
		(pad "39" smd rect
			(at 0.25 -3.749 270)
			(size 0.3 1.55)
			(layers "F.Cu" "F.Paste" "F.Mask")
			(net 1 "GND")
			(pinfunction "GND")
			(pintype "passive")
		)
		(pad "40" smd rect
			(at 0.5 3.749 270)
			(size 0.3 1.55)
			(layers "F.Cu" "F.Paste" "F.Mask")
			(net 224 "unconnected-(J1-VENDOR_2-Pad40)")
			(pinfunction "VENDOR_2")
			(pintype "bidirectional+no_connect")
		)
		(pad "41" smd rect
			(at 0.75 -3.749 270)
			(size 0.3 1.55)
			(layers "F.Cu" "F.Paste" "F.Mask")
			(net 61 "PCIE1_RX0_P")
			(pinfunction "PER0_P")
			(pintype "output")
		)
		(pad "42" smd rect
			(at 1 3.749 270)
			(size 0.3 1.55)
			(layers "F.Cu" "F.Paste" "F.Mask")
			(net 226 "unconnected-(J1-VENDOR_3-Pad42)")
			(pinfunction "VENDOR_3")
			(pintype "bidirectional+no_connect")
		)
		(pad "43" smd rect
			(at 1.25 -3.749 270)
			(size 0.3 1.55)
			(layers "F.Cu" "F.Paste" "F.Mask")
			(net 60 "PCIE1_RX0_N")
			(pinfunction "PER0_N")
			(pintype "output")
		)
		(pad "44" smd rect
			(at 1.5 3.749 270)
			(size 0.3 1.55)
			(layers "F.Cu" "F.Paste" "F.Mask")
			(net 227 "unconnected-(J1-COEX3-Pad44)")
			(pinfunction "COEX3")
			(pintype "bidirectional+no_connect")
		)
		(pad "45" smd rect
			(at 1.75 -3.749 270)
			(size 0.3 1.55)
			(layers "F.Cu" "F.Paste" "F.Mask")
			(net 1 "GND")
			(pinfunction "GND")
			(pintype "passive")
		)
		(pad "46" smd rect
			(at 2 3.749 270)
			(size 0.3 1.55)
			(layers "F.Cu" "F.Paste" "F.Mask")
			(net 228 "unconnected-(J1-COEX_TXD-Pad46)")
			(pinfunction "COEX_TXD")
			(pintype "bidirectional+no_connect")
		)
		(pad "47" smd rect
			(at 2.25 -3.749 270)
			(size 0.3 1.55)
			(layers "F.Cu" "F.Paste" "F.Mask")
			(net 63 "PCIE1_CLK_P")
			(pinfunction "REFCLK0_P")
			(pintype "input")
		)
		(pad "48" smd rect
			(at 2.5 3.749 270)
			(size 0.3 1.55)
			(layers "F.Cu" "F.Paste" "F.Mask")
			(net 229 "unconnected-(J1-COEX_RXD-Pad48)")
			(pinfunction "COEX_RXD")
			(pintype "bidirectional+no_connect")
		)
		(pad "49" smd rect
			(at 2.75 -3.749 270)
			(size 0.3 1.55)
			(layers "F.Cu" "F.Paste" "F.Mask")
			(net 62 "PCIE1_CLK_N")
			(pinfunction "REFCLK0_N")
			(pintype "input")
		)
		(pad "50" smd rect
			(at 3 3.749 270)
			(size 0.3 1.55)
			(layers "F.Cu" "F.Paste" "F.Mask")
			(net 216 "/M.2/M2_E_SUSCLK")
			(pinfunction "SUSCLK")
			(pintype "input")
		)
		(pad "51" smd rect
			(at 3.25 -3.749 270)
			(size 0.3 1.55)
			(layers "F.Cu" "F.Paste" "F.Mask")
			(net 1 "GND")
			(pinfunction "GND")
			(pintype "passive")
		)
		(pad "52" smd rect
			(at 3.5 3.749 270)
			(size 0.3 1.55)
			(layers "F.Cu" "F.Paste" "F.Mask")
			(net 65 "PCIE1_RST*")
			(pinfunction "~{PERST0}")
			(pintype "input")
		)
		(pad "53" smd rect
			(at 3.75 -3.749 270)
			(size 0.3 1.55)
			(layers "F.Cu" "F.Paste" "F.Mask")
			(net 64 "PCIE1_CLKREQ*")
			(pinfunction "~{CLKREQ0}")
			(pintype "output")
		)
		(pad "54" smd rect
			(at 4 3.749 270)
			(size 0.3 1.55)
			(layers "F.Cu" "F.Paste" "F.Mask")
			(net 218 "/M.2/M2_E_W_DIS_2")
			(pinfunction "W_DISABLE2")
			(pintype "input")
		)
		(pad "55" smd rect
			(at 4.25 -3.749 270)
			(size 0.3 1.55)
			(layers "F.Cu" "F.Paste" "F.Mask")
			(net 171 "/M.2/PCIE_WAKE_SEL1")
			(pinfunction "~{PEWAKE0}")
			(pintype "output")
		)
		(pad "56" smd rect
			(at 4.5 3.749 270)
			(size 0.3 1.55)
			(layers "F.Cu" "F.Paste" "F.Mask")
			(net 220 "/M.2/M2_E_W_DIS_1")
			(pinfunction "W_DISABLE1")
			(pintype "input")
		)
		(pad "57" smd rect
			(at 4.75 -3.749 270)
			(size 0.3 1.55)
			(layers "F.Cu" "F.Paste" "F.Mask")
			(net 1 "GND")
			(pinfunction "GND")
			(pintype "passive")
		)
		(pad "58" smd rect
			(at 5 3.749 270)
			(size 0.3 1.55)
			(layers "F.Cu" "F.Paste" "F.Mask")
			(net 221 "/M.2/M2_E_I2C_DAT")
			(pinfunction "I2C_DATA")
			(pintype "bidirectional")
		)
		(pad "59" smd rect
			(at 5.25 -3.749 270)
			(size 0.3 1.55)
			(layers "F.Cu" "F.Paste" "F.Mask")
			(net 230 "unconnected-(J1-PET1_P-Pad59)")
			(pinfunction "PET1_P")
			(pintype "input+no_connect")
		)
		(pad "60" smd rect
			(at 5.5 3.749 270)
			(size 0.3 1.55)
			(layers "F.Cu" "F.Paste" "F.Mask")
			(net 223 "/M.2/M2_E_I2C_CLK")
			(pinfunction "I2C_CLK")
			(pintype "bidirectional")
		)
		(pad "61" smd rect
			(at 5.75 -3.749 270)
			(size 0.3 1.55)
			(layers "F.Cu" "F.Paste" "F.Mask")
			(net 231 "unconnected-(J1-PET1_N-Pad61)")
			(pinfunction "PET1_N")
			(pintype "input+no_connect")
		)
		(pad "62" smd rect
			(at 6 3.749 270)
			(size 0.3 1.55)
			(layers "F.Cu" "F.Paste" "F.Mask")
			(net 225 "/M.2/~{M2_E_ALERT}")
			(pinfunction "~{ALERT}")
			(pintype "output")
		)
		(pad "63" smd rect
			(at 6.25 -3.749 270)
			(size 0.3 1.55)
			(layers "F.Cu" "F.Paste" "F.Mask")
			(net 1 "GND")
			(pinfunction "GND")
			(pintype "passive")
		)
		(pad "64" smd rect
			(at 6.5 3.749 270)
			(size 0.3 1.55)
			(layers "F.Cu" "F.Paste" "F.Mask")
			(net 232 "unconnected-(J1-RFU-Pad64)")
			(pinfunction "RFU")
			(pintype "no_connect")
		)
		(pad "65" smd rect
			(at 6.75 -3.749 270)
			(size 0.3 1.55)
			(layers "F.Cu" "F.Paste" "F.Mask")
			(net 233 "unconnected-(J1-PER1_P-Pad65)")
			(pinfunction "PER1_P")
			(pintype "output+no_connect")
		)
		(pad "66" smd rect
			(at 6.999 3.749 270)
			(size 0.3 1.55)
			(layers "F.Cu" "F.Paste" "F.Mask")
			(net 280 "unconnected-(J1-UIM_SWP-Pad66)")
			(pinfunction "UIM_SWP")
			(pintype "bidirectional+no_connect")
		)
		(pad "67" smd rect
			(at 7.249 -3.749 270)
			(size 0.3 1.55)
			(layers "F.Cu" "F.Paste" "F.Mask")
			(net 288 "unconnected-(J1-PER1_N-Pad67)")
			(pinfunction "PER1_N")
			(pintype "output+no_connect")
		)
		(pad "68" smd rect
			(at 7.499 3.749 270)
			(size 0.3 1.55)
			(layers "F.Cu" "F.Paste" "F.Mask")
			(net 289 "unconnected-(J1-UIM_POWER_SNK-Pad68)")
			(pinfunction "UIM_POWER_SNK")
			(pintype "bidirectional+no_connect")
		)
		(pad "69" smd rect
			(at 7.749 -3.749 270)
			(size 0.3 1.55)
			(layers "F.Cu" "F.Paste" "F.Mask")
			(net 1 "GND")
			(pinfunction "GND")
			(pintype "passive")
		)
		(pad "70" smd rect
			(at 7.999 3.749 270)
			(size 0.3 1.55)
			(layers "F.Cu" "F.Paste" "F.Mask")
			(net 290 "unconnected-(J1-UIM_POWER_SRC-Pad70)")
			(pinfunction "UIM_POWER_SRC")
			(pintype "bidirectional+no_connect")
		)
		(pad "71" smd rect
			(at 8.249 -3.749 270)
			(size 0.3 1.55)
			(layers "F.Cu" "F.Paste" "F.Mask")
			(net 291 "unconnected-(J1-REFCLK1_P-Pad71)")
			(pinfunction "REFCLK1_P")
			(pintype "input+no_connect")
		)
		(pad "72" smd rect
			(at 8.499 3.749 270)
			(size 0.3 1.55)
			(layers "F.Cu" "F.Paste" "F.Mask")
			(net 87 "+3V3")
			(pinfunction "3.3V")
			(pintype "passive")
		)
		(pad "73" smd rect
			(at 8.749 -3.749 270)
			(size 0.3 1.55)
			(layers "F.Cu" "F.Paste" "F.Mask")
			(net 292 "unconnected-(J1-REFCLK1_N-Pad73)")
			(pinfunction "REFCLK1_N")
			(pintype "input+no_connect")
		)
		(pad "74" smd rect
			(at 8.999 3.749 270)
			(size 0.3 1.55)
			(layers "F.Cu" "F.Paste" "F.Mask")
			(net 87 "+3V3")
			(pinfunction "3.3V")
			(pintype "passive")
		)
		(pad "75" smd rect
			(at 9.249 -3.749 270)
			(size 0.3 1.55)
			(layers "F.Cu" "F.Paste" "F.Mask")
			(net 1 "GND")
			(pinfunction "GND")
			(pintype "passive")
		)
		(pad "MP" smd rect
			(at -10.35 -3.001 270)
			(size 1.2 2.75)
			(layers "F.Cu" "F.Paste" "F.Mask")
			(net 1 "GND")
			(pinfunction "MP")
			(pintype "passive")
		)
		(pad "MP" smd rect
			(at 10.351 -3.001 270)
			(size 1.2 2.75)
			(layers "F.Cu" "F.Paste" "F.Mask")
			(net 1 "GND")
			(pinfunction "MP")
			(pintype "passive")
		)
	)
	(footprint "antmicro-footprints:TP_SMD_0.75mm"
		(layer "F.Cu")
		(at 127.905 114.225 180)
		(property "Reference" "TP7"
			(at -0.445 -0.45 180)
			(layer "F.SilkS")
			(effects
				(font
					(size 0.7 0.7)
					(thickness 0.15)
				)
				(justify left bottom)
			)
		)
		(property "Value" "TP_0.75mm_SMD"
			(at 0 1.2 180)
			(layer "F.Fab")
			(effects
				(font
					(size 0.7 0.7)
					(thickness 0.15)
				)
				(justify left bottom)
			)
		)
		(property "Footprint" "antmicro-footprints:TP_SMD_0.75mm"
			(at 0 0 180)
			(layer "F.Fab")
			(hide yes)
			(effects
				(font
					(size 1.27 1.27)
					(thickness 0.15)
				)
			)
		)
		(property "Author" "Antmicro"
			(at 255.81 228.45 0)
			(layer "F.Fab")
			(hide yes)
			(effects
				(font
					(size 1 1)
					(thickness 0.15)
				)
			)
		)
		(property "License" "Apache-2.0"
			(at 255.81 228.45 0)
			(layer "F.Fab")
			(hide yes)
			(effects
				(font
					(size 1 1)
					(thickness 0.15)
				)
			)
		)
		(property "MPN" ""
			(at 255.81 228.45 0)
			(layer "F.Fab")
			(hide yes)
			(effects
				(font
					(size 1 1)
					(thickness 0.15)
				)
			)
		)
		(property "Manufacturer" ""
			(at 255.81 228.45 0)
			(layer "F.Fab")
			(hide yes)
			(effects
				(font
					(size 1 1)
					(thickness 0.15)
				)
			)
		)
		(sheetname "M.2")
		(sheetfile "m-2.kicad_sch")
		(attr exclude_from_pos_files exclude_from_bom)
		(fp_circle
			(center 0 0)
			(end 0.475 0)
			(stroke
				(width 0.05)
				(type default)
			)
			(fill none)
			(layer "F.CrtYd")
		)
		(fp_text user "${REFERENCE}"
			(at -0.4 2.7 180)
			(layer "F.Fab")
			(hide yes)
			(effects
				(font
					(size 0.7 0.7)
					(thickness 0.15)
				)
				(justify left bottom)
			)
		)
		(fp_text user "Author: Antmicro"
			(at -0.4 3.901 180)
			(layer "F.Fab")
			(hide yes)
			(effects
				(font
					(size 0.7 0.7)
					(thickness 0.15)
				)
				(justify left bottom)
			)
		)
		(fp_text user "License: Apache-2.0"
			(at -0.4 5.101 180)
			(layer "F.Fab")
			(hide yes)
			(effects
				(font
					(size 0.7 0.7)
					(thickness 0.15)
				)
				(justify left bottom)
			)
		)
		(pad "1" smd circle
			(at 0 0 180)
			(size 0.75 0.75)
			(layers "F.Cu" "F.Mask")
			(net 220 "/M.2/M2_E_W_DIS_1")
			(pinfunction "1")
			(pintype "passive")
		)
	)
	(footprint "antmicro-footprints:VQFN-HR-10_2x2mm"
		(layer "F.Cu")
		(at 56.73 90.05 180)
		(property "Reference" "U29"
			(at 1.375 -0.725 0)
			(layer "F.SilkS")
			(effects
				(font
					(size 0.7 0.7)
					(thickness 0.15)
				)
				(justify right top)
			)
		)
		(property "Value" "TPS259474"
			(at 0 2.8 0)
			(layer "F.Fab")
			(effects
				(font
					(size 0.7 0.7)
					(thickness 0.15)
				)
				(justify right top)
			)
		)
		(property "Footprint" "antmicro-footprints:VQFN-HR-10_2x2mm"
			(at 0 -0.045 0)
			(layer "F.Fab")
			(hide yes)
			(effects
				(font
					(size 1.27 1.27)
					(thickness 0.15)
				)
			)
		)
		(property "Datasheet" "https://www.ti.com/lit/ds/symlink/tps25947.pdf"
			(at 0 -0.045 0)
			(layer "F.Fab")
			(hide yes)
			(effects
				(font
					(size 1.27 1.27)
					(thickness 0.15)
				)
			)
		)
		(property "Description" "Reverse Current Blocking eFuse with Input Reverse Polarity Protection, 5.5A, 23V, -40 to 125 Deg C, VQFN-HR-10"
			(at -0.05 3.75 0)
			(layer "F.Fab")
			(hide yes)
			(effects
				(font
					(size 0.7 0.7)
					(thickness 0.15)
				)
			)
		)
		(property "MPN" "TPS259474ARPWR"
			(at 0 0 180)
			(unlocked yes)
			(layer "F.Fab")
			(hide yes)
			(effects
				(font
					(size 1 1)
					(thickness 0.15)
				)
			)
		)
		(property "Manufacturer" "Texas Instruments"
			(at 0 0 180)
			(unlocked yes)
			(layer "F.Fab")
			(hide yes)
			(effects
				(font
					(size 1 1)
					(thickness 0.15)
				)
			)
		)
		(property "Author" "Antmicro"
			(at 0 0 180)
			(unlocked yes)
			(layer "F.Fab")
			(hide yes)
			(effects
				(font
					(size 1 1)
					(thickness 0.15)
				)
			)
		)
		(property "License" "Apache-2.0"
			(at 0 0 180)
			(unlocked yes)
			(layer "F.Fab")
			(hide yes)
			(effects
				(font
					(size 1 1)
					(thickness 0.15)
				)
			)
		)
		(sheetname "Supply")
		(sheetfile "supply.kicad_sch")
		(attr smd)
		(fp_circle
			(center -1.2 -1.195)
			(end -1.15 -1.195)
			(stroke
				(width 0.15)
				(type solid)
			)
			(fill solid)
			(layer "F.SilkS")
		)
		(fp_rect
			(start -1.45 -1.45)
			(end 1.45 1.45)
			(stroke
				(width 0.05)
				(type default)
			)
			(fill none)
			(layer "F.CrtYd")
		)
		(fp_line
			(start 1 1)
			(end -1 1)
			(stroke
				(width 0.1)
				(type default)
			)
			(layer "F.Fab")
		)
		(fp_line
			(start 1 -1)
			(end 1 1)
			(stroke
				(width 0.1)
				(type default)
			)
			(layer "F.Fab")
		)
		(fp_line
			(start -0.5 -1)
			(end 1 -1)
			(stroke
				(width 0.1)
				(type default)
			)
			(layer "F.Fab")
		)
		(fp_line
			(start -0.5 -1)
			(end -1 -0.5)
			(stroke
				(width 0.1)
				(type default)
			)
			(layer "F.Fab")
		)
		(fp_line
			(start -1 1)
			(end -1 -0.5)
			(stroke
				(width 0.1)
				(type default)
			)
			(layer "F.Fab")
		)
		(fp_text user "${REFERENCE}"
			(at -2.851 5.45 0)
			(layer "F.Fab")
			(hide yes)
			(effects
				(font
					(size 0.7 0.7)
					(thickness 0.15)
				)
				(justify right top)
			)
		)
		(fp_text user "Author: Antmicro"
			(at -2.851 6.65 0)
			(layer "F.Fab")
			(hide yes)
			(effects
				(font
					(size 0.7 0.7)
					(thickness 0.15)
				)
				(justify right top)
			)
		)
		(fp_text user "License: Apache-2.0"
			(at -2.851 7.85 0)
			(layer "F.Fab")
			(hide yes)
			(effects
				(font
					(size 0.7 0.7)
					(thickness 0.15)
				)
				(justify right top)
			)
		)
		(pad "" smd roundrect
			(at -0.9 -0.6875 180)
			(size 0.6 0.275)
			(layers "F.Paste")
			(roundrect_rratio 0.1818181818)
			(thermal_bridge_angle 45)
		)
		(pad "" smd roundrect
			(at -0.9 0.6875 180)
			(size 0.6 0.275)
			(layers "F.Paste")
			(roundrect_rratio 0.1818181818)
			(thermal_bridge_angle 45)
		)
		(pad "" smd roundrect
			(at -0.7125 -0.875 180)
			(size 0.225 0.65)
			(layers "F.Paste")
			(roundrect_rratio 0.2222222222)
			(thermal_bridge_angle 45)
		)
		(pad "" smd roundrect
			(at -0.7125 0.875 180)
			(size 0.225 0.65)
			(layers "F.Paste")
			(roundrect_rratio 0.2222222222)
			(thermal_bridge_angle 45)
		)
		(pad "" smd roundrect
			(at -0.25 -0.63 180)
			(size 0.28 1.06)
			(layers "F.Paste")
			(roundrect_rratio 0.1785714286)
			(thermal_bridge_angle 45)
		)
		(pad "" smd roundrect
			(at -0.25 0.63 180)
			(size 0.28 1.06)
			(layers "F.Paste")
			(roundrect_rratio 0.1785714286)
			(thermal_bridge_angle 45)
		)
		(pad "" smd roundrect
			(at 0.25 -0.63 180)
			(size 0.28 1.06)
			(layers "F.Paste")
			(roundrect_rratio 0.1785714286)
			(thermal_bridge_angle 45)
		)
		(pad "" smd roundrect
			(at 0.25 0.63 180)
			(size 0.28 1.06)
			(layers "F.Paste")
			(roundrect_rratio 0.1785714286)
			(thermal_bridge_angle 45)
		)
		(pad "" smd roundrect
			(at 0.7125 -0.875 180)
			(size 0.225 0.65)
			(layers "F.Paste")
			(roundrect_rratio 0.2222222222)
			(thermal_bridge_angle 45)
		)
		(pad "" smd roundrect
			(at 0.7125 0.875 180)
			(size 0.225 0.65)
			(layers "F.Paste")
			(roundrect_rratio 0.2222222222)
			(thermal_bridge_angle 45)
		)
		(pad "" smd roundrect
			(at 0.9 -0.6875 180)
			(size 0.6 0.275)
			(layers "F.Paste")
			(roundrect_rratio 0.1818181818)
			(thermal_bridge_angle 45)
		)
		(pad "" smd roundrect
			(at 0.9 0.6875 180)
			(size 0.6 0.275)
			(layers "F.Paste")
			(roundrect_rratio 0.1818181818)
			(thermal_bridge_angle 45)
		)
		(pad "1" smd roundrect
			(at -0.9 -0.7 180)
			(size 0.6 0.3)
			(layers "F.Cu" "F.Mask")
			(roundrect_rratio 0.1666666667)
			(net 787 "+5V_SoM")
			(pinfunction "EN/UVLO")
			(pintype "input")
			(thermal_bridge_angle 45)
		)
		(pad "1" smd roundrect
			(at -0.725 -0.875)
			(size 0.25 0.65)
			(layers "F.Cu" "F.Mask")
			(roundrect_rratio 0.2)
			(net 787 "+5V_SoM")
			(pinfunction "EN/UVLO")
			(pintype "input")
			(thermal_bridge_angle 45)
		)
		(pad "2" smd roundrect
			(at -0.9 -0.225 180)
			(size 0.6 0.25)
			(layers "F.Cu" "F.Paste" "F.Mask")
			(roundrect_rratio 0.2)
			(net 1 "GND")
			(pinfunction "OVLO")
			(pintype "input")
			(thermal_bridge_angle 45)
		)
		(pad "3" smd roundrect
			(at -0.9 0.225 180)
			(size 0.6 0.25)
			(layers "F.Cu" "F.Paste" "F.Mask")
			(roundrect_rratio 0.2)
			(net 792 "Net-(U29-PG)")
			(pinfunction "PG")
			(pintype "output")
			(thermal_bridge_angle 45)
		)
		(pad "4" smd roundrect
			(at -0.9 0.7 180)
			(size 0.6 0.3)
			(layers "F.Cu" "F.Mask")
			(roundrect_rratio 0.1666666667)
			(net 787 "+5V_SoM")
			(pinfunction "PGTH")
			(pintype "input")
			(thermal_bridge_angle 45)
		)
		(pad "4" smd roundrect
			(at -0.725 0.875)
			(size 0.25 0.65)
			(layers "F.Cu" "F.Mask")
			(roundrect_rratio 0.2)
			(net 787 "+5V_SoM")
			(pinfunction "PGTH")
			(pintype "input")
			(thermal_bridge_angle 45)
		)
		(pad "5" smd roundrect
			(at -0.25 0 180)
			(size 0.3 2.4)
			(layers "F.Cu" "F.Mask")
			(roundrect_rratio 0.25)
			(net 787 "+5V_SoM")
			(pinfunction "IN")
			(pintype "power_in")
			(thermal_bridge_angle 45)
		)
		(pad "6" smd roundrect
			(at 0.25 0 180)
			(size 0.3 2.4)
			(layers "F.Cu" "F.Mask")
			(roundrect_rratio 0.25)
			(net 788 "VDD_SoM")
			(pinfunction "OUT")
			(pintype "power_out")
			(thermal_bridge_angle 45)
		)
		(pad "7" smd roundrect
			(at 0.725 0.875)
			(size 0.25 0.65)
			(layers "F.Cu" "F.Mask")
			(roundrect_rratio 0.2)
			(net 751 "Net-(U29-DVDT)")
			(pinfunction "DVDT")
			(pintype "output")
			(thermal_bridge_angle 45)
		)
		(pad "7" smd roundrect
			(at 0.9 0.7)
			(size 0.6 0.3)
			(layers "F.Cu" "F.Mask")
			(roundrect_rratio 0.1666666667)
			(net 751 "Net-(U29-DVDT)")
			(pinfunction "DVDT")
			(pintype "output")
			(thermal_bridge_angle 45)
		)
		(pad "8" smd roundrect
			(at 0.9 0.225)
			(size 0.6 0.25)
			(layers "F.Cu" "F.Paste" "F.Mask")
			(roundrect_rratio 0.2)
			(net 1 "GND")
			(pinfunction "GND")
			(pintype "power_in")
			(thermal_bridge_angle 45)
		)
		(pad "9" smd roundrect
			(at 0.9 -0.225)
			(size 0.6 0.25)
			(layers "F.Cu" "F.Paste" "F.Mask")
			(roundrect_rratio 0.2)
			(net 790 "Net-(U29-ILIM)")
			(pinfunction "ILIM")
			(pintype "output")
			(thermal_bridge_angle 45)
		)
		(pad "10" smd roundrect
			(at 0.725 -0.875)
			(size 0.25 0.65)
			(layers "F.Cu" "F.Mask")
			(roundrect_rratio 0.2)
			(net 794 "unconnected-(U29-ITIMER-Pad10)")
			(pinfunction "ITIMER")
			(pintype "output+no_connect")
			(thermal_bridge_angle 45)
		)
		(pad "10" smd roundrect
			(at 0.9 -0.7)
			(size 0.6 0.3)
			(layers "F.Cu" "F.Mask")
			(roundrect_rratio 0.1666666667)
			(net 795 "unconnected-(U29-ITIMER-Pad10)_1")
			(pinfunction "ITIMER")
			(pintype "output+no_connect")
			(thermal_bridge_angle 45)
		)
	)
	(footprint "antmicro-footprints:R_0402_1005Metric"
		(layer "F.Cu")
		(at 68.67 97.5 90)
		(descr "Resistor SMD 0402")
		(tags "resistor SMD 0402")
		(property "Reference" "R263"
			(at -1.1 1.355 90)
			(layer "F.SilkS")
			(effects
				(font
					(size 0.7 0.7)
					(thickness 0.15)
				)
				(justify left bottom)
			)
		)
		(property "Value" "R_20k_0402"
			(at -1.011843 1.772047 90)
			(layer "F.Fab")
			(effects
				(font
					(size 0.7 0.7)
					(thickness 0.15)
				)
				(justify left bottom)
			)
		)
		(property "Footprint" "antmicro-footprints:R_0402_1005Metric"
			(at 0 0 90)
			(layer "F.Fab")
			(hide yes)
			(effects
				(font
					(size 1.27 1.27)
					(thickness 0.15)
				)
			)
		)
		(property "Datasheet" "https://www.bourns.com/docs/product-datasheets/cr.pdf"
			(at 0 0 90)
			(layer "F.Fab")
			(hide yes)
			(effects
				(font
					(size 1.27 1.27)
					(thickness 0.15)
				)
			)
		)
		(property "Description" "SMD Chip Resistor, 20 kohm, ± 1%, 62.5 mW, 0402 [1005 Metric], Thick Film, General Purpose"
			(at 0 0 90)
			(layer "F.Fab")
			(hide yes)
			(effects
				(font
					(size 1.27 1.27)
					(thickness 0.15)
				)
			)
		)
		(property "Author" "Antmicro"
			(at 166.17 28.83 0)
			(layer "F.Fab")
			(hide yes)
			(effects
				(font
					(size 1 1)
					(thickness 0.15)
				)
			)
		)
		(property "License" "Apache-2.0"
			(at 166.17 28.83 0)
			(layer "F.Fab")
			(hide yes)
			(effects
				(font
					(size 1 1)
					(thickness 0.15)
				)
			)
		)
		(property "MPN" "CR0402-FX-2002GLF"
			(at 166.17 28.83 0)
			(layer "F.Fab")
			(hide yes)
			(effects
				(font
					(size 1 1)
					(thickness 0.15)
				)
			)
		)
		(property "Manufacturer" "Bourns"
			(at 166.17 28.83 0)
			(layer "F.Fab")
			(hide yes)
			(effects
				(font
					(size 1 1)
					(thickness 0.15)
				)
			)
		)
		(property "Tolerance" "1%"
			(at 166.17 28.83 0)
			(layer "F.Fab")
			(hide yes)
			(effects
				(font
					(size 1 1)
					(thickness 0.15)
				)
			)
		)
		(property "Val" "20k"
			(at 166.17 28.83 0)
			(layer "F.Fab")
			(hide yes)
			(effects
				(font
					(size 1 1)
					(thickness 0.15)
				)
			)
		)
		(sheetname "Supply")
		(sheetfile "supply.kicad_sch")
		(attr smd)
		(fp_rect
			(start -0.925 -0.47)
			(end 0.925 0.47)
			(stroke
				(width 0.05)
				(type default)
			)
			(fill none)
			(layer "F.CrtYd")
		)
		(fp_rect
			(start -0.5 -0.25)
			(end 0.5 0.25)
			(stroke
				(width 0.15)
				(type solid)
			)
			(fill none)
			(layer "F.Fab")
		)
		(fp_text user "License: Apache-2.0"
			(at -0.95 5.169 90)
			(layer "F.Fab")
			(hide yes)
			(effects
				(font
					(size 0.7 0.7)
					(thickness 0.15)
				)
				(justify left bottom)
			)
		)
		(fp_text user "Author: Antmicro"
			(at -0.95 4.169 90)
			(layer "F.Fab")
			(hide yes)
			(effects
				(font
					(size 0.7 0.7)
					(thickness 0.15)
				)
				(justify left bottom)
			)
		)
		(fp_text user "${REFERENCE}"
			(at -0.95 3.168 90)
			(layer "F.Fab")
			(hide yes)
			(effects
				(font
					(size 0.7 0.7)
					(thickness 0.15)
				)
				(justify left bottom)
			)
		)
		(pad "1" smd roundrect
			(at -0.48 0 90)
			(size 0.59 0.64)
			(layers "F.Cu" "F.Paste" "F.Mask")
			(roundrect_rratio 0.25)
			(net 712 "/Supply/5V_EN")
			(pintype "passive")
		)
		(pad "2" smd roundrect
			(at 0.48 0 90)
			(size 0.59 0.64)
			(layers "F.Cu" "F.Paste" "F.Mask")
			(roundrect_rratio 0.25)
			(net 115 "VCC")
			(pintype "passive")
		)
	)
	(footprint "antmicro-footprints:R_0402_1005Metric"
		(layer "F.Cu")
		(at 38.2 104.7 180)
		(descr "Resistor SMD 0402")
		(tags "resistor SMD 0402")
		(property "Reference" "R198"
			(at 3.65 -0.4 180)
			(layer "F.SilkS")
			(effects
				(font
					(size 0.7 0.7)
					(thickness 0.15)
				)
				(justify left bottom)
			)
		)
		(property "Value" "R_470k_0402"
			(at 0 1.4 180)
			(layer "F.Fab")
			(effects
				(font
					(size 0.7 0.7)
					(thickness 0.15)
				)
				(justify left bottom)
			)
		)
		(property "Footprint" "antmicro-footprints:R_0402_1005Metric"
			(at 0 0 180)
			(layer "F.Fab")
			(hide yes)
			(effects
				(font
					(size 1.27 1.27)
					(thickness 0.15)
				)
			)
		)
		(property "Datasheet" "https://www.bourns.com/docs/product-datasheets/cr.pdf"
			(at 0 0 180)
			(layer "F.Fab")
			(hide yes)
			(effects
				(font
					(size 1.27 1.27)
					(thickness 0.15)
				)
			)
		)
		(property "Author" "Antmicro"
			(at 76.4 209.4 0)
			(layer "F.Fab")
			(hide yes)
			(effects
				(font
					(size 1 1)
					(thickness 0.15)
				)
			)
		)
		(property "License" "Apache-2.0"
			(at 76.4 209.4 0)
			(layer "F.Fab")
			(hide yes)
			(effects
				(font
					(size 1 1)
					(thickness 0.15)
				)
			)
		)
		(property "MPN" "CR0402-FX-4703GLF"
			(at 76.4 209.4 0)
			(layer "F.Fab")
			(hide yes)
			(effects
				(font
					(size 1 1)
					(thickness 0.15)
				)
			)
		)
		(property "Manufacturer" "Bourns"
			(at 76.4 209.4 0)
			(layer "F.Fab")
			(hide yes)
			(effects
				(font
					(size 1 1)
					(thickness 0.15)
				)
			)
		)
		(property "Tolerance" "1%"
			(at 76.4 209.4 0)
			(layer "F.Fab")
			(hide yes)
			(effects
				(font
					(size 1 1)
					(thickness 0.15)
				)
			)
		)
		(property "Val" "470k"
			(at 76.4 209.4 0)
			(layer "F.Fab")
			(hide yes)
			(effects
				(font
					(size 1 1)
					(thickness 0.15)
				)
			)
		)
		(sheetname "Ethernet")
		(sheetfile "ethernet.kicad_sch")
		(attr smd)
		(fp_rect
			(start -0.925 -0.47)
			(end 0.925 0.47)
			(stroke
				(width 0.05)
				(type default)
			)
			(fill none)
			(layer "F.CrtYd")
		)
		(fp_rect
			(start -0.5 -0.25)
			(end 0.5 0.25)
			(stroke
				(width 0.15)
				(type solid)
			)
			(fill none)
			(layer "F.Fab")
		)
		(fp_text user "License: Apache-2.0"
			(at -0.95 5.169 180)
			(layer "F.Fab")
			(hide yes)
			(effects
				(font
					(size 0.7 0.7)
					(thickness 0.15)
				)
				(justify left bottom)
			)
		)
		(fp_text user "Author: Antmicro"
			(at -0.95 4.169 180)
			(layer "F.Fab")
			(hide yes)
			(effects
				(font
					(size 0.7 0.7)
					(thickness 0.15)
				)
				(justify left bottom)
			)
		)
		(fp_text user "${REFERENCE}"
			(at -0.95 3.168 180)
			(layer "F.Fab")
			(hide yes)
			(effects
				(font
					(size 0.7 0.7)
					(thickness 0.15)
				)
				(justify left bottom)
			)
		)
		(pad "1" smd roundrect
			(at -0.48 0 180)
			(size 0.59 0.64)
			(layers "F.Cu" "F.Paste" "F.Mask")
			(roundrect_rratio 0.25)
			(net 127 "/Ethernet/POE_ACTIVE")
			(pintype "passive")
		)
		(pad "2" smd roundrect
			(at 0.48 0 180)
			(size 0.59 0.64)
			(layers "F.Cu" "F.Paste" "F.Mask")
			(roundrect_rratio 0.25)
			(net 105 "/Ethernet/VDD")
			(pintype "passive")
		)
	)
	(footprint "antmicro-footprints:C_0402_1005Metric"
		(layer "F.Cu")
		(at 71.7 103.35 90)
		(descr "Capacitor SMD 0402")
		(tags "capacitor SMD 0402")
		(property "Reference" "C54"
			(at 0.8 0.45 90)
			(layer "F.SilkS")
			(effects
				(font
					(size 0.7 0.7)
					(thickness 0.15)
				)
				(justify left bottom)
			)
		)
		(property "Value" "C_100n_0402"
			(at 0 1.4 90)
			(layer "F.Fab")
			(effects
				(font
					(size 0.7 0.7)
					(thickness 0.15)
				)
				(justify left bottom)
			)
		)
		(property "Footprint" "antmicro-footprints:C_0402_1005Metric"
			(at 0 0 90)
			(layer "F.Fab")
			(hide yes)
			(effects
				(font
					(size 1.27 1.27)
					(thickness 0.15)
				)
			)
		)
		(property "Datasheet" "https://www.murata.com/products/productdetail?partno=GRM155R61H104KE14%23"
			(at 0 0 90)
			(layer "F.Fab")
			(hide yes)
			(effects
				(font
					(size 1.27 1.27)
					(thickness 0.15)
				)
			)
		)
		(property "Author" "Antmicro"
			(at 175.05 31.65 0)
			(layer "F.Fab")
			(hide yes)
			(effects
				(font
					(size 1 1)
					(thickness 0.15)
				)
			)
		)
		(property "Dielectric" "X5R"
			(at 175.05 31.65 0)
			(layer "F.Fab")
			(hide yes)
			(effects
				(font
					(size 1 1)
					(thickness 0.15)
				)
			)
		)
		(property "License" "Apache-2.0"
			(at 175.05 31.65 0)
			(layer "F.Fab")
			(hide yes)
			(effects
				(font
					(size 1 1)
					(thickness 0.15)
				)
			)
		)
		(property "MPN" "GRM155R61H104KE14D"
			(at 175.05 31.65 0)
			(layer "F.Fab")
			(hide yes)
			(effects
				(font
					(size 1 1)
					(thickness 0.15)
				)
			)
		)
		(property "Manufacturer" "Murata"
			(at 175.05 31.65 0)
			(layer "F.Fab")
			(hide yes)
			(effects
				(font
					(size 1 1)
					(thickness 0.15)
				)
			)
		)
		(property "Val" "100n"
			(at 175.05 31.65 0)
			(layer "F.Fab")
			(hide yes)
			(effects
				(font
					(size 1 1)
					(thickness 0.15)
				)
			)
		)
		(property "Voltage" "50V"
			(at 175.05 31.65 0)
			(layer "F.Fab")
			(hide yes)
			(effects
				(font
					(size 1 1)
					(thickness 0.15)
				)
			)
		)
		(sheetname "USB Debug, DP")
		(sheetfile "usb.kicad_sch")
		(attr smd)
		(fp_rect
			(start -0.925 -0.47)
			(end 0.925 0.47)
			(stroke
				(width 0.05)
				(type default)
			)
			(fill none)
			(layer "F.CrtYd")
		)
		(fp_line
			(start 0.504 -0.25)
			(end 0.504 0.248)
			(stroke
				(width 0.15)
				(type solid)
			)
			(layer "F.Fab")
		)
		(fp_line
			(start -0.494 -0.25)
			(end 0.504 -0.25)
			(stroke
				(width 0.15)
				(type solid)
			)
			(layer "F.Fab")
		)
		(fp_line
			(start 0.504 0.248)
			(end -0.494 0.248)
			(stroke
				(width 0.15)
				(type solid)
			)
			(layer "F.Fab")
		)
		(fp_line
			(start -0.494 0.248)
			(end -0.494 -0.25)
			(stroke
				(width 0.15)
				(type solid)
			)
			(layer "F.Fab")
		)
		(fp_text user "License: Apache-2.0"
			(at -0.932 5.17 90)
			(layer "F.Fab")
			(hide yes)
			(effects
				(font
					(size 0.7 0.7)
					(thickness 0.15)
				)
				(justify left bottom)
			)
		)
		(fp_text user "Author: Antmicro"
			(at -0.932 4.17 90)
			(layer "F.Fab")
			(hide yes)
			(effects
				(font
					(size 0.7 0.7)
					(thickness 0.15)
				)
				(justify left bottom)
			)
		)
		(fp_text user "${REFERENCE}"
			(at -0.932 3.168 90)
			(layer "F.Fab")
			(hide yes)
			(effects
				(font
					(size 0.7 0.7)
					(thickness 0.15)
				)
				(justify left bottom)
			)
		)
		(pad "1" smd roundrect
			(at -0.48 0 90)
			(size 0.59 0.64)
			(layers "F.Cu" "F.Paste" "F.Mask")
			(roundrect_rratio 0.25)
			(net 87 "+3V3")
			(pintype "passive")
		)
		(pad "2" smd roundrect
			(at 0.48 0 90)
			(size 0.59 0.64)
			(layers "F.Cu" "F.Paste" "F.Mask")
			(roundrect_rratio 0.25)
			(net 1 "GND")
			(pintype "passive")
		)
	)
	(footprint "antmicro-footprints:USON-10_2.5x1mm_P0.5mm"
		(layer "F.Cu")
		(at 75 115.5 90)
		(descr "USON-10 2.5x1mm_ Pitch 0.5mm")
		(tags "USON-10 2.5x1mm Pitch 0.5mm")
		(property "Reference" "U16"
			(at -1.66 -1.01 180)
			(layer "F.SilkS")
			(effects
				(font
					(size 0.7 0.7)
					(thickness 0.15)
				)
				(justify left bottom)
			)
		)
		(property "Value" "TPD4E05U06QDQARQ1"
			(at 0.018 2.499 90)
			(layer "F.Fab")
			(effects
				(font
					(size 0.7 0.7)
					(thickness 0.15)
				)
				(justify left bottom)
			)
		)
		(property "Footprint" "antmicro-footprints:USON-10_2.5x1mm_P0.5mm"
			(at 0 0 90)
			(layer "F.Fab")
			(hide yes)
			(effects
				(font
					(size 1.27 1.27)
					(thickness 0.15)
				)
			)
		)
		(property "Datasheet" "https://www.ti.com/lit/ds/symlink/tpd4e05u06-q1.pdf?HQS=dis-mous-null-mousermode-dsf-pf-null-wwe&ts=1663591265741&ref_url=https%253A%252F%252Fwww.mouser.com%252F"
			(at 0 0 90)
			(layer "F.Fab")
			(hide yes)
			(effects
				(font
					(size 1.27 1.27)
					(thickness 0.15)
				)
			)
		)
		(property "Author" "Antmicro"
			(at 190.5 40.5 0)
			(layer "F.Fab")
			(hide yes)
			(effects
				(font
					(size 1 1)
					(thickness 0.15)
				)
			)
		)
		(property "License" "Apache-2.0"
			(at 190.5 40.5 0)
			(layer "F.Fab")
			(hide yes)
			(effects
				(font
					(size 1 1)
					(thickness 0.15)
				)
			)
		)
		(property "MPN" "TPD4E05U06QDQARQ1"
			(at 190.5 40.5 0)
			(layer "F.Fab")
			(hide yes)
			(effects
				(font
					(size 1 1)
					(thickness 0.15)
				)
			)
		)
		(property "Manufacturer" "Texas Instruments"
			(at 190.5 40.5 0)
			(layer "F.Fab")
			(hide yes)
			(effects
				(font
					(size 1 1)
					(thickness 0.15)
				)
			)
		)
		(sheetname "USB Debug, DP")
		(sheetfile "usb.kicad_sch")
		(attr smd)
		(fp_line
			(start 0.498 -1.401)
			(end -0.5 -1.401)
			(stroke
				(width 0.15)
				(type solid)
			)
			(layer "F.SilkS")
		)
		(fp_line
			(start 0.498 1.398)
			(end -0.5 1.398)
			(stroke
				(width 0.15)
				(type solid)
			)
			(layer "F.SilkS")
		)
		(fp_circle
			(center -0.68 -1.27)
			(end -0.63 -1.27)
			(stroke
				(width 0.15)
				(type solid)
			)
			(fill solid)
			(layer "F.SilkS")
		)
		(fp_rect
			(start -0.8 -1.5)
			(end 0.8 1.499)
			(stroke
				(width 0.05)
				(type solid)
			)
			(fill none)
			(layer "F.CrtYd")
		)
		(fp_line
			(start 0.498 -1.25)
			(end -0.25 -1.25)
			(stroke
				(width 0.15)
				(type solid)
			)
			(layer "F.Fab")
		)
		(fp_line
			(start 0.498 -1.25)
			(end 0.498 1.249)
			(stroke
				(width 0.15)
				(type solid)
			)
			(layer "F.Fab")
		)
		(fp_line
			(start -0.25 -1.25)
			(end -0.5 -1)
			(stroke
				(width 0.15)
				(type solid)
			)
			(layer "F.Fab")
		)
		(fp_line
			(start -0.5 -1)
			(end -0.5 1.249)
			(stroke
				(width 0.15)
				(type solid)
			)
			(layer "F.Fab")
		)
		(fp_line
			(start -0.5 1.249)
			(end 0.498 1.249)
			(stroke
				(width 0.15)
				(type solid)
			)
			(layer "F.Fab")
		)
		(fp_text user "${REFERENCE}"
			(at -0.802 4.498 90)
			(layer "F.Fab")
			(hide yes)
			(effects
				(font
					(size 0.7 0.7)
					(thickness 0.15)
				)
				(justify left bottom)
			)
		)
		(fp_text user "License: Apache-2.0"
			(at -0.802 6.9 90)
			(layer "F.Fab")
			(hide yes)
			(effects
				(font
					(size 0.7 0.7)
					(thickness 0.15)
				)
				(justify left bottom)
			)
		)
		(fp_text user "Author: Antmicro"
			(at -0.802 5.7 90)
			(layer "F.Fab")
			(hide yes)
			(effects
				(font
					(size 0.7 0.7)
					(thickness 0.15)
				)
				(justify left bottom)
			)
		)
		(pad "1" smd roundrect
			(at -0.387 -1)
			(size 0.25 0.55)
			(layers "F.Cu" "F.Paste" "F.Mask")
			(roundrect_rratio 0.25)
			(net 277 "/USB Debug, DP/USBC0_CC1")
			(pintype "passive")
		)
		(pad "2" smd roundrect
			(at -0.387 -0.5)
			(size 0.25 0.55)
			(layers "F.Cu" "F.Paste" "F.Mask")
			(roundrect_rratio 0.25)
			(net 439 "USB2_D_P")
			(pintype "passive")
		)
		(pad "3" smd roundrect
			(at -0.387 0)
			(size 0.4 0.55)
			(layers "F.Cu" "F.Paste" "F.Mask")
			(roundrect_rratio 0.25)
			(net 1 "GND")
			(pintype "power_in")
		)
		(pad "4" smd roundrect
			(at -0.387 0.498)
			(size 0.25 0.55)
			(layers "F.Cu" "F.Paste" "F.Mask")
			(roundrect_rratio 0.25)
			(net 437 "USB2_D_N")
			(pintype "passive")
		)
		(pad "5" smd roundrect
			(at -0.387 0.998)
			(size 0.25 0.55)
			(layers "F.Cu" "F.Paste" "F.Mask")
			(roundrect_rratio 0.25)
			(net 278 "/USB Debug, DP/USBC0_CC2")
			(pintype "passive")
		)
		(pad "6" smd roundrect
			(at 0.385 0.998)
			(size 0.25 0.55)
			(layers "F.Cu" "F.Paste" "F.Mask")
			(roundrect_rratio 0.25)
			(net 278 "/USB Debug, DP/USBC0_CC2")
			(pintype "passive")
		)
		(pad "7" smd roundrect
			(at 0.385 0.498)
			(size 0.25 0.55)
			(layers "F.Cu" "F.Paste" "F.Mask")
			(roundrect_rratio 0.25)
			(net 437 "USB2_D_N")
			(pintype "passive")
		)
		(pad "8" smd roundrect
			(at 0.385 0)
			(size 0.4 0.55)
			(layers "F.Cu" "F.Paste" "F.Mask")
			(roundrect_rratio 0.25)
			(net 1 "GND")
			(pintype "passive")
		)
		(pad "9" smd roundrect
			(at 0.385 -0.5)
			(size 0.25 0.55)
			(layers "F.Cu" "F.Paste" "F.Mask")
			(roundrect_rratio 0.25)
			(net 439 "USB2_D_P")
			(pintype "passive")
		)
		(pad "10" smd roundrect
			(at 0.385 -1)
			(size 0.25 0.55)
			(layers "F.Cu" "F.Paste" "F.Mask")
			(roundrect_rratio 0.25)
			(net 277 "/USB Debug, DP/USBC0_CC1")
			(pintype "passive")
		)
	)
	(footprint "antmicro-footprints:C_0402_1005Metric"
		(layer "F.Cu")
		(at 73.6 111 -90)
		(descr "Capacitor SMD 0402")
		(tags "capacitor SMD 0402")
		(property "Reference" "C60"
			(at 2.95 -0.4 -90)
			(layer "F.SilkS")
			(effects
				(font
					(size 0.7 0.7)
					(thickness 0.15)
				)
				(justify left bottom)
			)
		)
		(property "Value" "C_100n_0402"
			(at 0 1.4 -90)
			(layer "F.Fab")
			(effects
				(font
					(size 0.7 0.7)
					(thickness 0.15)
				)
				(justify left bottom)
			)
		)
		(property "Footprint" "antmicro-footprints:C_0402_1005Metric"
			(at 0 0 -90)
			(layer "F.Fab")
			(hide yes)
			(effects
				(font
					(size 1.27 1.27)
					(thickness 0.15)
				)
			)
		)
		(property "Datasheet" "https://www.murata.com/products/productdetail?partno=GRM155R61H104KE14%23"
			(at 0 0 -90)
			(layer "F.Fab")
			(hide yes)
			(effects
				(font
					(size 1.27 1.27)
					(thickness 0.15)
				)
			)
		)
		(property "Author" "Antmicro"
			(at -37.4 184.6 0)
			(layer "F.Fab")
			(hide yes)
			(effects
				(font
					(size 1 1)
					(thickness 0.15)
				)
			)
		)
		(property "Dielectric" "X5R"
			(at -37.4 184.6 0)
			(layer "F.Fab")
			(hide yes)
			(effects
				(font
					(size 1 1)
					(thickness 0.15)
				)
			)
		)
		(property "License" "Apache-2.0"
			(at -37.4 184.6 0)
			(layer "F.Fab")
			(hide yes)
			(effects
				(font
					(size 1 1)
					(thickness 0.15)
				)
			)
		)
		(property "MPN" "GRM155R61H104KE14D"
			(at -37.4 184.6 0)
			(layer "F.Fab")
			(hide yes)
			(effects
				(font
					(size 1 1)
					(thickness 0.15)
				)
			)
		)
		(property "Manufacturer" "Murata"
			(at -37.4 184.6 0)
			(layer "F.Fab")
			(hide yes)
			(effects
				(font
					(size 1 1)
					(thickness 0.15)
				)
			)
		)
		(property "Val" "100n"
			(at -37.4 184.6 0)
			(layer "F.Fab")
			(hide yes)
			(effects
				(font
					(size 1 1)
					(thickness 0.15)
				)
			)
		)
		(property "Voltage" "50V"
			(at -37.4 184.6 0)
			(layer "F.Fab")
			(hide yes)
			(effects
				(font
					(size 1 1)
					(thickness 0.15)
				)
			)
		)
		(sheetname "USB Debug, DP")
		(sheetfile "usb.kicad_sch")
		(attr smd)
		(fp_rect
			(start -0.925 -0.47)
			(end 0.925 0.47)
			(stroke
				(width 0.05)
				(type default)
			)
			(fill none)
			(layer "F.CrtYd")
		)
		(fp_line
			(start -0.494 0.248)
			(end -0.494 -0.25)
			(stroke
				(width 0.15)
				(type solid)
			)
			(layer "F.Fab")
		)
		(fp_line
			(start 0.504 0.248)
			(end -0.494 0.248)
			(stroke
				(width 0.15)
				(type solid)
			)
			(layer "F.Fab")
		)
		(fp_line
			(start -0.494 -0.25)
			(end 0.504 -0.25)
			(stroke
				(width 0.15)
				(type solid)
			)
			(layer "F.Fab")
		)
		(fp_line
			(start 0.504 -0.25)
			(end 0.504 0.248)
			(stroke
				(width 0.15)
				(type solid)
			)
			(layer "F.Fab")
		)
		(fp_text user "Author: Antmicro"
			(at -0.932 4.17 -90)
			(layer "F.Fab")
			(hide yes)
			(effects
				(font
					(size 0.7 0.7)
					(thickness 0.15)
				)
				(justify left bottom)
			)
		)
		(fp_text user "${REFERENCE}"
			(at -0.932 3.168 -90)
			(layer "F.Fab")
			(hide yes)
			(effects
				(font
					(size 0.7 0.7)
					(thickness 0.15)
				)
				(justify left bottom)
			)
		)
		(fp_text user "License: Apache-2.0"
			(at -0.932 5.17 -90)
			(layer "F.Fab")
			(hide yes)
			(effects
				(font
					(size 0.7 0.7)
					(thickness 0.15)
				)
				(justify left bottom)
			)
		)
		(pad "1" smd roundrect
			(at -0.48 0 270)
			(size 0.59 0.64)
			(layers "F.Cu" "F.Paste" "F.Mask")
			(roundrect_rratio 0.25)
			(net 257 "/USB Debug, DP/USBC0_TX1_P")
			(pintype "passive")
		)
		(pad "2" smd roundrect
			(at 0.48 0 270)
			(size 0.59 0.64)
			(layers "F.Cu" "F.Paste" "F.Mask")
			(roundrect_rratio 0.25)
			(net 258 "/USB Debug, DP/USBC0_CONN_TX1_P")
			(pintype "passive")
		)
	)
	(footprint "antmicro-footprints:C_0402_1005Metric"
		(layer "F.Cu")
		(at 117.8 111.75 90)
		(descr "Capacitor SMD 0402")
		(tags "capacitor SMD 0402")
		(property "Reference" "C72"
			(at 0.8 0.35 90)
			(layer "F.SilkS")
			(effects
				(font
					(size 0.7 0.7)
					(thickness 0.15)
				)
				(justify left bottom)
			)
		)
		(property "Value" "C_100n_0402"
			(at 0 1.4 90)
			(layer "F.Fab")
			(effects
				(font
					(size 0.7 0.7)
					(thickness 0.15)
				)
				(justify left bottom)
			)
		)
		(property "Footprint" "antmicro-footprints:C_0402_1005Metric"
			(at 0 0 90)
			(layer "F.Fab")
			(hide yes)
			(effects
				(font
					(size 1.27 1.27)
					(thickness 0.15)
				)
			)
		)
		(property "Datasheet" "https://www.murata.com/products/productdetail?partno=GRM155R61H104KE14%23"
			(at 0 0 90)
			(layer "F.Fab")
			(hide yes)
			(effects
				(font
					(size 1.27 1.27)
					(thickness 0.15)
				)
			)
		)
		(property "Author" "Antmicro"
			(at 229.55 -6.05 0)
			(layer "F.Fab")
			(hide yes)
			(effects
				(font
					(size 1 1)
					(thickness 0.15)
				)
			)
		)
		(property "Dielectric" "X5R"
			(at 229.55 -6.05 0)
			(layer "F.Fab")
			(hide yes)
			(effects
				(font
					(size 1 1)
					(thickness 0.15)
				)
			)
		)
		(property "License" "Apache-2.0"
			(at 229.55 -6.05 0)
			(layer "F.Fab")
			(hide yes)
			(effects
				(font
					(size 1 1)
					(thickness 0.15)
				)
			)
		)
		(property "MPN" "GRM155R61H104KE14D"
			(at 229.55 -6.05 0)
			(layer "F.Fab")
			(hide yes)
			(effects
				(font
					(size 1 1)
					(thickness 0.15)
				)
			)
		)
		(property "Manufacturer" "Murata"
			(at 229.55 -6.05 0)
			(layer "F.Fab")
			(hide yes)
			(effects
				(font
					(size 1 1)
					(thickness 0.15)
				)
			)
		)
		(property "Val" "100n"
			(at 229.55 -6.05 0)
			(layer "F.Fab")
			(hide yes)
			(effects
				(font
					(size 1 1)
					(thickness 0.15)
				)
			)
		)
		(property "Voltage" "50V"
			(at 229.55 -6.05 0)
			(layer "F.Fab")
			(hide yes)
			(effects
				(font
					(size 1 1)
					(thickness 0.15)
				)
			)
		)
		(sheetname "USB3")
		(sheetfile "usb3.kicad_sch")
		(attr smd)
		(fp_rect
			(start -0.925 -0.47)
			(end 0.925 0.47)
			(stroke
				(width 0.05)
				(type default)
			)
			(fill none)
			(layer "F.CrtYd")
		)
		(fp_line
			(start 0.504 -0.25)
			(end 0.504 0.248)
			(stroke
				(width 0.15)
				(type solid)
			)
			(layer "F.Fab")
		)
		(fp_line
			(start -0.494 -0.25)
			(end 0.504 -0.25)
			(stroke
				(width 0.15)
				(type solid)
			)
			(layer "F.Fab")
		)
		(fp_line
			(start 0.504 0.248)
			(end -0.494 0.248)
			(stroke
				(width 0.15)
				(type solid)
			)
			(layer "F.Fab")
		)
		(fp_line
			(start -0.494 0.248)
			(end -0.494 -0.25)
			(stroke
				(width 0.15)
				(type solid)
			)
			(layer "F.Fab")
		)
		(fp_text user "License: Apache-2.0"
			(at -0.932 5.17 90)
			(layer "F.Fab")
			(hide yes)
			(effects
				(font
					(size 0.7 0.7)
					(thickness 0.15)
				)
				(justify left bottom)
			)
		)
		(fp_text user "Author: Antmicro"
			(at -0.932 4.17 90)
			(layer "F.Fab")
			(hide yes)
			(effects
				(font
					(size 0.7 0.7)
					(thickness 0.15)
				)
				(justify left bottom)
			)
		)
		(fp_text user "${REFERENCE}"
			(at -0.932 3.168 90)
			(layer "F.Fab")
			(hide yes)
			(effects
				(font
					(size 0.7 0.7)
					(thickness 0.15)
				)
				(justify left bottom)
			)
		)
		(pad "1" smd roundrect
			(at -0.48 0 90)
			(size 0.59 0.64)
			(layers "F.Cu" "F.Paste" "F.Mask")
			(roundrect_rratio 0.25)
			(net 269 "/USB3/USBC1_CONN_TX2_P")
			(pintype "passive")
		)
		(pad "2" smd roundrect
			(at 0.48 0 90)
			(size 0.59 0.64)
			(layers "F.Cu" "F.Paste" "F.Mask")
			(roundrect_rratio 0.25)
			(net 268 "/USB3/USBC1_TX2_P")
			(pintype "passive")
		)
	)
	(footprint "antmicro-footprints:SOT-523"
		(layer "F.Cu")
		(at 85.4 113.15 90)
		(property "Reference" "Q12"
			(at 0.93 0.39 90)
			(layer "F.SilkS")
			(effects
				(font
					(size 0.7 0.7)
					(thickness 0.15)
				)
				(justify left bottom)
			)
		)
		(property "Value" "PJE138K"
			(at 0.1 1.824 90)
			(layer "F.Fab")
			(effects
				(font
					(size 0.7 0.7)
					(thickness 0.15)
				)
				(justify left bottom)
			)
		)
		(property "Footprint" "antmicro-footprints:SOT-523"
			(at 0 0 90)
			(layer "F.Fab")
			(hide yes)
			(effects
				(font
					(size 1.27 1.27)
					(thickness 0.15)
				)
			)
		)
		(property "Datasheet" "https://www.mouser.com/datasheet/2/1057/PJE138K-1876698.pdf"
			(at 0 0 90)
			(layer "F.Fab")
			(hide yes)
			(effects
				(font
					(size 1.27 1.27)
					(thickness 0.15)
				)
			)
		)
		(property "Author" "Antmicro"
			(at 198.55 27.75 0)
			(layer "F.Fab")
			(hide yes)
			(effects
				(font
					(size 1 1)
					(thickness 0.15)
				)
			)
		)
		(property "License" "Apache-2.0"
			(at 198.55 27.75 0)
			(layer "F.Fab")
			(hide yes)
			(effects
				(font
					(size 1 1)
					(thickness 0.15)
				)
			)
		)
		(property "MPN" "PJE138K_R1_00001"
			(at 198.55 27.75 0)
			(layer "F.Fab")
			(hide yes)
			(effects
				(font
					(size 1 1)
					(thickness 0.15)
				)
			)
		)
		(property "Manufacturer" "PANJIT"
			(at 198.55 27.75 0)
			(layer "F.Fab")
			(hide yes)
			(effects
				(font
					(size 1 1)
					(thickness 0.15)
				)
			)
		)
		(sheetname "HDMI")
		(sheetfile "hdmi.kicad_sch")
		(attr smd exclude_from_pos_files exclude_from_bom dnp)
		(fp_line
			(start -0.277 -0.551)
			(end -0.277 -0.75)
			(stroke
				(width 0.15)
				(type solid)
			)
			(layer "F.SilkS")
		)
		(fp_line
			(start -0.725 -0.551)
			(end -0.277 -0.551)
			(stroke
				(width 0.15)
				(type solid)
			)
			(layer "F.SilkS")
		)
		(fp_line
			(start -0.927 -0.351)
			(end -0.725 -0.551)
			(stroke
				(width 0.15)
				(type solid)
			)
			(layer "F.SilkS")
		)
		(fp_line
			(start -0.927 -0.051)
			(end -0.927 -0.351)
			(stroke
				(width 0.15)
				(type solid)
			)
			(layer "F.SilkS")
		)
		(fp_circle
			(center -0.9652 0.9652)
			(end -0.9152 0.9652)
			(stroke
				(width 0.15)
				(type solid)
			)
			(fill solid)
			(layer "F.SilkS")
		)
		(fp_line
			(start 1.1 -1.16)
			(end 1.1 1.15)
			(stroke
				(width 0.05)
				(type solid)
			)
			(layer "F.CrtYd")
		)
		(fp_line
			(start -1.12 -1.16)
			(end 1.1 -1.16)
			(stroke
				(width 0.05)
				(type solid)
			)
			(layer "F.CrtYd")
		)
		(fp_line
			(start -1.12 -1.16)
			(end -1.12 1.15)
			(stroke
				(width 0.05)
				(type solid)
			)
			(layer "F.CrtYd")
		)
		(fp_line
			(start -1.12 1.15)
			(end 1.1 1.15)
			(stroke
				(width 0.05)
				(type solid)
			)
			(layer "F.CrtYd")
		)
		(fp_line
			(start 0.8 -0.425)
			(end -0.652 -0.425)
			(stroke
				(width 0.15)
				(type solid)
			)
			(layer "F.Fab")
		)
		(fp_line
			(start 0.8 -0.425)
			(end 0.8 0.424)
			(stroke
				(width 0.15)
				(type solid)
			)
			(layer "F.Fab")
		)
		(fp_line
			(start -0.652 -0.425)
			(end -0.802 -0.276)
			(stroke
				(width 0.15)
				(type solid)
			)
			(layer "F.Fab")
		)
		(fp_line
			(start -0.802 -0.276)
			(end -0.802 0.424)
			(stroke
				(width 0.15)
				(type solid)
			)
			(layer "F.Fab")
		)
		(fp_line
			(start 0.8 0.424)
			(end -0.802 0.424)
			(stroke
				(width 0.15)
				(type solid)
			)
			(layer "F.Fab")
		)
		(fp_circle
			(center -0.9652 0.9652)
			(end -0.9144 0.9652)
			(stroke
				(width 0.15)
				(type solid)
			)
			(fill none)
			(layer "F.Fab")
		)
		(fp_text user "License: Apache-2.0"
			(at -1.12 5.024 90)
			(layer "F.Fab")
			(hide yes)
			(effects
				(font
					(size 0.7 0.7)
					(thickness 0.15)
				)
				(justify left bottom)
			)
		)
		(fp_text user "${REFERENCE}"
			(at -1.12 3.824 90)
			(layer "F.Fab")
			(hide yes)
			(effects
				(font
					(size 0.7 0.7)
					(thickness 0.15)
				)
				(justify left bottom)
			)
		)
		(fp_text user "Author: Antmicro"
			(at -1.12 6.224 90)
			(layer "F.Fab")
			(hide yes)
			(effects
				(font
					(size 0.7 0.7)
					(thickness 0.15)
				)
				(justify left bottom)
			)
		)
		(pad "1" smd rect
			(at -0.5 0.65 90)
			(size 0.4 0.51)
			(layers "F.Cu" "F.Paste" "F.Mask")
			(net 576 "/HDMI/HDMI_HPD_5V_R")
			(pinfunction "G")
			(pintype "passive")
		)
		(pad "2" smd rect
			(at 0.498 0.65 90)
			(size 0.4 0.51)
			(layers "F.Cu" "F.Paste" "F.Mask")
			(net 1 "GND")
			(pinfunction "S")
			(pintype "passive")
		)
		(pad "3" smd rect
			(at 0 -0.652 90)
			(size 0.4 0.51)
			(layers "F.Cu" "F.Paste" "F.Mask")
			(net 703 "/HDMI/HDMI_HPD")
			(pinfunction "D")
			(pintype "passive")
		)
	)
	(footprint "antmicro-footprints:R_0402_1005Metric"
		(layer "F.Cu")
		(at 148 109.5)
		(descr "Resistor SMD 0402")
		(tags "resistor SMD 0402")
		(property "Reference" "R121"
			(at -1.21 5.99 0)
			(layer "F.SilkS")
			(effects
				(font
					(size 0.7 0.7)
					(thickness 0.15)
				)
				(justify left bottom)
			)
		)
		(property "Value" "R_0R_0402"
			(at 0 1.4 0)
			(layer "F.Fab")
			(effects
				(font
					(size 0.7 0.7)
					(thickness 0.15)
				)
				(justify left bottom)
			)
		)
		(property "Footprint" "antmicro-footprints:R_0402_1005Metric"
			(at 0 0 0)
			(layer "F.Fab")
			(hide yes)
			(effects
				(font
					(size 1.27 1.27)
					(thickness 0.15)
				)
			)
		)
		(property "Datasheet" "https://industrial.panasonic.com/cdbs/www-data/pdf/RDA0000/AOA0000C301.pdf"
			(at 0 0 0)
			(layer "F.Fab")
			(hide yes)
			(effects
				(font
					(size 1.27 1.27)
					(thickness 0.15)
				)
			)
		)
		(property "Author" "Antmicro"
			(at 0 0 0)
			(layer "F.Fab")
			(hide yes)
			(effects
				(font
					(size 1 1)
					(thickness 0.15)
				)
			)
		)
		(property "Current" "1A"
			(at 0 0 0)
			(layer "F.Fab")
			(hide yes)
			(effects
				(font
					(size 1 1)
					(thickness 0.15)
				)
			)
		)
		(property "License" "Apache-2.0"
			(at 0 0 0)
			(layer "F.Fab")
			(hide yes)
			(effects
				(font
					(size 1 1)
					(thickness 0.15)
				)
			)
		)
		(property "MPN" "ERJ2GE0R00X"
			(at 0 0 0)
			(layer "F.Fab")
			(hide yes)
			(effects
				(font
					(size 1 1)
					(thickness 0.15)
				)
			)
		)
		(property "Manufacturer" "Panasonic"
			(at 0 0 0)
			(layer "F.Fab")
			(hide yes)
			(effects
				(font
					(size 1 1)
					(thickness 0.15)
				)
			)
		)
		(property "Tolerance" ""
			(at 0 0 0)
			(layer "F.Fab")
			(hide yes)
			(effects
				(font
					(size 1 1)
					(thickness 0.15)
				)
			)
		)
		(property "Val" "0R"
			(at 0 0 0)
			(layer "F.Fab")
			(hide yes)
			(effects
				(font
					(size 1 1)
					(thickness 0.15)
				)
			)
		)
		(sheetname "Peripherals")
		(sheetfile "peripherals.kicad_sch")
		(attr smd exclude_from_pos_files exclude_from_bom dnp)
		(fp_rect
			(start -0.925 -0.47)
			(end 0.925 0.47)
			(stroke
				(width 0.05)
				(type default)
			)
			(fill none)
			(layer "F.CrtYd")
		)
		(fp_rect
			(start -0.5 -0.25)
			(end 0.5 0.25)
			(stroke
				(width 0.15)
				(type solid)
			)
			(fill none)
			(layer "F.Fab")
		)
		(fp_text user "License: Apache-2.0"
			(at -0.95 5.169 0)
			(layer "F.Fab")
			(hide yes)
			(effects
				(font
					(size 0.7 0.7)
					(thickness 0.15)
				)
				(justify left bottom)
			)
		)
		(fp_text user "${REFERENCE}"
			(at -0.95 3.168 0)
			(layer "F.Fab")
			(hide yes)
			(effects
				(font
					(size 0.7 0.7)
					(thickness 0.15)
				)
				(justify left bottom)
			)
		)
		(fp_text user "Author: Antmicro"
			(at -0.95 4.169 0)
			(layer "F.Fab")
			(hide yes)
			(effects
				(font
					(size 0.7 0.7)
					(thickness 0.15)
				)
				(justify left bottom)
			)
		)
		(pad "1" smd roundrect
			(at -0.48 0)
			(size 0.59 0.64)
			(layers "F.Cu" "F.Paste" "F.Mask")
			(roundrect_rratio 0.25)
			(net 599 "Net-(J11-Pad66)")
			(pintype "passive")
		)
		(pad "2" smd roundrect
			(at 0.48 0)
			(size 0.59 0.64)
			(layers "F.Cu" "F.Paste" "F.Mask")
			(roundrect_rratio 0.25)
			(net 129 "I2C2_SCL")
			(pintype "passive")
		)
	)
	(footprint "antmicro-footprints:R_0402_1005Metric"
		(layer "F.Cu")
		(at 133.7 121.1 90)
		(descr "Resistor SMD 0402")
		(tags "resistor SMD 0402")
		(property "Reference" "R231"
			(at 0.75 0.45 90)
			(layer "F.SilkS")
			(effects
				(font
					(size 0.7 0.7)
					(thickness 0.15)
				)
				(justify left bottom)
			)
		)
		(property "Value" "R_200R_0402"
			(at 0 1.4 90)
			(layer "F.Fab")
			(effects
				(font
					(size 0.7 0.7)
					(thickness 0.15)
				)
				(justify left bottom)
			)
		)
		(property "Footprint" "antmicro-footprints:R_0402_1005Metric"
			(at 0 0 90)
			(layer "F.Fab")
			(hide yes)
			(effects
				(font
					(size 1.27 1.27)
					(thickness 0.15)
				)
			)
		)
		(property "Datasheet" "https://www.bourns.com/docs/product-datasheets/cr.pdf"
			(at 0 0 90)
			(layer "F.Fab")
			(hide yes)
			(effects
				(font
					(size 1.27 1.27)
					(thickness 0.15)
				)
			)
		)
		(property "Author" "Antmicro"
			(at 254.8 -12.6 0)
			(layer "F.Fab")
			(hide yes)
			(effects
				(font
					(size 1 1)
					(thickness 0.15)
				)
			)
		)
		(property "License" "Apache-2.0"
			(at 254.8 -12.6 0)
			(layer "F.Fab")
			(hide yes)
			(effects
				(font
					(size 1 1)
					(thickness 0.15)
				)
			)
		)
		(property "MPN" "CR0402-FX-2000GLF"
			(at 254.8 -12.6 0)
			(layer "F.Fab")
			(hide yes)
			(effects
				(font
					(size 1 1)
					(thickness 0.15)
				)
			)
		)
		(property "Manufacturer" "Bourns"
			(at 254.8 -12.6 0)
			(layer "F.Fab")
			(hide yes)
			(effects
				(font
					(size 1 1)
					(thickness 0.15)
				)
			)
		)
		(property "Tolerance" "1%"
			(at 254.8 -12.6 0)
			(layer "F.Fab")
			(hide yes)
			(effects
				(font
					(size 1 1)
					(thickness 0.15)
				)
			)
		)
		(property "Val" "200R"
			(at 254.8 -12.6 0)
			(layer "F.Fab")
			(hide yes)
			(effects
				(font
					(size 1 1)
					(thickness 0.15)
				)
			)
		)
		(sheetname "Peripherals")
		(sheetfile "peripherals.kicad_sch")
		(attr smd)
		(fp_rect
			(start -0.925 -0.47)
			(end 0.925 0.47)
			(stroke
				(width 0.05)
				(type default)
			)
			(fill none)
			(layer "F.CrtYd")
		)
		(fp_rect
			(start -0.5 -0.25)
			(end 0.5 0.25)
			(stroke
				(width 0.15)
				(type solid)
			)
			(fill none)
			(layer "F.Fab")
		)
		(fp_text user "${REFERENCE}"
			(at -0.95 3.168 90)
			(layer "F.Fab")
			(hide yes)
			(effects
				(font
					(size 0.7 0.7)
					(thickness 0.15)
				)
				(justify left bottom)
			)
		)
		(fp_text user "License: Apache-2.0"
			(at -0.95 5.169 90)
			(layer "F.Fab")
			(hide yes)
			(effects
				(font
					(size 0.7 0.7)
					(thickness 0.15)
				)
				(justify left bottom)
			)
		)
		(fp_text user "Author: Antmicro"
			(at -0.95 4.169 90)
			(layer "F.Fab")
			(hide yes)
			(effects
				(font
					(size 0.7 0.7)
					(thickness 0.15)
				)
				(justify left bottom)
			)
		)
		(pad "1" smd roundrect
			(at -0.48 0 90)
			(size 0.59 0.64)
			(layers "F.Cu" "F.Paste" "F.Mask")
			(roundrect_rratio 0.25)
			(net 182 "Net-(D27-A)")
			(pintype "passive")
		)
		(pad "2" smd roundrect
			(at 0.48 0 90)
			(size 0.59 0.64)
			(layers "F.Cu" "F.Paste" "F.Mask")
			(roundrect_rratio 0.25)
			(net 87 "+3V3")
			(pintype "passive")
		)
	)
	(footprint "antmicro-footprints:C_0402_1005Metric"
		(layer "F.Cu")
		(at 116.8 111.75 90)
		(descr "Capacitor SMD 0402")
		(tags "capacitor SMD 0402")
		(property "Reference" "C69"
			(at 0.8 0.35 90)
			(layer "F.SilkS")
			(effects
				(font
					(size 0.7 0.7)
					(thickness 0.15)
				)
				(justify left bottom)
			)
		)
		(property "Value" "C_100n_0402"
			(at 0 1.4 90)
			(layer "F.Fab")
			(effects
				(font
					(size 0.7 0.7)
					(thickness 0.15)
				)
				(justify left bottom)
			)
		)
		(property "Footprint" "antmicro-footprints:C_0402_1005Metric"
			(at 0 0 90)
			(layer "F.Fab")
			(hide yes)
			(effects
				(font
					(size 1.27 1.27)
					(thickness 0.15)
				)
			)
		)
		(property "Datasheet" "https://www.murata.com/products/productdetail?partno=GRM155R61H104KE14%23"
			(at 0 0 90)
			(layer "F.Fab")
			(hide yes)
			(effects
				(font
					(size 1.27 1.27)
					(thickness 0.15)
				)
			)
		)
		(property "Author" "Antmicro"
			(at 228.55 -5.05 0)
			(layer "F.Fab")
			(hide yes)
			(effects
				(font
					(size 1 1)
					(thickness 0.15)
				)
			)
		)
		(property "Dielectric" "X5R"
			(at 228.55 -5.05 0)
			(layer "F.Fab")
			(hide yes)
			(effects
				(font
					(size 1 1)
					(thickness 0.15)
				)
			)
		)
		(property "License" "Apache-2.0"
			(at 228.55 -5.05 0)
			(layer "F.Fab")
			(hide yes)
			(effects
				(font
					(size 1 1)
					(thickness 0.15)
				)
			)
		)
		(property "MPN" "GRM155R61H104KE14D"
			(at 228.55 -5.05 0)
			(layer "F.Fab")
			(hide yes)
			(effects
				(font
					(size 1 1)
					(thickness 0.15)
				)
			)
		)
		(property "Manufacturer" "Murata"
			(at 228.55 -5.05 0)
			(layer "F.Fab")
			(hide yes)
			(effects
				(font
					(size 1 1)
					(thickness 0.15)
				)
			)
		)
		(property "Val" "100n"
			(at 228.55 -5.05 0)
			(layer "F.Fab")
			(hide yes)
			(effects
				(font
					(size 1 1)
					(thickness 0.15)
				)
			)
		)
		(property "Voltage" "50V"
			(at 228.55 -5.05 0)
			(layer "F.Fab")
			(hide yes)
			(effects
				(font
					(size 1 1)
					(thickness 0.15)
				)
			)
		)
		(sheetname "USB3")
		(sheetfile "usb3.kicad_sch")
		(attr smd)
		(fp_rect
			(start -0.925 -0.47)
			(end 0.925 0.47)
			(stroke
				(width 0.05)
				(type default)
			)
			(fill none)
			(layer "F.CrtYd")
		)
		(fp_line
			(start 0.504 -0.25)
			(end 0.504 0.248)
			(stroke
				(width 0.15)
				(type solid)
			)
			(layer "F.Fab")
		)
		(fp_line
			(start -0.494 -0.25)
			(end 0.504 -0.25)
			(stroke
				(width 0.15)
				(type solid)
			)
			(layer "F.Fab")
		)
		(fp_line
			(start 0.504 0.248)
			(end -0.494 0.248)
			(stroke
				(width 0.15)
				(type solid)
			)
			(layer "F.Fab")
		)
		(fp_line
			(start -0.494 0.248)
			(end -0.494 -0.25)
			(stroke
				(width 0.15)
				(type solid)
			)
			(layer "F.Fab")
		)
		(fp_text user "Author: Antmicro"
			(at -0.932 4.17 90)
			(layer "F.Fab")
			(hide yes)
			(effects
				(font
					(size 0.7 0.7)
					(thickness 0.15)
				)
				(justify left bottom)
			)
		)
		(fp_text user "${REFERENCE}"
			(at -0.932 3.168 90)
			(layer "F.Fab")
			(hide yes)
			(effects
				(font
					(size 0.7 0.7)
					(thickness 0.15)
				)
				(justify left bottom)
			)
		)
		(fp_text user "License: Apache-2.0"
			(at -0.932 5.17 90)
			(layer "F.Fab")
			(hide yes)
			(effects
				(font
					(size 0.7 0.7)
					(thickness 0.15)
				)
				(justify left bottom)
			)
		)
		(pad "1" smd roundrect
			(at -0.48 0 90)
			(size 0.59 0.64)
			(layers "F.Cu" "F.Paste" "F.Mask")
			(roundrect_rratio 0.25)
			(net 263 "/USB3/USBC1_CONN_TX2_N")
			(pintype "passive")
		)
		(pad "2" smd roundrect
			(at 0.48 0 90)
			(size 0.59 0.64)
			(layers "F.Cu" "F.Paste" "F.Mask")
			(roundrect_rratio 0.25)
			(net 262 "/USB3/USBC1_TX2_N")
			(pintype "passive")
		)
	)
	(footprint "antmicro-footprints:R_0603_1608Metric"
		(layer "F.Cu")
		(at 137.2 111.8)
		(descr "Resistor SMD 0603")
		(tags "resistor SMD 0603")
		(property "Reference" "R234"
			(at -5.59 0.48 0)
			(layer "F.SilkS")
			(effects
				(font
					(size 0.7 0.7)
					(thickness 0.15)
				)
				(justify left bottom)
			)
		)
		(property "Value" "R_0R_0603"
			(at 0 1.6 0)
			(layer "F.Fab")
			(effects
				(font
					(size 0.7 0.7)
					(thickness 0.15)
				)
				(justify left bottom)
			)
		)
		(property "Footprint" "antmicro-footprints:R_0603_1608Metric"
			(at 0 0 0)
			(layer "F.Fab")
			(hide yes)
			(effects
				(font
					(size 1.27 1.27)
					(thickness 0.15)
				)
			)
		)
		(property "Datasheet" "https://www.bourns.com/docs/product-datasheets/cr.pdf?sfvrsn=574d41f6_14"
			(at 0 0 0)
			(layer "F.Fab")
			(hide yes)
			(effects
				(font
					(size 1.27 1.27)
					(thickness 0.15)
				)
			)
		)
		(property "Author" "Antmicro"
			(at 0 0 0)
			(layer "F.Fab")
			(hide yes)
			(effects
				(font
					(size 1 1)
					(thickness 0.15)
				)
			)
		)
		(property "Current" "1A"
			(at 0 0 0)
			(layer "F.Fab")
			(hide yes)
			(effects
				(font
					(size 1 1)
					(thickness 0.15)
				)
			)
		)
		(property "License" "Apache-2.0"
			(at 0 0 0)
			(layer "F.Fab")
			(hide yes)
			(effects
				(font
					(size 1 1)
					(thickness 0.15)
				)
			)
		)
		(property "MPN" "CR0603-J/-000ELF"
			(at 0 0 0)
			(layer "F.Fab")
			(hide yes)
			(effects
				(font
					(size 1 1)
					(thickness 0.15)
				)
			)
		)
		(property "Manufacturer" "Bourns"
			(at 0 0 0)
			(layer "F.Fab")
			(hide yes)
			(effects
				(font
					(size 1 1)
					(thickness 0.15)
				)
			)
		)
		(property "Tolerance" ""
			(at 0 0 0)
			(layer "F.Fab")
			(hide yes)
			(effects
				(font
					(size 1 1)
					(thickness 0.15)
				)
			)
		)
		(property "Val" "0R"
			(at 0 0 0)
			(layer "F.Fab")
			(hide yes)
			(effects
				(font
					(size 1 1)
					(thickness 0.15)
				)
			)
		)
		(sheetname "Peripherals")
		(sheetfile "peripherals.kicad_sch")
		(attr smd exclude_from_pos_files exclude_from_bom dnp)
		(fp_line
			(start -0.15 -0.4)
			(end 0.15 -0.4)
			(stroke
				(width 0.15)
				(type solid)
			)
			(layer "F.SilkS")
		)
		(fp_line
			(start -0.15 0.4)
			(end 0.15 0.4)
			(stroke
				(width 0.15)
				(type solid)
			)
			(layer "F.SilkS")
		)
		(fp_rect
			(start -1.25 -0.65)
			(end 1.25 0.65)
			(stroke
				(width 0.05)
				(type solid)
			)
			(fill none)
			(layer "F.CrtYd")
		)
		(fp_rect
			(start -0.8 -0.4)
			(end 0.8 0.4)
			(stroke
				(width 0.15)
				(type solid)
			)
			(fill none)
			(layer "F.Fab")
		)
		(fp_text user "License: Apache-2.0"
			(at -1.25 5.9 0)
			(layer "F.Fab")
			(hide yes)
			(effects
				(font
					(size 0.7 0.7)
					(thickness 0.15)
				)
				(justify left bottom)
			)
		)
		(fp_text user "Author: Antmicro"
			(at -1.25 4.9 0)
			(layer "F.Fab")
			(hide yes)
			(effects
				(font
					(size 0.7 0.7)
					(thickness 0.15)
				)
				(justify left bottom)
			)
		)
		(fp_text user "${REFERENCE}"
			(at -1.25 3.898 0)
			(layer "F.Fab")
			(hide yes)
			(effects
				(font
					(size 0.7 0.7)
					(thickness 0.15)
				)
				(justify left bottom)
			)
		)
		(pad "1" smd roundrect
			(at -0.7 0)
			(size 0.8 1)
			(layers "F.Cu" "F.Paste" "F.Mask")
			(roundrect_rratio 0.2)
			(net 112 "+1V8")
			(pintype "passive")
		)
		(pad "2" smd roundrect
			(at 0.7 0)
			(size 0.8 1)
			(layers "F.Cu" "F.Paste" "F.Mask")
			(roundrect_rratio 0.2)
			(net 483 "/Peripherals/1V8_CONN")
			(pintype "passive")
		)
	)
	(footprint "antmicro-footprints:R_0402_1005Metric"
		(layer "F.Cu")
		(at 95.5 84.65 90)
		(descr "Resistor SMD 0402")
		(tags "resistor SMD 0402")
		(property "Reference" "R67"
			(at -0.725 -2.625 180)
			(layer "F.SilkS")
			(effects
				(font
					(size 0.7 0.7)
					(thickness 0.15)
				)
				(justify left bottom)
			)
		)
		(property "Value" "R_10k_0402"
			(at 0 1.4 90)
			(layer "F.Fab")
			(effects
				(font
					(size 0.7 0.7)
					(thickness 0.15)
				)
				(justify left bottom)
			)
		)
		(property "Footprint" "antmicro-footprints:R_0402_1005Metric"
			(at 0 0 90)
			(layer "F.Fab")
			(hide yes)
			(effects
				(font
					(size 1.27 1.27)
					(thickness 0.15)
				)
			)
		)
		(property "Datasheet" "https://www.bourns.com/docs/product-datasheets/cr.pdf"
			(at 0 0 90)
			(layer "F.Fab")
			(hide yes)
			(effects
				(font
					(size 1.27 1.27)
					(thickness 0.15)
				)
			)
		)
		(property "Author" "Antmicro"
			(at 180.15 -10.85 0)
			(layer "F.Fab")
			(hide yes)
			(effects
				(font
					(size 1 1)
					(thickness 0.15)
				)
			)
		)
		(property "License" "Apache-2.0"
			(at 180.15 -10.85 0)
			(layer "F.Fab")
			(hide yes)
			(effects
				(font
					(size 1 1)
					(thickness 0.15)
				)
			)
		)
		(property "MPN" "CR0402-FX-1002GLF"
			(at 180.15 -10.85 0)
			(layer "F.Fab")
			(hide yes)
			(effects
				(font
					(size 1 1)
					(thickness 0.15)
				)
			)
		)
		(property "Manufacturer" "Bourns"
			(at 180.15 -10.85 0)
			(layer "F.Fab")
			(hide yes)
			(effects
				(font
					(size 1 1)
					(thickness 0.15)
				)
			)
		)
		(property "Tolerance" "1%"
			(at 180.15 -10.85 0)
			(layer "F.Fab")
			(hide yes)
			(effects
				(font
					(size 1 1)
					(thickness 0.15)
				)
			)
		)
		(property "Val" "10k"
			(at 180.15 -10.85 0)
			(layer "F.Fab")
			(hide yes)
			(effects
				(font
					(size 1 1)
					(thickness 0.15)
				)
			)
		)
		(sheetname "CSI")
		(sheetfile "csi.kicad_sch")
		(attr smd)
		(fp_rect
			(start -0.925 -0.47)
			(end 0.925 0.47)
			(stroke
				(width 0.05)
				(type default)
			)
			(fill none)
			(layer "F.CrtYd")
		)
		(fp_rect
			(start -0.5 -0.25)
			(end 0.5 0.25)
			(stroke
				(width 0.15)
				(type solid)
			)
			(fill none)
			(layer "F.Fab")
		)
		(fp_text user "${REFERENCE}"
			(at -0.95 3.168 90)
			(layer "F.Fab")
			(hide yes)
			(effects
				(font
					(size 0.7 0.7)
					(thickness 0.15)
				)
				(justify left bottom)
			)
		)
		(fp_text user "License: Apache-2.0"
			(at -0.95 5.169 90)
			(layer "F.Fab")
			(hide yes)
			(effects
				(font
					(size 0.7 0.7)
					(thickness 0.15)
				)
				(justify left bottom)
			)
		)
		(fp_text user "Author: Antmicro"
			(at -0.95 4.169 90)
			(layer "F.Fab")
			(hide yes)
			(effects
				(font
					(size 0.7 0.7)
					(thickness 0.15)
				)
				(justify left bottom)
			)
		)
		(pad "1" smd roundrect
			(at -0.48 0 90)
			(size 0.59 0.64)
			(layers "F.Cu" "F.Paste" "F.Mask")
			(roundrect_rratio 0.25)
			(net 87 "+3V3")
			(pintype "passive")
		)
		(pad "2" smd roundrect
			(at 0.48 0 90)
			(size 0.59 0.64)
			(layers "F.Cu" "F.Paste" "F.Mask")
			(roundrect_rratio 0.25)
			(net 393 "CSIB_FLG")
			(pintype "passive")
		)
	)
	(footprint "antmicro-footprints:C_0805_2012Metric"
		(layer "F.Cu")
		(at 71.58 88.63)
		(descr "Capacitor SMD 0805")
		(tags "capacitor SMD 0805")
		(property "Reference" "C151"
			(at -1.28 1.8 0)
			(layer "F.SilkS")
			(effects
				(font
					(size 0.7 0.7)
					(thickness 0.15)
				)
				(justify left bottom)
			)
		)
		(property "Value" "C_22u_25V_0805"
			(at -2.055717 1.963152 0)
			(layer "F.Fab")
			(effects
				(font
					(size 0.7 0.7)
					(thickness 0.15)
				)
				(justify left bottom)
			)
		)
		(property "Footprint" "antmicro-footprints:C_0805_2012Metric"
			(at 0 0 0)
			(layer "F.Fab")
			(hide yes)
			(effects
				(font
					(size 1.27 1.27)
					(thickness 0.15)
				)
			)
		)
		(property "Datasheet" "https://product.samsungsem.com/mlcc/CL21A226MAYNNN.do"
			(at 0 0 0)
			(layer "F.Fab")
			(hide yes)
			(effects
				(font
					(size 1.27 1.27)
					(thickness 0.15)
				)
			)
		)
		(property "Author" "Antmicro"
			(at 0 0 0)
			(layer "F.Fab")
			(hide yes)
			(effects
				(font
					(size 1 1)
					(thickness 0.15)
				)
			)
		)
		(property "Dielectric" "X5R"
			(at 0 0 0)
			(layer "F.Fab")
			(hide yes)
			(effects
				(font
					(size 1 1)
					(thickness 0.15)
				)
			)
		)
		(property "License" "Apache-2.0"
			(at 0 0 0)
			(layer "F.Fab")
			(hide yes)
			(effects
				(font
					(size 1 1)
					(thickness 0.15)
				)
			)
		)
		(property "MPN" "CL21A226MAYNNNE"
			(at 0 0 0)
			(layer "F.Fab")
			(hide yes)
			(effects
				(font
					(size 1 1)
					(thickness 0.15)
				)
			)
		)
		(property "Manufacturer" "Samsung Electro-Mechanics"
			(at 0 0 0)
			(layer "F.Fab")
			(hide yes)
			(effects
				(font
					(size 1 1)
					(thickness 0.15)
				)
			)
		)
		(property "Public" "False"
			(at 0 0 0)
			(layer "F.Fab")
			(hide yes)
			(effects
				(font
					(size 1 1)
					(thickness 0.15)
				)
			)
		)
		(property "Val" "22u"
			(at 0 0 0)
			(layer "F.Fab")
			(hide yes)
			(effects
				(font
					(size 1 1)
					(thickness 0.15)
				)
			)
		)
		(property "Voltage" "25V"
			(at 0 0 0)
			(layer "F.Fab")
			(hide yes)
			(effects
				(font
					(size 1 1)
					(thickness 0.15)
				)
			)
		)
		(sheetname "Supply")
		(sheetfile "supply.kicad_sch")
		(attr smd)
		(fp_line
			(start -0.3 -0.7)
			(end 0.3 -0.7)
			(stroke
				(width 0.15)
				(type solid)
			)
			(layer "F.SilkS")
		)
		(fp_line
			(start -0.3 0.7)
			(end 0.3 0.7)
			(stroke
				(width 0.15)
				(type solid)
			)
			(layer "F.SilkS")
		)
		(fp_rect
			(start 1.95 -0.9)
			(end -1.95 0.9)
			(stroke
				(width 0.05)
				(type default)
			)
			(fill none)
			(layer "F.CrtYd")
		)
		(fp_rect
			(start -0.95 -0.675)
			(end 0.95 0.675)
			(stroke
				(width 0.15)
				(type solid)
			)
			(fill none)
			(layer "F.Fab")
		)
		(fp_text user "${REFERENCE}"
			(at -1.9 3.947 0)
			(layer "F.Fab")
			(hide yes)
			(effects
				(font
					(size 0.7 0.7)
					(thickness 0.15)
				)
				(justify left bottom)
			)
		)
		(fp_text user "Author: Antmicro"
			(at -1.9 5.947 0)
			(layer "F.Fab")
			(hide yes)
			(effects
				(font
					(size 0.7 0.7)
					(thickness 0.15)
				)
				(justify left bottom)
			)
		)
		(fp_text user "License: Apache-2.0"
			(at -1.9 4.947 0)
			(layer "F.Fab")
			(hide yes)
			(effects
				(font
					(size 0.7 0.7)
					(thickness 0.15)
				)
				(justify left bottom)
			)
		)
		(pad "1" smd roundrect
			(at -1.1 0)
			(size 1.2 1.3)
			(layers "F.Cu" "F.Paste" "F.Mask")
			(roundrect_rratio 0.25)
			(net 1 "GND")
			(pintype "passive")
		)
		(pad "2" smd roundrect
			(at 1.1 0)
			(size 1.2 1.3)
			(layers "F.Cu" "F.Paste" "F.Mask")
			(roundrect_rratio 0.25)
			(net 115 "VCC")
			(pintype "passive")
		)
	)
	(footprint "antmicro-footprints:LED_0603_1608Metric_G"
		(layer "F.Cu")
		(at 107.6 127.2 90)
		(descr "LED SMD 0603 Green")
		(tags "LED SMD 0603 Green")
		(property "Reference" "D11"
			(at 5.375 0.45 90)
			(layer "F.SilkS")
			(effects
				(font
					(size 0.7 0.7)
					(thickness 0.15)
				)
				(justify right bottom)
			)
		)
		(property "Value" "LED_G_0603_LTST-C190GKT"
			(at -0.001 1.599 90)
			(layer "F.Fab")
			(effects
				(font
					(size 0.7 0.7)
					(thickness 0.15)
				)
				(justify left bottom)
			)
		)
		(property "Footprint" "antmicro-footprints:LED_0603_1608Metric_G"
			(at 0 0 90)
			(layer "F.Fab")
			(hide yes)
			(effects
				(font
					(size 1.27 1.27)
					(thickness 0.15)
				)
			)
		)
		(property "Datasheet" "https://media.digikey.com/pdf/Data%20Sheets/Lite-On%20PDFs/LTST-C190GKT.pdf"
			(at 0 0 90)
			(layer "F.Fab")
			(hide yes)
			(effects
				(font
					(size 1.27 1.27)
					(thickness 0.15)
				)
			)
		)
		(property "Author" "Antmicro"
			(at 234.8 19.6 0)
			(layer "F.Fab")
			(hide yes)
			(effects
				(font
					(size 1 1)
					(thickness 0.15)
				)
			)
		)
		(property "Color" "Green"
			(at 234.8 19.6 0)
			(layer "F.Fab")
			(hide yes)
			(effects
				(font
					(size 1 1)
					(thickness 0.15)
				)
			)
		)
		(property "License" "Apache-2.0"
			(at 234.8 19.6 0)
			(layer "F.Fab")
			(hide yes)
			(effects
				(font
					(size 1 1)
					(thickness 0.15)
				)
			)
		)
		(property "MPN" "LTST-C190GKT"
			(at 234.8 19.6 0)
			(layer "F.Fab")
			(hide yes)
			(effects
				(font
					(size 1 1)
					(thickness 0.15)
				)
			)
		)
		(property "Manufacturer" "Lite-On"
			(at 234.8 19.6 0)
			(layer "F.Fab")
			(hide yes)
			(effects
				(font
					(size 1 1)
					(thickness 0.15)
				)
			)
		)
		(sheetname "USB3")
		(sheetfile "usb3.kicad_sch")
		(attr smd)
		(fp_line
			(start 0.22 -0.35)
			(end -0.22 -0.35)
			(stroke
				(width 0.15)
				(type solid)
			)
			(layer "F.SilkS")
		)
		(fp_line
			(start -1.18 -0.319)
			(end -1.18 0.321)
			(stroke
				(width 0.15)
				(type solid)
			)
			(layer "F.SilkS")
		)
		(fp_line
			(start 0.105328 0.001008)
			(end 0.24 0.001)
			(stroke
				(width 0.1)
				(type solid)
			)
			(layer "F.SilkS")
		)
		(fp_line
			(start -0.094672 0.001008)
			(end 0.105328 -0.198992)
			(stroke
				(width 0.1)
				(type solid)
			)
			(layer "F.SilkS")
		)
		(fp_line
			(start -0.094672 0.001008)
			(end -0.24 0.001008)
			(stroke
				(width 0.1)
				(type solid)
			)
			(layer "F.SilkS")
		)
		(fp_line
			(start 0.105328 0.201008)
			(end 0.105328 -0.198992)
			(stroke
				(width 0.1)
				(type solid)
			)
			(layer "F.SilkS")
		)
		(fp_line
			(start 0.105328 0.201008)
			(end -0.094672 0.001008)
			(stroke
				(width 0.1)
				(type solid)
			)
			(layer "F.SilkS")
		)
		(fp_line
			(start -0.094672 0.201008)
			(end -0.094672 -0.198992)
			(stroke
				(width 0.1)
				(type solid)
			)
			(layer "F.SilkS")
		)
		(fp_line
			(start 0.22 0.35)
			(end -0.22 0.35)
			(stroke
				(width 0.15)
				(type solid)
			)
			(layer "F.SilkS")
		)
		(fp_rect
			(start 1.25 0.65)
			(end -1.25 -0.65)
			(stroke
				(width 0.05)
				(type solid)
			)
			(fill none)
			(layer "F.CrtYd")
		)
		(fp_line
			(start 0.201 -0.202)
			(end -0.101 0)
			(stroke
				(width 0.15)
				(type solid)
			)
			(layer "F.Fab")
		)
		(fp_line
			(start -0.199 -0.202)
			(end -0.199 0.1)
			(stroke
				(width 0.15)
				(type solid)
			)
			(layer "F.Fab")
		)
		(fp_line
			(start 0.599 0)
			(end 0.201 0)
			(stroke
				(width 0.15)
				(type solid)
			)
			(layer "F.Fab")
		)
		(fp_line
			(start 0.201 0)
			(end 0.201 -0.202)
			(stroke
				(width 0.15)
				(type solid)
			)
			(layer "F.Fab")
		)
		(fp_line
			(start -0.101 0)
			(end 0.201 0.2)
			(stroke
				(width 0.15)
				(type solid)
			)
			(layer "F.Fab")
		)
		(fp_line
			(start -0.199 0)
			(end -0.597 0)
			(stroke
				(width 0.15)
				(type solid)
			)
			(layer "F.Fab")
		)
		(fp_line
			(start 0.201 0.2)
			(end 0.201 0)
			(stroke
				(width 0.15)
				(type solid)
			)
			(layer "F.Fab")
		)
		(fp_line
			(start -0.199 0.2)
			(end -0.199 0.1)
			(stroke
				(width 0.15)
				(type solid)
			)
			(layer "F.Fab")
		)
		(fp_rect
			(start 0.848 0.4)
			(end -0.85 -0.402)
			(stroke
				(width 0.15)
				(type solid)
			)
			(fill none)
			(layer "F.Fab")
		)
		(fp_text user "${REFERENCE}"
			(at -1.4224 5.999 90)
			(layer "F.Fab")
			(hide yes)
			(effects
				(font
					(size 0.7 0.7)
					(thickness 0.15)
				)
				(justify left bottom)
			)
		)
		(fp_text user "License: Apache-2.0"
			(at -1.4224 3.599 90)
			(layer "F.Fab")
			(hide yes)
			(effects
				(font
					(size 0.7 0.7)
					(thickness 0.15)
				)
				(justify left bottom)
			)
		)
		(fp_text user "Author: Antmicro"
			(at -1.4224 4.799 90)
			(layer "F.Fab")
			(hide yes)
			(effects
				(font
					(size 0.7 0.7)
					(thickness 0.15)
				)
				(justify left bottom)
			)
		)
		(pad "1" smd roundrect
			(at -0.7 0 270)
			(size 0.8 1)
			(layers "F.Cu" "F.Paste" "F.Mask")
			(roundrect_rratio 0.2)
			(net 1 "GND")
			(pinfunction "C")
			(pintype "passive")
		)
		(pad "2" smd roundrect
			(at 0.7 0 270)
			(size 0.8 1)
			(layers "F.Cu" "F.Paste" "F.Mask")
			(roundrect_rratio 0.2)
			(net 150 "Net-(D11-A)")
			(pinfunction "A")
			(pintype "passive")
		)
	)
	(footprint "antmicro-footprints:R_0402_1005Metric"
		(layer "F.Cu")
		(at 93.92 104.08 -135)
		(descr "Resistor SMD 0402")
		(tags "resistor SMD 0402")
		(property "Reference" "R210"
			(at 0.876812 -1.414214 -135)
			(layer "F.SilkS")
			(effects
				(font
					(size 0.7 0.7)
					(thickness 0.15)
				)
				(justify left bottom)
			)
		)
		(property "Value" "R_499R_0402"
			(at -1.011843 1.772046 -135)
			(layer "F.Fab")
			(effects
				(font
					(size 0.7 0.7)
					(thickness 0.15)
				)
				(justify left bottom)
			)
		)
		(property "Footprint" "antmicro-footprints:R_0402_1005Metric"
			(at 0 0 -135)
			(layer "F.Fab")
			(hide yes)
			(effects
				(font
					(size 1.27 1.27)
					(thickness 0.15)
				)
			)
		)
		(property "Datasheet" "https://www.mouser.com/datasheet/2/54/cr-1858361.pdf"
			(at 0 0 -135)
			(layer "F.Fab")
			(hide yes)
			(effects
				(font
					(size 1.27 1.27)
					(thickness 0.15)
				)
			)
		)
		(property "Author" "Antmicro"
			(at 86.735795 244.087143 0)
			(layer "F.Fab")
			(hide yes)
			(effects
				(font
					(size 1 1)
					(thickness 0.15)
				)
			)
		)
		(property "License" "Apache-2.0"
			(at 86.735795 244.087143 0)
			(layer "F.Fab")
			(hide yes)
			(effects
				(font
					(size 1 1)
					(thickness 0.15)
				)
			)
		)
		(property "MPN" "CR0402-FX-4990GLF"
			(at 86.735795 244.087143 0)
			(layer "F.Fab")
			(hide yes)
			(effects
				(font
					(size 1 1)
					(thickness 0.15)
				)
			)
		)
		(property "Manufacturer" "Bourns"
			(at 86.735795 244.087143 0)
			(layer "F.Fab")
			(hide yes)
			(effects
				(font
					(size 1 1)
					(thickness 0.15)
				)
			)
		)
		(property "Tolerance" "1%"
			(at 86.735795 244.087143 0)
			(layer "F.Fab")
			(hide yes)
			(effects
				(font
					(size 1 1)
					(thickness 0.15)
				)
			)
		)
		(property "Val" "499R"
			(at 86.735795 244.087143 0)
			(layer "F.Fab")
			(hide yes)
			(effects
				(font
					(size 1 1)
					(thickness 0.15)
				)
			)
		)
		(sheetname "HDMI")
		(sheetfile "hdmi.kicad_sch")
		(attr smd)
		(fp_poly
			(pts
				(xy -0.925 -0.47) (xy 0.925 -0.47) (xy 0.925 0.47) (xy -0.925 0.47)
			)
			(stroke
				(width 0.05)
				(type default)
			)
			(fill none)
			(layer "F.CrtYd")
		)
		(fp_poly
			(pts
				(xy -0.5 -0.25) (xy 0.5 -0.25) (xy 0.5 0.25) (xy -0.5 0.25)
			)
			(stroke
				(width 0.15)
				(type solid)
			)
			(fill none)
			(layer "F.Fab")
		)
		(fp_text user "License: Apache-2.0"
			(at -0.949999 5.169 -135)
			(layer "F.Fab")
			(hide yes)
			(effects
				(font
					(size 0.7 0.7)
					(thickness 0.15)
				)
				(justify left bottom)
			)
		)
		(fp_text user "Author: Antmicro"
			(at -0.95 4.169 -135)
			(layer "F.Fab")
			(hide yes)
			(effects
				(font
					(size 0.7 0.7)
					(thickness 0.15)
				)
				(justify left bottom)
			)
		)
		(fp_text user "${REFERENCE}"
			(at -0.95 3.168 -135)
			(layer "F.Fab")
			(hide yes)
			(effects
				(font
					(size 0.7 0.7)
					(thickness 0.15)
				)
				(justify left bottom)
			)
		)
		(pad "1" smd roundrect
			(at -0.48 0 225)
			(size 0.59 0.64)
			(layers "F.Cu" "F.Paste" "F.Mask")
			(roundrect_rratio 0.25)
			(net 623 "Net-(Q2-D)")
			(pintype "passive")
		)
		(pad "2" smd roundrect
			(at 0.48 0 225)
			(size 0.59 0.64)
			(layers "F.Cu" "F.Paste" "F.Mask")
			(roundrect_rratio 0.25)
			(net 492 "/HDMI/HDMI_D2_P")
			(pintype "passive")
		)
	)
	(footprint "antmicro-footprints:R_0402_1005Metric"
		(layer "F.Cu")
		(at 61 121.9)
		(descr "Resistor SMD 0402")
		(tags "resistor SMD 0402")
		(property "Reference" "R188"
			(at -0.035 1.32 0)
			(layer "F.SilkS")
			(effects
				(font
					(size 0.7 0.7)
					(thickness 0.15)
				)
				(justify left bottom)
			)
		)
		(property "Value" "R_10k_0402"
			(at 0 1.4 0)
			(layer "F.Fab")
			(effects
				(font
					(size 0.7 0.7)
					(thickness 0.15)
				)
				(justify left bottom)
			)
		)
		(property "Footprint" "antmicro-footprints:R_0402_1005Metric"
			(at 0 0 0)
			(layer "F.Fab")
			(hide yes)
			(effects
				(font
					(size 1.27 1.27)
					(thickness 0.15)
				)
			)
		)
		(property "Datasheet" "https://www.bourns.com/docs/product-datasheets/cr.pdf"
			(at 0 0 0)
			(layer "F.Fab")
			(hide yes)
			(effects
				(font
					(size 1.27 1.27)
					(thickness 0.15)
				)
			)
		)
		(property "Author" "Antmicro"
			(at 0 0 0)
			(layer "F.Fab")
			(hide yes)
			(effects
				(font
					(size 1 1)
					(thickness 0.15)
				)
			)
		)
		(property "License" "Apache-2.0"
			(at 0 0 0)
			(layer "F.Fab")
			(hide yes)
			(effects
				(font
					(size 1 1)
					(thickness 0.15)
				)
			)
		)
		(property "MPN" "CR0402-FX-1002GLF"
			(at 0 0 0)
			(layer "F.Fab")
			(hide yes)
			(effects
				(font
					(size 1 1)
					(thickness 0.15)
				)
			)
		)
		(property "Manufacturer" "Bourns"
			(at 0 0 0)
			(layer "F.Fab")
			(hide yes)
			(effects
				(font
					(size 1 1)
					(thickness 0.15)
				)
			)
		)
		(property "Tolerance" "1%"
			(at 0 0 0)
			(layer "F.Fab")
			(hide yes)
			(effects
				(font
					(size 1 1)
					(thickness 0.15)
				)
			)
		)
		(property "Val" "10k"
			(at 0 0 0)
			(layer "F.Fab")
			(hide yes)
			(effects
				(font
					(size 1 1)
					(thickness 0.15)
				)
			)
		)
		(sheetname "Supply")
		(sheetfile "supply.kicad_sch")
		(attr smd)
		(fp_rect
			(start -0.925 -0.47)
			(end 0.925 0.47)
			(stroke
				(width 0.05)
				(type default)
			)
			(fill none)
			(layer "F.CrtYd")
		)
		(fp_rect
			(start -0.5 -0.25)
			(end 0.5 0.25)
			(stroke
				(width 0.15)
				(type solid)
			)
			(fill none)
			(layer "F.Fab")
		)
		(fp_text user "Author: Antmicro"
			(at -0.95 4.169 0)
			(layer "F.Fab")
			(hide yes)
			(effects
				(font
					(size 0.7 0.7)
					(thickness 0.15)
				)
				(justify left bottom)
			)
		)
		(fp_text user "License: Apache-2.0"
			(at -0.95 5.169 0)
			(layer "F.Fab")
			(hide yes)
			(effects
				(font
					(size 0.7 0.7)
					(thickness 0.15)
				)
				(justify left bottom)
			)
		)
		(fp_text user "${REFERENCE}"
			(at -0.95 3.168 0)
			(layer "F.Fab")
			(hide yes)
			(effects
				(font
					(size 0.7 0.7)
					(thickness 0.15)
				)
				(justify left bottom)
			)
		)
		(pad "1" smd roundrect
			(at -0.48 0)
			(size 0.59 0.64)
			(layers "F.Cu" "F.Paste" "F.Mask")
			(roundrect_rratio 0.25)
			(net 654 "Net-(D53-A)")
			(pintype "passive")
		)
		(pad "2" smd roundrect
			(at 0.48 0)
			(size 0.59 0.64)
			(layers "F.Cu" "F.Paste" "F.Mask")
			(roundrect_rratio 0.25)
			(net 115 "VCC")
			(pintype "passive")
		)
	)
	(footprint "antmicro-footprints:R_0402_1005Metric"
		(layer "F.Cu")
		(at 136.3 119.7)
		(descr "Resistor SMD 0402")
		(tags "resistor SMD 0402")
		(property "Reference" "R222"
			(at -1.05 -0.4 0)
			(layer "F.SilkS")
			(effects
				(font
					(size 0.7 0.7)
					(thickness 0.15)
				)
				(justify left bottom)
			)
		)
		(property "Value" "R_100k_0402"
			(at 0 1.4 0)
			(layer "F.Fab")
			(effects
				(font
					(size 0.7 0.7)
					(thickness 0.15)
				)
				(justify left bottom)
			)
		)
		(property "Footprint" "antmicro-footprints:R_0402_1005Metric"
			(at 0 0 0)
			(layer "F.Fab")
			(hide yes)
			(effects
				(font
					(size 1.27 1.27)
					(thickness 0.15)
				)
			)
		)
		(property "Datasheet" "https://www.bourns.com/docs/product-datasheets/cr.pdf"
			(at 0 0 0)
			(layer "F.Fab")
			(hide yes)
			(effects
				(font
					(size 1.27 1.27)
					(thickness 0.15)
				)
			)
		)
		(property "Author" "Antmicro"
			(at 0 0 0)
			(layer "F.Fab")
			(hide yes)
			(effects
				(font
					(size 1 1)
					(thickness 0.15)
				)
			)
		)
		(property "License" "Apache-2.0"
			(at 0 0 0)
			(layer "F.Fab")
			(hide yes)
			(effects
				(font
					(size 1 1)
					(thickness 0.15)
				)
			)
		)
		(property "MPN" "CR0402-FX-1003GLF"
			(at 0 0 0)
			(layer "F.Fab")
			(hide yes)
			(effects
				(font
					(size 1 1)
					(thickness 0.15)
				)
			)
		)
		(property "Manufacturer" "Bourns"
			(at 0 0 0)
			(layer "F.Fab")
			(hide yes)
			(effects
				(font
					(size 1 1)
					(thickness 0.15)
				)
			)
		)
		(property "Tolerance" "1%"
			(at 0 0 0)
			(layer "F.Fab")
			(hide yes)
			(effects
				(font
					(size 1 1)
					(thickness 0.15)
				)
			)
		)
		(property "Val" "100k"
			(at 0 0 0)
			(layer "F.Fab")
			(hide yes)
			(effects
				(font
					(size 1 1)
					(thickness 0.15)
				)
			)
		)
		(sheetname "Peripherals")
		(sheetfile "peripherals.kicad_sch")
		(attr smd)
		(fp_rect
			(start -0.925 -0.47)
			(end 0.925 0.47)
			(stroke
				(width 0.05)
				(type default)
			)
			(fill none)
			(layer "F.CrtYd")
		)
		(fp_rect
			(start -0.5 -0.25)
			(end 0.5 0.25)
			(stroke
				(width 0.15)
				(type solid)
			)
			(fill none)
			(layer "F.Fab")
		)
		(fp_text user "${REFERENCE}"
			(at -0.95 3.168 0)
			(layer "F.Fab")
			(hide yes)
			(effects
				(font
					(size 0.7 0.7)
					(thickness 0.15)
				)
				(justify left bottom)
			)
		)
		(fp_text user "License: Apache-2.0"
			(at -0.95 5.169 0)
			(layer "F.Fab")
			(hide yes)
			(effects
				(font
					(size 0.7 0.7)
					(thickness 0.15)
				)
				(justify left bottom)
			)
		)
		(fp_text user "Author: Antmicro"
			(at -0.95 4.169 0)
			(layer "F.Fab")
			(hide yes)
			(effects
				(font
					(size 0.7 0.7)
					(thickness 0.15)
				)
				(justify left bottom)
			)
		)
		(pad "1" smd roundrect
			(at -0.48 0)
			(size 0.59 0.64)
			(layers "F.Cu" "F.Paste" "F.Mask")
			(roundrect_rratio 0.25)
			(net 1 "GND")
			(pintype "passive")
		)
		(pad "2" smd roundrect
			(at 0.48 0)
			(size 0.59 0.64)
			(layers "F.Cu" "F.Paste" "F.Mask")
			(roundrect_rratio 0.25)
			(net 440 "USER_LED0")
			(pintype "passive")
		)
	)
	(footprint "antmicro-footprints:R_0402_1005Metric"
		(layer "F.Cu")
		(at 101.95 87.65 90)
		(descr "Resistor SMD 0402")
		(tags "resistor SMD 0402")
		(property "Reference" "R40"
			(at -1.05 -0.45 90)
			(layer "F.SilkS")
			(effects
				(font
					(size 0.7 0.7)
					(thickness 0.15)
				)
				(justify left bottom)
			)
		)
		(property "Value" "R_0R_0402"
			(at 0 1.4 90)
			(layer "F.Fab")
			(effects
				(font
					(size 0.7 0.7)
					(thickness 0.15)
				)
				(justify left bottom)
			)
		)
		(property "Footprint" "antmicro-footprints:R_0402_1005Metric"
			(at 0 0 90)
			(layer "F.Fab")
			(hide yes)
			(effects
				(font
					(size 1.27 1.27)
					(thickness 0.15)
				)
			)
		)
		(property "Datasheet" "https://industrial.panasonic.com/cdbs/www-data/pdf/RDA0000/AOA0000C301.pdf"
			(at 0 0 90)
			(layer "F.Fab")
			(hide yes)
			(effects
				(font
					(size 1.27 1.27)
					(thickness 0.15)
				)
			)
		)
		(property "Author" "Antmicro"
			(at 189.6 -14.3 0)
			(layer "F.Fab")
			(hide yes)
			(effects
				(font
					(size 1 1)
					(thickness 0.15)
				)
			)
		)
		(property "Current" "1A"
			(at 189.6 -14.3 0)
			(layer "F.Fab")
			(hide yes)
			(effects
				(font
					(size 1 1)
					(thickness 0.15)
				)
			)
		)
		(property "License" "Apache-2.0"
			(at 189.6 -14.3 0)
			(layer "F.Fab")
			(hide yes)
			(effects
				(font
					(size 1 1)
					(thickness 0.15)
				)
			)
		)
		(property "MPN" "ERJ2GE0R00X"
			(at 189.6 -14.3 0)
			(layer "F.Fab")
			(hide yes)
			(effects
				(font
					(size 1 1)
					(thickness 0.15)
				)
			)
		)
		(property "Manufacturer" "Panasonic"
			(at 189.6 -14.3 0)
			(layer "F.Fab")
			(hide yes)
			(effects
				(font
					(size 1 1)
					(thickness 0.15)
				)
			)
		)
		(property "Tolerance" ""
			(at 189.6 -14.3 0)
			(layer "F.Fab")
			(hide yes)
			(effects
				(font
					(size 1 1)
					(thickness 0.15)
				)
			)
		)
		(property "Val" "0R"
			(at 189.6 -14.3 0)
			(layer "F.Fab")
			(hide yes)
			(effects
				(font
					(size 1 1)
					(thickness 0.15)
				)
			)
		)
		(sheetname "HDMI")
		(sheetfile "hdmi.kicad_sch")
		(attr smd)
		(fp_rect
			(start -0.925 -0.47)
			(end 0.925 0.47)
			(stroke
				(width 0.05)
				(type default)
			)
			(fill none)
			(layer "F.CrtYd")
		)
		(fp_rect
			(start -0.5 -0.25)
			(end 0.5 0.25)
			(stroke
				(width 0.15)
				(type solid)
			)
			(fill none)
			(layer "F.Fab")
		)
		(fp_text user "${REFERENCE}"
			(at -0.95 3.168 90)
			(layer "F.Fab")
			(hide yes)
			(effects
				(font
					(size 0.7 0.7)
					(thickness 0.15)
				)
				(justify left bottom)
			)
		)
		(fp_text user "License: Apache-2.0"
			(at -0.95 5.169 90)
			(layer "F.Fab")
			(hide yes)
			(effects
				(font
					(size 0.7 0.7)
					(thickness 0.15)
				)
				(justify left bottom)
			)
		)
		(fp_text user "Author: Antmicro"
			(at -0.95 4.169 90)
			(layer "F.Fab")
			(hide yes)
			(effects
				(font
					(size 0.7 0.7)
					(thickness 0.15)
				)
				(justify left bottom)
			)
		)
		(pad "1" smd roundrect
			(at -0.48 0 90)
			(size 0.59 0.64)
			(layers "F.Cu" "F.Paste" "F.Mask")
			(roundrect_rratio 0.25)
			(net 621 "Net-(Q1-S)")
			(pintype "passive")
		)
		(pad "2" smd roundrect
			(at 0.48 0 90)
			(size 0.59 0.64)
			(layers "F.Cu" "F.Paste" "F.Mask")
			(roundrect_rratio 0.25)
			(net 428 "DP1_HPD")
			(pintype "passive")
		)
	)
	(footprint "antmicro-footprints:C_0402_1005Metric"
		(layer "F.Cu")
		(at 89.3 116.05 -90)
		(descr "Capacitor SMD 0402")
		(tags "capacitor SMD 0402")
		(property "Reference" "C163"
			(at 0.24 0.53 -90)
			(layer "F.SilkS")
			(effects
				(font
					(size 0.7 0.7)
					(thickness 0.15)
				)
				(justify left bottom)
			)
		)
		(property "Value" "C_100n_0402"
			(at 0 1.4 -90)
			(layer "F.Fab")
			(effects
				(font
					(size 0.7 0.7)
					(thickness 0.15)
				)
				(justify left bottom)
			)
		)
		(property "Footprint" "antmicro-footprints:C_0402_1005Metric"
			(at 0 0 -90)
			(layer "F.Fab")
			(hide yes)
			(effects
				(font
					(size 1.27 1.27)
					(thickness 0.15)
				)
			)
		)
		(property "Datasheet" "https://www.murata.com/products/productdetail?partno=GRM155R61H104KE14%23"
			(at 0 0 -90)
			(layer "F.Fab")
			(hide yes)
			(effects
				(font
					(size 1.27 1.27)
					(thickness 0.15)
				)
			)
		)
		(property "Author" "Antmicro"
			(at -26.75 205.35 0)
			(layer "F.Fab")
			(hide yes)
			(effects
				(font
					(size 1 1)
					(thickness 0.15)
				)
			)
		)
		(property "Dielectric" "X5R"
			(at -26.75 205.35 0)
			(layer "F.Fab")
			(hide yes)
			(effects
				(font
					(size 1 1)
					(thickness 0.15)
				)
			)
		)
		(property "License" "Apache-2.0"
			(at -26.75 205.35 0)
			(layer "F.Fab")
			(hide yes)
			(effects
				(font
					(size 1 1)
					(thickness 0.15)
				)
			)
		)
		(property "MPN" "GRM155R61H104KE14D"
			(at -26.75 205.35 0)
			(layer "F.Fab")
			(hide yes)
			(effects
				(font
					(size 1 1)
					(thickness 0.15)
				)
			)
		)
		(property "Manufacturer" "Murata"
			(at -26.75 205.35 0)
			(layer "F.Fab")
			(hide yes)
			(effects
				(font
					(size 1 1)
					(thickness 0.15)
				)
			)
		)
		(property "Val" "100n"
			(at -26.75 205.35 0)
			(layer "F.Fab")
			(hide yes)
			(effects
				(font
					(size 1 1)
					(thickness 0.15)
				)
			)
		)
		(property "Voltage" "50V"
			(at -26.75 205.35 0)
			(layer "F.Fab")
			(hide yes)
			(effects
				(font
					(size 1 1)
					(thickness 0.15)
				)
			)
		)
		(sheetname "HDMI")
		(sheetfile "hdmi.kicad_sch")
		(attr smd)
		(fp_rect
			(start -0.925 -0.47)
			(end 0.925 0.47)
			(stroke
				(width 0.05)
				(type default)
			)
			(fill none)
			(layer "F.CrtYd")
		)
		(fp_line
			(start -0.494 0.248)
			(end -0.494 -0.25)
			(stroke
				(width 0.15)
				(type solid)
			)
			(layer "F.Fab")
		)
		(fp_line
			(start 0.504 0.248)
			(end -0.494 0.248)
			(stroke
				(width 0.15)
				(type solid)
			)
			(layer "F.Fab")
		)
		(fp_line
			(start -0.494 -0.25)
			(end 0.504 -0.25)
			(stroke
				(width 0.15)
				(type solid)
			)
			(layer "F.Fab")
		)
		(fp_line
			(start 0.504 -0.25)
			(end 0.504 0.248)
			(stroke
				(width 0.15)
				(type solid)
			)
			(layer "F.Fab")
		)
		(fp_text user "Author: Antmicro"
			(at -0.932 4.17 -90)
			(layer "F.Fab")
			(hide yes)
			(effects
				(font
					(size 0.7 0.7)
					(thickness 0.15)
				)
				(justify left bottom)
			)
		)
		(fp_text user "${REFERENCE}"
			(at -0.932 3.168 -90)
			(layer "F.Fab")
			(hide yes)
			(effects
				(font
					(size 0.7 0.7)
					(thickness 0.15)
				)
				(justify left bottom)
			)
		)
		(fp_text user "License: Apache-2.0"
			(at -0.932 5.17 -90)
			(layer "F.Fab")
			(hide yes)
			(effects
				(font
					(size 0.7 0.7)
					(thickness 0.15)
				)
				(justify left bottom)
			)
		)
		(pad "1" smd roundrect
			(at -0.48 0 270)
			(size 0.59 0.64)
			(layers "F.Cu" "F.Paste" "F.Mask")
			(roundrect_rratio 0.25)
			(net 1 "GND")
			(pintype "passive")
		)
		(pad "2" smd roundrect
			(at 0.48 0 270)
			(size 0.59 0.64)
			(layers "F.Cu" "F.Paste" "F.Mask")
			(roundrect_rratio 0.25)
			(net 87 "+3V3")
			(pintype "passive")
		)
	)
	(footprint "antmicro-footprints:C_0603_1608Metric"
		(layer "F.Cu")
		(at 87.75 120.8 180)
		(descr "Capacitor SMD 0603")
		(tags "capacitor 0603")
		(property "Reference" "C51"
			(at 1.825 -1.5 180)
			(layer "F.SilkS")
			(effects
				(font
					(size 0.7 0.7)
					(thickness 0.15)
				)
				(justify left bottom)
			)
		)
		(property "Value" "C_10u_0603"
			(at 0 1.6 180)
			(layer "F.Fab")
			(effects
				(font
					(size 0.7 0.7)
					(thickness 0.15)
				)
				(justify left bottom)
			)
		)
		(property "Footprint" "antmicro-footprints:C_0603_1608Metric"
			(at 0 0 180)
			(layer "F.Fab")
			(hide yes)
			(effects
				(font
					(size 1.27 1.27)
					(thickness 0.15)
				)
			)
		)
		(property "Datasheet" "https://www.murata.com/products/productdetail?partno=GRM188R61A106KE69%23"
			(at 0 0 180)
			(layer "F.Fab")
			(hide yes)
			(effects
				(font
					(size 1.27 1.27)
					(thickness 0.15)
				)
			)
		)
		(property "Author" "Antmicro"
			(at 175.5 241.6 0)
			(layer "F.Fab")
			(hide yes)
			(effects
				(font
					(size 1 1)
					(thickness 0.15)
				)
			)
		)
		(property "Dielectric" "template_dielectric"
			(at 175.5 241.6 0)
			(layer "F.Fab")
			(hide yes)
			(effects
				(font
					(size 1 1)
					(thickness 0.15)
				)
			)
		)
		(property "License" "Apache-2.0"
			(at 175.5 241.6 0)
			(layer "F.Fab")
			(hide yes)
			(effects
				(font
					(size 1 1)
					(thickness 0.15)
				)
			)
		)
		(property "MPN" "GRM188R61A106KE69D"
			(at 175.5 241.6 0)
			(layer "F.Fab")
			(hide yes)
			(effects
				(font
					(size 1 1)
					(thickness 0.15)
				)
			)
		)
		(property "Manufacturer" "Murata"
			(at 175.5 241.6 0)
			(layer "F.Fab")
			(hide yes)
			(effects
				(font
					(size 1 1)
					(thickness 0.15)
				)
			)
		)
		(property "Val" "10u"
			(at 175.5 241.6 0)
			(layer "F.Fab")
			(hide yes)
			(effects
				(font
					(size 1 1)
					(thickness 0.15)
				)
			)
		)
		(property "Voltage" ""
			(at 175.5 241.6 0)
			(layer "F.Fab")
			(hide yes)
			(effects
				(font
					(size 1 1)
					(thickness 0.15)
				)
			)
		)
		(sheetname "HDMI")
		(sheetfile "hdmi.kicad_sch")
		(attr smd)
		(fp_line
			(start -0.15 0.4)
			(end 0.15 0.4)
			(stroke
				(width 0.15)
				(type solid)
			)
			(layer "F.SilkS")
		)
		(fp_line
			(start -0.15 -0.4)
			(end 0.15 -0.4)
			(stroke
				(width 0.15)
				(type solid)
			)
			(layer "F.SilkS")
		)
		(fp_rect
			(start -1.25 -0.65)
			(end 1.25 0.65)
			(stroke
				(width 0.05)
				(type solid)
			)
			(fill none)
			(layer "F.CrtYd")
		)
		(fp_rect
			(start -0.8 -0.4)
			(end 0.8 0.4)
			(stroke
				(width 0.15)
				(type solid)
			)
			(fill none)
			(layer "F.Fab")
		)
		(fp_text user "Author: Antmicro"
			(at -1.682 4.894 180)
			(layer "F.Fab")
			(hide yes)
			(effects
				(font
					(size 0.7 0.7)
					(thickness 0.15)
				)
				(justify left bottom)
			)
		)
		(fp_text user "License: Apache-2.0"
			(at -1.682 5.895 180)
			(layer "F.Fab")
			(hide yes)
			(effects
				(font
					(size 0.7 0.7)
					(thickness 0.15)
				)
				(justify left bottom)
			)
		)
		(fp_text user "${REFERENCE}"
			(at -1.682 3.895 180)
			(layer "F.Fab")
			(hide yes)
			(effects
				(font
					(size 0.7 0.7)
					(thickness 0.15)
				)
				(justify left bottom)
			)
		)
		(pad "1" smd roundrect
			(at -0.7 0 180)
			(size 0.8 1)
			(layers "F.Cu" "F.Paste" "F.Mask")
			(roundrect_rratio 0.2)
			(net 498 "/HDMI/5V_HDMI")
			(pintype "passive")
		)
		(pad "2" smd roundrect
			(at 0.7 0 180)
			(size 0.8 1)
			(layers "F.Cu" "F.Paste" "F.Mask")
			(roundrect_rratio 0.2)
			(net 1 "GND")
			(pintype "passive")
		)
	)
	(footprint "antmicro-footprints:R_Array_4x0201_Panasonic_EXB18V"
		(layer "F.Cu")
		(at 93.625 118.3)
		(property "Reference" "R34"
			(at -1.05 -0.7 180)
			(layer "F.SilkS")
			(effects
				(font
					(size 0.7 0.7)
					(thickness 0.15)
				)
				(justify left bottom)
			)
		)
		(property "Value" "R_4x0R_0201_array"
			(at -1.1 1.8 0)
			(layer "F.Fab")
			(effects
				(font
					(size 0.7 0.7)
					(thickness 0.15)
				)
				(justify left bottom)
			)
		)
		(property "Footprint" "antmicro-footprints:R_Array_4x0201_Panasonic_EXB18V"
			(at 0 0 0)
			(layer "F.Fab")
			(hide yes)
			(effects
				(font
					(size 1.27 1.27)
					(thickness 0.15)
				)
			)
		)
		(property "Datasheet" "http://industrial.panasonic.com/cdbs/www-data/pdf/AOC0000/AOC0000C14.pdf"
			(at 0 0 0)
			(layer "F.Fab")
			(hide yes)
			(effects
				(font
					(size 1.27 1.27)
					(thickness 0.15)
				)
			)
		)
		(property "Author" "Antmicro"
			(at 0 0 0)
			(layer "F.Fab")
			(hide yes)
			(effects
				(font
					(size 1 1)
					(thickness 0.15)
				)
			)
		)
		(property "License" "Apache-2.0"
			(at 0 0 0)
			(layer "F.Fab")
			(hide yes)
			(effects
				(font
					(size 1 1)
					(thickness 0.15)
				)
			)
		)
		(property "MPN" "EXB-18VR000X"
			(at 0 0 0)
			(layer "F.Fab")
			(hide yes)
			(effects
				(font
					(size 1 1)
					(thickness 0.15)
				)
			)
		)
		(property "Manufacturer" "Panasonic"
			(at 0 0 0)
			(layer "F.Fab")
			(hide yes)
			(effects
				(font
					(size 1 1)
					(thickness 0.15)
				)
			)
		)
		(property "Val" "4x0R_0201"
			(at 0 0 0)
			(layer "F.Fab")
			(hide yes)
			(effects
				(font
					(size 1 1)
					(thickness 0.15)
				)
			)
		)
		(sheetname "HDMI")
		(sheetfile "hdmi.kicad_sch")
		(attr smd)
		(fp_line
			(start -0.8 -0.45)
			(end -0.8 0.45)
			(stroke
				(width 0.12)
				(type solid)
			)
			(layer "F.SilkS")
		)
		(fp_line
			(start 0.8 -0.45)
			(end 0.8 0.45)
			(stroke
				(width 0.12)
				(type solid)
			)
			(layer "F.SilkS")
		)
		(fp_rect
			(start -0.898 -0.66)
			(end 0.898 0.65)
			(stroke
				(width 0.05)
				(type solid)
			)
			(fill none)
			(layer "F.CrtYd")
		)
		(fp_text user "License: Apache-2.0"
			(at -1.051 6 0)
			(layer "F.Fab")
			(hide yes)
			(effects
				(font
					(size 0.7 0.7)
					(thickness 0.15)
				)
				(justify left bottom)
			)
		)
		(fp_text user "${REFERENCE}"
			(at -1.051 3.2 0)
			(layer "F.Fab")
			(hide yes)
			(effects
				(font
					(size 0.7 0.7)
					(thickness 0.15)
				)
				(justify left bottom)
			)
		)
		(fp_text user "Author: Antmicro"
			(at -1.051 4.599 0)
			(layer "F.Fab")
			(hide yes)
			(effects
				(font
					(size 0.7 0.7)
					(thickness 0.15)
				)
				(justify left bottom)
			)
		)
		(pad "1" smd roundrect
			(at -0.6 0.298)
			(size 0.2 0.4)
			(layers "F.Cu" "F.Paste" "F.Mask")
			(roundrect_rratio 0.25)
			(net 521 "/HDMI/HDMI_CLK_CONN_N")
			(pinfunction "R1.1")
			(pintype "passive")
		)
		(pad "2" smd roundrect
			(at -0.202 0.298)
			(size 0.2 0.4)
			(layers "F.Cu" "F.Paste" "F.Mask")
			(roundrect_rratio 0.25)
			(net 522 "/HDMI/HDMI_CLK_CONN_P")
			(pinfunction "R2.1")
			(pintype "passive")
		)
		(pad "3" smd roundrect
			(at 0.2 0.298)
			(size 0.2 0.4)
			(layers "F.Cu" "F.Paste" "F.Mask")
			(roundrect_rratio 0.25)
			(net 523 "/HDMI/HDMI_D0_CONN_N")
			(pinfunction "R3.1")
			(pintype "passive")
		)
		(pad "4" smd roundrect
			(at 0.598 0.298)
			(size 0.2 0.4)
			(layers "F.Cu" "F.Paste" "F.Mask")
			(roundrect_rratio 0.25)
			(net 524 "/HDMI/HDMI_D0_CONN_P")
			(pinfunction "R4.1")
			(pintype "passive")
		)
		(pad "5" smd roundrect
			(at 0.598 -0.3)
			(size 0.2 0.4)
			(layers "F.Cu" "F.Paste" "F.Mask")
			(roundrect_rratio 0.25)
			(net 494 "/HDMI/HDMI_D0_P")
			(pinfunction "R4.2")
			(pintype "passive")
		)
		(pad "6" smd roundrect
			(at 0.2 -0.3)
			(size 0.2 0.4)
			(layers "F.Cu" "F.Paste" "F.Mask")
			(roundrect_rratio 0.25)
			(net 488 "/HDMI/HDMI_D0_N")
			(pinfunction "R3.2")
			(pintype "passive")
		)
		(pad "7" smd roundrect
			(at -0.202 -0.3)
			(size 0.2 0.4)
			(layers "F.Cu" "F.Paste" "F.Mask")
			(roundrect_rratio 0.25)
			(net 495 "/HDMI/HDMI_CLK_P")
			(pinfunction "R2.2")
			(pintype "passive")
		)
		(pad "8" smd roundrect
			(at -0.6 -0.3)
			(size 0.2 0.4)
			(layers "F.Cu" "F.Paste" "F.Mask")
			(roundrect_rratio 0.25)
			(net 489 "/HDMI/HDMI_CLK_N")
			(pinfunction "R1.2")
			(pintype "passive")
		)
	)
	(footprint "antmicro-footprints:R_0402_1005Metric"
		(layer "B.Cu")
		(at 59.69 97.15 180)
		(descr "Resistor SMD 0402")
		(tags "resistor SMD 0402")
		(property "Reference" "R262"
			(at -1.34 0.53 0)
			(layer "B.SilkS")
			(effects
				(font
					(size 0.7 0.7)
					(thickness 0.15)
				)
				(justify left bottom mirror)
			)
		)
		(property "Value" "R_4k7_0402"
			(at 0 -1.4 0)
			(layer "B.Fab")
			(effects
				(font
					(size 0.7 0.7)
					(thickness 0.15)
				)
				(justify left bottom mirror)
			)
		)
		(property "Footprint" "antmicro-footprints:R_0402_1005Metric"
			(at 0 0 180)
			(layer "F.Fab")
			(hide yes)
			(effects
				(font
					(size 1.27 1.27)
					(thickness 0.15)
				)
			)
		)
		(property "Datasheet" "https://www.bourns.com/docs/product-datasheets/cr.pdf"
			(at 0 0 180)
			(layer "F.Fab")
			(hide yes)
			(effects
				(font
					(size 1.27 1.27)
					(thickness 0.15)
				)
			)
		)
		(property "Author" "Antmicro"
			(at 119.38 194.3 0)
			(layer "B.Fab")
			(hide yes)
			(effects
				(font
					(size 1 1)
					(thickness 0.15)
				)
				(justify mirror)
			)
		)
		(property "License" "Apache-2.0"
			(at 119.38 194.3 0)
			(layer "B.Fab")
			(hide yes)
			(effects
				(font
					(size 1 1)
					(thickness 0.15)
				)
				(justify mirror)
			)
		)
		(property "MPN" "CR0402-FX-4701GLF"
			(at 119.38 194.3 0)
			(layer "B.Fab")
			(hide yes)
			(effects
				(font
					(size 1 1)
					(thickness 0.15)
				)
				(justify mirror)
			)
		)
		(property "Manufacturer" "Bourns"
			(at 119.38 194.3 0)
			(layer "B.Fab")
			(hide yes)
			(effects
				(font
					(size 1 1)
					(thickness 0.15)
				)
				(justify mirror)
			)
		)
		(property "Tolerance" "1%"
			(at 119.38 194.3 0)
			(layer "B.Fab")
			(hide yes)
			(effects
				(font
					(size 1 1)
					(thickness 0.15)
				)
				(justify mirror)
			)
		)
		(property "Val" "4k7"
			(at 119.38 194.3 0)
			(layer "B.Fab")
			(hide yes)
			(effects
				(font
					(size 1 1)
					(thickness 0.15)
				)
				(justify mirror)
			)
		)
		(sheetname "USB Debug, DP")
		(sheetfile "usb.kicad_sch")
		(attr smd)
		(fp_rect
			(start -0.925 0.47)
			(end 0.925 -0.47)
			(stroke
				(width 0.05)
				(type default)
			)
			(fill none)
			(layer "B.CrtYd")
		)
		(fp_rect
			(start -0.5 0.25)
			(end 0.5 -0.25)
			(stroke
				(width 0.15)
				(type solid)
			)
			(fill none)
			(layer "B.Fab")
		)
		(fp_text user "Author: Antmicro"
			(at -0.95 -4.169 0)
			(layer "B.Fab")
			(hide yes)
			(effects
				(font
					(size 0.7 0.7)
					(thickness 0.15)
				)
				(justify left bottom mirror)
			)
		)
		(fp_text user "License: Apache-2.0"
			(at -0.95 -5.169 0)
			(layer "B.Fab")
			(hide yes)
			(effects
				(font
					(size 0.7 0.7)
					(thickness 0.15)
				)
				(justify left bottom mirror)
			)
		)
		(fp_text user "${REFERENCE}"
			(at -0.95 -3.168 0)
			(layer "B.Fab")
			(hide yes)
			(effects
				(font
					(size 0.7 0.7)
					(thickness 0.15)
				)
				(justify left bottom mirror)
			)
		)
		(pad "1" smd roundrect
			(at -0.48 0 180)
			(size 0.59 0.64)
			(layers "B.Cu" "B.Paste" "B.Mask")
			(roundrect_rratio 0.25)
			(net 87 "+3V3")
			(pintype "passive")
		)
		(pad "2" smd roundrect
			(at 0.48 0 180)
			(size 0.59 0.64)
			(layers "B.Cu" "B.Paste" "B.Mask")
			(roundrect_rratio 0.25)
			(net 302 "/USB Debug, DP/PDC_I2C1_SCL")
			(pintype "passive")
		)
	)
	(footprint "antmicro-footprints:C_2220_5650Metric"
		(layer "B.Cu")
		(at 33.8 89.6 180)
		(descr "Capacitor SMD 2220")
		(tags "capacitor SMD 2220")
		(property "Reference" "C82"
			(at -4.49 -0.28 90)
			(layer "B.SilkS")
			(effects
				(font
					(size 0.7 0.7)
					(thickness 0.15)
				)
				(justify left bottom mirror)
			)
		)
		(property "Value" "C_22u_100V_2220"
			(at 0 -3.9 0)
			(layer "B.Fab")
			(effects
				(font
					(size 0.7 0.7)
					(thickness 0.15)
				)
				(justify left bottom mirror)
			)
		)
		(property "Footprint" "antmicro-footprints:C_2220_5650Metric"
			(at 0 0 180)
			(layer "F.Fab")
			(hide yes)
			(effects
				(font
					(size 1.27 1.27)
					(thickness 0.15)
				)
			)
		)
		(property "Datasheet" "https://product.tdk.com/en/search/capacitor/ceramic/mlcc/info?part_no=C5750X7S2A226M280KB"
			(at 0 0 180)
			(layer "F.Fab")
			(hide yes)
			(effects
				(font
					(size 1.27 1.27)
					(thickness 0.15)
				)
			)
		)
		(property "Author" "Antmicro"
			(at 67.6 179.2 0)
			(layer "B.Fab")
			(hide yes)
			(effects
				(font
					(size 1 1)
					(thickness 0.15)
				)
				(justify mirror)
			)
		)
		(property "Dielectric" "X7S"
			(at 67.6 179.2 0)
			(layer "B.Fab")
			(hide yes)
			(effects
				(font
					(size 1 1)
					(thickness 0.15)
				)
				(justify mirror)
			)
		)
		(property "License" "Apache-2.0"
			(at 67.6 179.2 0)
			(layer "B.Fab")
			(hide yes)
			(effects
				(font
					(size 1 1)
					(thickness 0.15)
				)
				(justify mirror)
			)
		)
		(property "MPN" "C5750X7S2A226M280KB"
			(at 67.6 179.2 0)
			(layer "B.Fab")
			(hide yes)
			(effects
				(font
					(size 1 1)
					(thickness 0.15)
				)
				(justify mirror)
			)
		)
		(property "Manufacturer" "TDK"
			(at 67.6 179.2 0)
			(layer "B.Fab")
			(hide yes)
			(effects
				(font
					(size 1 1)
					(thickness 0.15)
				)
				(justify mirror)
			)
		)
		(property "Public" "False"
			(at 67.6 179.2 0)
			(layer "B.Fab")
			(hide yes)
			(effects
				(font
					(size 1 1)
					(thickness 0.15)
				)
				(justify mirror)
			)
		)
		(property "Val" "22u"
			(at 67.6 179.2 0)
			(layer "B.Fab")
			(hide yes)
			(effects
				(font
					(size 1 1)
					(thickness 0.15)
				)
				(justify mirror)
			)
		)
		(property "Voltage" "100V"
			(at 67.6 179.2 0)
			(layer "B.Fab")
			(hide yes)
			(effects
				(font
					(size 1 1)
					(thickness 0.15)
				)
				(justify mirror)
			)
		)
		(sheetname "Ethernet")
		(sheetfile "ethernet.kicad_sch")
		(attr smd)
		(fp_line
			(start 1.415 2.61)
			(end -1.415 2.61)
			(stroke
				(width 0.15)
				(type solid)
			)
			(layer "B.SilkS")
		)
		(fp_line
			(start 1.415 -2.61)
			(end -1.415 -2.61)
			(stroke
				(width 0.15)
				(type solid)
			)
			(layer "B.SilkS")
		)
		(fp_rect
			(start -3.7 2.95)
			(end 3.7 -2.95)
			(stroke
				(width 0.05)
				(type solid)
			)
			(fill none)
			(layer "B.CrtYd")
		)
		(fp_rect
			(start -2.85 2.5)
			(end 2.85 -2.5)
			(stroke
				(width 0.15)
				(type solid)
			)
			(fill none)
			(layer "B.Fab")
		)
		(fp_text user "Author: Antmicro"
			(at -3.7 -7.9 0)
			(layer "B.Fab")
			(hide yes)
			(effects
				(font
					(size 0.7 0.7)
					(thickness 0.15)
				)
				(justify left bottom mirror)
			)
		)
		(fp_text user "License: Apache-2.0"
			(at -3.7 -6.9 0)
			(layer "B.Fab")
			(hide yes)
			(effects
				(font
					(size 0.7 0.7)
					(thickness 0.15)
				)
				(justify left bottom mirror)
			)
		)
		(fp_text user "${REFERENCE}"
			(at -3.7 -5.9 0)
			(layer "B.Fab")
			(hide yes)
			(effects
				(font
					(size 0.7 0.7)
					(thickness 0.15)
				)
				(justify left bottom mirror)
			)
		)
		(pad "1" smd roundrect
			(at -2.55 0 180)
			(size 1.8 5.4)
			(layers "B.Cu" "B.Paste" "B.Mask")
			(roundrect_rratio 0.138889)
			(net 106 "GNDD")
			(pintype "passive")
		)
		(pad "2" smd roundrect
			(at 2.55 0 180)
			(size 1.8 5.4)
			(layers "B.Cu" "B.Paste" "B.Mask")
			(roundrect_rratio 0.138889)
			(net 105 "/Ethernet/VDD")
			(pintype "passive")
		)
	)
	(footprint "antmicro-footprints:Fiducial_1mm_Mask2mm"
		(layer "B.Cu")
		(at 39.3 81.5 180)
		(descr "Circular Fiducial, 1mm bare copper, 3mm soldermask opening")
		(tags "fiducial")
		(property "Reference" "FID6"
			(at 0 1.4 0)
			(layer "B.SilkS")
			(hide yes)
			(effects
				(font
					(size 0.7 0.7)
					(thickness 0.15)
				)
				(justify left bottom mirror)
			)
		)
		(property "Value" "Fiducial_1mm_Mask2mm"
			(at 0 -2.2 0)
			(layer "B.Fab")
			(effects
				(font
					(size 0.7 0.7)
					(thickness 0.15)
				)
				(justify left bottom mirror)
			)
		)
		(property "Footprint" "antmicro-footprints:Fiducial_1mm_Mask2mm"
			(at 0 0 180)
			(layer "F.Fab")
			(hide yes)
			(effects
				(font
					(size 1.27 1.27)
					(thickness 0.15)
				)
			)
		)
		(attr board_only exclude_from_pos_files exclude_from_bom)
		(fp_circle
			(center 0 0)
			(end 1.24 0)
			(stroke
				(width 0.05)
				(type solid)
			)
			(fill none)
			(layer "B.CrtYd")
		)
		(fp_circle
			(center 0 0)
			(end 0.999 0)
			(stroke
				(width 0.15)
				(type solid)
			)
			(fill none)
			(layer "B.Fab")
		)
		(fp_text user "License: Apache-2.0"
			(at -1.25 -7.003 0)
			(layer "B.Fab")
			(hide yes)
			(effects
				(font
					(size 0.7 0.7)
					(thickness 0.15)
				)
				(justify left bottom mirror)
			)
		)
		(fp_text user "${REFERENCE}"
			(at -1.25 -4.603 0)
			(layer "B.Fab")
			(hide yes)
			(effects
				(font
					(size 0.7 0.7)
					(thickness 0.15)
				)
				(justify left bottom mirror)
			)
		)
		(fp_text user "Author: Antmicro"
			(at -1.25 -5.803 0)
			(layer "B.Fab")
			(hide yes)
			(effects
				(font
					(size 0.7 0.7)
					(thickness 0.15)
				)
				(justify left bottom mirror)
			)
		)
		(pad "" smd circle
			(at 0 0 180)
			(size 1 1)
			(layers "B.Cu" "B.Mask")
			(solder_mask_margin 0.5)
			(clearance 0.5)
		)
	)
	(footprint "antmicro-footprints:SOT-23-3"
		(layer "B.Cu")
		(at 42.8 77.975 180)
		(property "Reference" "Q16"
			(at -0.22 -2.66 180)
			(layer "B.SilkS")
			(effects
				(font
					(size 0.7 0.7)
					(thickness 0.15)
				)
				(justify left bottom mirror)
			)
		)
		(property "Value" "SSM3J332R"
			(at -1.9 -2.7 0)
			(layer "B.Fab")
			(effects
				(font
					(size 0.7 0.7)
					(thickness 0.15)
				)
				(justify left bottom mirror)
			)
		)
		(property "Footprint" "antmicro-footprints:SOT-23-3"
			(at 0 0 180)
			(layer "F.Fab")
			(hide yes)
			(effects
				(font
					(size 1.27 1.27)
					(thickness 0.15)
				)
			)
		)
		(property "Datasheet" "https://www.mouser.com/datasheet/2/408/SSM3J332R_datasheet_en_20181015-1150575.pdf"
			(at 0 0 180)
			(layer "F.Fab")
			(hide yes)
			(effects
				(font
					(size 1.27 1.27)
					(thickness 0.15)
				)
			)
		)
		(property "Author" "Antmicro"
			(at 87.4 156.2 0)
			(layer "B.Fab")
			(hide yes)
			(effects
				(font
					(size 1 1)
					(thickness 0.15)
				)
				(justify mirror)
			)
		)
		(property "License" "Apache-2.0"
			(at 87.4 156.2 0)
			(layer "B.Fab")
			(hide yes)
			(effects
				(font
					(size 1 1)
					(thickness 0.15)
				)
				(justify mirror)
			)
		)
		(property "MPN" "SSM3J332R,LF"
			(at 87.4 156.2 0)
			(layer "B.Fab")
			(hide yes)
			(effects
				(font
					(size 1 1)
					(thickness 0.15)
				)
				(justify mirror)
			)
		)
		(property "Manufacturer" "Toshiba"
			(at 87.4 156.2 0)
			(layer "B.Fab")
			(hide yes)
			(effects
				(font
					(size 1 1)
					(thickness 0.15)
				)
				(justify mirror)
			)
		)
		(sheetname "Supply")
		(sheetfile "supply.kicad_sch")
		(attr smd)
		(fp_line
			(start 0.7 1.5)
			(end 0.7 0.4)
			(stroke
				(width 0.15)
				(type solid)
			)
			(layer "B.SilkS")
		)
		(fp_line
			(start 0.7 -1.5)
			(end 0.7 -0.4)
			(stroke
				(width 0.15)
				(type solid)
			)
			(layer "B.SilkS")
		)
		(fp_line
			(start -0.7 1.5)
			(end 0.7 1.5)
			(stroke
				(width 0.15)
				(type solid)
			)
			(layer "B.SilkS")
		)
		(fp_line
			(start -0.7 1.5)
			(end -0.85 1.35)
			(stroke
				(width 0.15)
				(type solid)
			)
			(layer "B.SilkS")
		)
		(fp_line
			(start -0.7 -1.35)
			(end -0.7 -1.5)
			(stroke
				(width 0.15)
				(type solid)
			)
			(layer "B.SilkS")
		)
		(fp_line
			(start -0.7 -1.5)
			(end 0.7 -1.5)
			(stroke
				(width 0.15)
				(type solid)
			)
			(layer "B.SilkS")
		)
		(fp_line
			(start -0.85 1.35)
			(end -1.45 1.35)
			(stroke
				(width 0.15)
				(type solid)
			)
			(layer "B.SilkS")
		)
		(fp_line
			(start 1.75 0.45)
			(end 0.825 0.45)
			(stroke
				(width 0.05)
				(type solid)
			)
			(layer "B.CrtYd")
		)
		(fp_line
			(start 1.75 -0.45)
			(end 1.75 0.45)
			(stroke
				(width 0.05)
				(type solid)
			)
			(layer "B.CrtYd")
		)
		(fp_line
			(start 0.85 -0.45)
			(end 1.75 -0.45)
			(stroke
				(width 0.05)
				(type solid)
			)
			(layer "B.CrtYd")
		)
		(fp_line
			(start 0.85 -1.65)
			(end 0.85 -0.45)
			(stroke
				(width 0.05)
				(type solid)
			)
			(layer "B.CrtYd")
		)
		(fp_line
			(start 0.825 1.6)
			(end -0.9 1.6)
			(stroke
				(width 0.05)
				(type solid)
			)
			(layer "B.CrtYd")
		)
		(fp_line
			(start 0.825 0.45)
			(end 0.825 1.6)
			(stroke
				(width 0.05)
				(type solid)
			)
			(layer "B.CrtYd")
		)
		(fp_line
			(start -0.85 0.5)
			(end -0.85 -0.5)
			(stroke
				(width 0.05)
				(type solid)
			)
			(layer "B.CrtYd")
		)
		(fp_line
			(start -0.85 -0.5)
			(end -1.75 -0.5)
			(stroke
				(width 0.05)
				(type solid)
			)
			(layer "B.CrtYd")
		)
		(fp_line
			(start -0.85 -1.4)
			(end -0.85 -1.65)
			(stroke
				(width 0.05)
				(type solid)
			)
			(layer "B.CrtYd")
		)
		(fp_line
			(start -0.85 -1.65)
			(end 0.85 -1.65)
			(stroke
				(width 0.05)
				(type solid)
			)
			(layer "B.CrtYd")
		)
		(fp_line
			(start -0.9 1.4)
			(end -0.9 1.6)
			(stroke
				(width 0.05)
				(type solid)
			)
			(layer "B.CrtYd")
		)
		(fp_line
			(start -1.75 1.4)
			(end -0.9 1.4)
			(stroke
				(width 0.05)
				(type solid)
			)
			(layer "B.CrtYd")
		)
		(fp_line
			(start -1.75 1.4)
			(end -1.75 0.5)
			(stroke
				(width 0.05)
				(type solid)
			)
			(layer "B.CrtYd")
		)
		(fp_line
			(start -1.75 0.5)
			(end -0.85 0.5)
			(stroke
				(width 0.05)
				(type solid)
			)
			(layer "B.CrtYd")
		)
		(fp_line
			(start -1.75 -0.5)
			(end -1.75 -1.4)
			(stroke
				(width 0.05)
				(type solid)
			)
			(layer "B.CrtYd")
		)
		(fp_line
			(start -1.75 -1.4)
			(end -0.85 -1.4)
			(stroke
				(width 0.05)
				(type solid)
			)
			(layer "B.CrtYd")
		)
		(fp_line
			(start 0.688 1.526)
			(end -0.437 1.526)
			(stroke
				(width 0.15)
				(type solid)
			)
			(layer "B.Fab")
		)
		(fp_line
			(start 0.688 1.52)
			(end 0.688 -1.519)
			(stroke
				(width 0.15)
				(type solid)
			)
			(layer "B.Fab")
		)
		(fp_line
			(start 0.688 -1.519)
			(end -0.712 -1.519)
			(stroke
				(width 0.15)
				(type solid)
			)
			(layer "B.Fab")
		)
		(fp_line
			(start -0.712 1.325)
			(end -0.437 1.526)
			(stroke
				(width 0.15)
				(type solid)
			)
			(layer "B.Fab")
		)
		(fp_line
			(start -0.712 -1.523)
			(end -0.712 1.325)
			(stroke
				(width 0.15)
				(type solid)
			)
			(layer "B.Fab")
		)
		(fp_text user "License: Apache-2.0"
			(at -1.8 -6.8 0)
			(layer "B.Fab")
			(hide yes)
			(effects
				(font
					(size 0.7 0.7)
					(thickness 0.15)
				)
				(justify left bottom mirror)
			)
		)
		(fp_text user "Author: Antmicro"
			(at -1.837 -5.3 0)
			(layer "B.Fab")
			(hide yes)
			(effects
				(font
					(size 0.7 0.7)
					(thickness 0.15)
				)
				(justify left bottom mirror)
			)
		)
		(fp_text user "${REFERENCE}"
			(at -1.837 -4 0)
			(layer "B.Fab")
			(hide yes)
			(effects
				(font
					(size 0.7 0.7)
					(thickness 0.15)
				)
				(justify left bottom mirror)
			)
		)
		(pad "1" smd roundrect
			(at -1.1 0.951 180)
			(size 1 0.6)
			(layers "B.Cu" "B.Paste" "B.Mask")
			(roundrect_rratio 0.15)
			(net 631 "Net-(Q16-G)")
			(pinfunction "G")
			(pintype "bidirectional")
		)
		(pad "2" smd roundrect
			(at -1.1 -0.949 180)
			(size 1 0.6)
			(layers "B.Cu" "B.Paste" "B.Mask")
			(roundrect_rratio 0.15)
			(net 328 "/Supply/VCC_IN")
			(pinfunction "S")
			(pintype "bidirectional")
		)
		(pad "3" smd roundrect
			(at 1.1 0.0005 180)
			(size 1 0.6)
			(layers "B.Cu" "B.Paste" "B.Mask")
			(roundrect_rratio 0.15)
			(net 500 "POE_OUTPUT")
			(pinfunction "D")
			(pintype "bidirectional")
		)
	)
	(footprint "antmicro-footprints:TP_SMD_0.75mm"
		(layer "B.Cu")
		(at 77.69 75.395)
		(property "Reference" "TP3"
			(at 2.485 0.445 0)
			(layer "B.SilkS")
			(effects
				(font
					(size 0.7 0.7)
					(thickness 0.15)
				)
				(justify left bottom mirror)
			)
		)
		(property "Value" "TP_0.75mm_SMD"
			(at 0 -1.2 180)
			(layer "B.Fab")
			(effects
				(font
					(size 0.7 0.7)
					(thickness 0.15)
				)
				(justify left bottom mirror)
			)
		)
		(property "Footprint" "antmicro-footprints:TP_SMD_0.75mm"
			(at 0 0 0)
			(layer "F.Fab")
			(hide yes)
			(effects
				(font
					(size 1.27 1.27)
					(thickness 0.15)
				)
			)
		)
		(property "Author" "Antmicro"
			(at 0 0 0)
			(layer "B.Fab")
			(hide yes)
			(effects
				(font
					(size 1 1)
					(thickness 0.15)
				)
				(justify mirror)
			)
		)
		(property "License" "Apache-2.0"
			(at 0 0 0)
			(layer "B.Fab")
			(hide yes)
			(effects
				(font
					(size 1 1)
					(thickness 0.15)
				)
				(justify mirror)
			)
		)
		(property "MPN" ""
			(at 0 0 0)
			(layer "B.Fab")
			(hide yes)
			(effects
				(font
					(size 1 1)
					(thickness 0.15)
				)
				(justify mirror)
			)
		)
		(property "Manufacturer" ""
			(at 0 0 0)
			(layer "B.Fab")
			(hide yes)
			(effects
				(font
					(size 1 1)
					(thickness 0.15)
				)
				(justify mirror)
			)
		)
		(sheetname "SoM")
		(sheetfile "som.kicad_sch")
		(attr exclude_from_pos_files exclude_from_bom)
		(fp_circle
			(center 0 0)
			(end 0.475 0)
			(stroke
				(width 0.05)
				(type default)
			)
			(fill none)
			(layer "B.CrtYd")
		)
		(fp_text user "License: Apache-2.0"
			(at -0.4 -5.101 180)
			(layer "B.Fab")
			(hide yes)
			(effects
				(font
					(size 0.7 0.7)
					(thickness 0.15)
				)
				(justify left bottom mirror)
			)
		)
		(fp_text user "Author: Antmicro"
			(at -0.4 -3.901 180)
			(layer "B.Fab")
			(hide yes)
			(effects
				(font
					(size 0.7 0.7)
					(thickness 0.15)
				)
				(justify left bottom mirror)
			)
		)
		(fp_text user "${REFERENCE}"
			(at -0.4 -2.7 180)
			(layer "B.Fab")
			(hide yes)
			(effects
				(font
					(size 0.7 0.7)
					(thickness 0.15)
				)
				(justify left bottom mirror)
			)
		)
		(pad "1" smd circle
			(at 0 0)
			(size 0.75 0.75)
			(layers "B.Cu" "B.Mask")
			(net 452 "/SoM/~{MOD_SLEEP}")
			(pinfunction "1")
			(pintype "passive")
		)
	)
	(footprint "antmicro-footprints:R_0402_1005Metric"
		(layer "B.Cu")
		(at 73.9 101.95)
		(descr "Resistor SMD 0402")
		(tags "resistor SMD 0402")
		(property "Reference" "R69"
			(at 0.93 -1.54 180)
			(layer "B.SilkS")
			(effects
				(font
					(size 0.7 0.7)
					(thickness 0.15)
				)
				(justify left bottom mirror)
			)
		)
		(property "Value" "R_200R_0402"
			(at 0 -1.4 180)
			(layer "B.Fab")
			(effects
				(font
					(size 0.7 0.7)
					(thickness 0.15)
				)
				(justify left bottom mirror)
			)
		)
		(property "Footprint" "antmicro-footprints:R_0402_1005Metric"
			(at 0 0 0)
			(layer "F.Fab")
			(hide yes)
			(effects
				(font
					(size 1.27 1.27)
					(thickness 0.15)
				)
			)
		)
		(property "Datasheet" "https://www.bourns.com/docs/product-datasheets/cr.pdf"
			(at 0 0 0)
			(layer "F.Fab")
			(hide yes)
			(effects
				(font
					(size 1.27 1.27)
					(thickness 0.15)
				)
			)
		)
		(property "Author" "Antmicro"
			(at 0 0 0)
			(layer "B.Fab")
			(hide yes)
			(effects
				(font
					(size 1 1)
					(thickness 0.15)
				)
				(justify mirror)
			)
		)
		(property "License" "Apache-2.0"
			(at 0 0 0)
			(layer "B.Fab")
			(hide yes)
			(effects
				(font
					(size 1 1)
					(thickness 0.15)
				)
				(justify mirror)
			)
		)
		(property "MPN" "CR0402-FX-2000GLF"
			(at 0 0 0)
			(layer "B.Fab")
			(hide yes)
			(effects
				(font
					(size 1 1)
					(thickness 0.15)
				)
				(justify mirror)
			)
		)
		(property "Manufacturer" "Bourns"
			(at 0 0 0)
			(layer "B.Fab")
			(hide yes)
			(effects
				(font
					(size 1 1)
					(thickness 0.15)
				)
				(justify mirror)
			)
		)
		(property "Tolerance" "1%"
			(at 0 0 0)
			(layer "B.Fab")
			(hide yes)
			(effects
				(font
					(size 1 1)
					(thickness 0.15)
				)
				(justify mirror)
			)
		)
		(property "Val" "200R"
			(at 0 0 0)
			(layer "B.Fab")
			(hide yes)
			(effects
				(font
					(size 1 1)
					(thickness 0.15)
				)
				(justify mirror)
			)
		)
		(sheetname "USB Debug, DP")
		(sheetfile "usb.kicad_sch")
		(attr smd)
		(fp_rect
			(start -0.925 0.47)
			(end 0.925 -0.47)
			(stroke
				(width 0.05)
				(type default)
			)
			(fill none)
			(layer "B.CrtYd")
		)
		(fp_rect
			(start -0.5 0.25)
			(end 0.5 -0.25)
			(stroke
				(width 0.15)
				(type solid)
			)
			(fill none)
			(layer "B.Fab")
		)
		(fp_text user "Author: Antmicro"
			(at -0.95 -4.169 180)
			(layer "B.Fab")
			(hide yes)
			(effects
				(font
					(size 0.7 0.7)
					(thickness 0.15)
				)
				(justify left bottom mirror)
			)
		)
		(fp_text user "${REFERENCE}"
			(at -0.95 -3.168 180)
			(layer "B.Fab")
			(hide yes)
			(effects
				(font
					(size 0.7 0.7)
					(thickness 0.15)
				)
				(justify left bottom mirror)
			)
		)
		(fp_text user "License: Apache-2.0"
			(at -0.95 -5.169 180)
			(layer "B.Fab")
			(hide yes)
			(effects
				(font
					(size 0.7 0.7)
					(thickness 0.15)
				)
				(justify left bottom mirror)
			)
		)
		(pad "1" smd roundrect
			(at -0.48 0)
			(size 0.59 0.64)
			(layers "B.Cu" "B.Paste" "B.Mask")
			(roundrect_rratio 0.25)
			(net 301 "/USB Debug, DP/PDC_GPIO15")
			(pintype "passive")
		)
		(pad "2" smd roundrect
			(at 0.48 0)
			(size 0.59 0.64)
			(layers "B.Cu" "B.Paste" "B.Mask")
			(roundrect_rratio 0.25)
			(net 145 "Net-(D5-A)")
			(pintype "passive")
		)
	)
	(footprint "antmicro-footprints:TSOT23-6"
		(layer "B.Cu")
		(at 133.95 113.95 -90)
		(property "Reference" "U25"
			(at -1.99 -1.11 180)
			(layer "B.SilkS")
			(effects
				(font
					(size 0.7 0.7)
					(thickness 0.15)
				)
				(justify left bottom mirror)
			)
		)
		(property "Value" "AP22615A_TSOT26"
			(at 0 -2.6 90)
			(layer "B.Fab")
			(effects
				(font
					(size 0.7 0.7)
					(thickness 0.15)
				)
				(justify left bottom mirror)
			)
		)
		(property "Footprint" "antmicro-footprints:TSOT23-6"
			(at 0 0 -90)
			(layer "F.Fab")
			(hide yes)
			(effects
				(font
					(size 1.27 1.27)
					(thickness 0.15)
				)
			)
		)
		(property "Datasheet" "https://www.mouser.com/datasheet/2/115/DIOD_S_A0008958405_1-2543193.pdf"
			(at 0 0 -90)
			(layer "F.Fab")
			(hide yes)
			(effects
				(font
					(size 1.27 1.27)
					(thickness 0.15)
				)
			)
		)
		(property "Author" "Antmicro"
			(at 20 247.9 0)
			(layer "B.Fab")
			(hide yes)
			(effects
				(font
					(size 1 1)
					(thickness 0.15)
				)
				(justify mirror)
			)
		)
		(property "License" "Apache-2.0"
			(at 20 247.9 0)
			(layer "B.Fab")
			(hide yes)
			(effects
				(font
					(size 1 1)
					(thickness 0.15)
				)
				(justify mirror)
			)
		)
		(property "MPN" "AP22615AWU-7"
			(at 20 247.9 0)
			(layer "B.Fab")
			(hide yes)
			(effects
				(font
					(size 1 1)
					(thickness 0.15)
				)
				(justify mirror)
			)
		)
		(property "Manufacturer" "Diodes Incorporated"
			(at 20 247.9 0)
			(layer "B.Fab")
			(hide yes)
			(effects
				(font
					(size 1 1)
					(thickness 0.15)
				)
				(justify mirror)
			)
		)
		(sheetname "CSI")
		(sheetfile "csi.kicad_sch")
		(attr smd)
		(fp_line
			(start -1 1.5)
			(end 1 1.497)
			(stroke
				(width 0.15)
				(type solid)
			)
			(layer "B.SilkS")
		)
		(fp_line
			(start -1 1.375)
			(end -1 1.5)
			(stroke
				(width 0.15)
				(type solid)
			)
			(layer "B.SilkS")
		)
		(fp_line
			(start 1 1.375)
			(end 1 1.497)
			(stroke
				(width 0.15)
				(type solid)
			)
			(layer "B.SilkS")
		)
		(fp_line
			(start -1 -1.4)
			(end -1 -1.55)
			(stroke
				(width 0.15)
				(type solid)
			)
			(layer "B.SilkS")
		)
		(fp_line
			(start 1 -1.4)
			(end 1 -1.55)
			(stroke
				(width 0.15)
				(type solid)
			)
			(layer "B.SilkS")
		)
		(fp_line
			(start -1 -1.55)
			(end 1 -1.55)
			(stroke
				(width 0.15)
				(type solid)
			)
			(layer "B.SilkS")
		)
		(fp_circle
			(center -1.44 1.5)
			(end -1.39 1.5)
			(stroke
				(width 0.15)
				(type solid)
			)
			(fill solid)
			(layer "B.SilkS")
		)
		(fp_rect
			(start 1.93 1.7)
			(end -1.93 -1.7)
			(stroke
				(width 0.05)
				(type solid)
			)
			(fill none)
			(layer "B.CrtYd")
		)
		(fp_line
			(start -0.876 1.096)
			(end -0.45 1.521)
			(stroke
				(width 0.15)
				(type solid)
			)
			(layer "B.Fab")
		)
		(fp_rect
			(start 0.875 -1.528)
			(end -0.875 1.525)
			(stroke
				(width 0.15)
				(type solid)
			)
			(fill none)
			(layer "B.Fab")
		)
		(fp_text user "${REFERENCE}"
			(at -1.93 -3.8 90)
			(layer "B.Fab")
			(hide yes)
			(effects
				(font
					(size 0.7 0.7)
					(thickness 0.15)
				)
				(justify left bottom mirror)
			)
		)
		(fp_text user "Author: Antmicro"
			(at -1.93 -5 90)
			(layer "B.Fab")
			(hide yes)
			(effects
				(font
					(size 0.7 0.7)
					(thickness 0.15)
				)
				(justify left bottom mirror)
			)
		)
		(fp_text user "License: Apache-2.0"
			(at -1.93 -6.199 90)
			(layer "B.Fab")
			(hide yes)
			(effects
				(font
					(size 0.7 0.7)
					(thickness 0.15)
				)
				(justify left bottom mirror)
			)
		)
		(pad "1" smd rect
			(at -1.301 0.947)
			(size 0.7 1.2)
			(layers "B.Cu" "B.Paste" "B.Mask")
			(net 108 "/CSI/CSIA_3V3")
			(pinfunction "OUT")
			(pintype "power_out")
		)
		(pad "2" smd rect
			(at -1.301 -0.004)
			(size 0.7 1.2)
			(layers "B.Cu" "B.Paste" "B.Mask")
			(net 1 "GND")
			(pinfunction "GND")
			(pintype "power_in")
		)
		(pad "3" smd rect
			(at -1.301 -0.954)
			(size 0.7 1.2)
			(layers "B.Cu" "B.Paste" "B.Mask")
			(net 311 "CSIA_FLG")
			(pinfunction "FLG")
			(pintype "output")
		)
		(pad "4" smd rect
			(at 1.299 -0.954)
			(size 0.7 1.2)
			(layers "B.Cu" "B.Paste" "B.Mask")
			(net 322 "CSIA_PEN")
			(pinfunction "EN")
			(pintype "input")
		)
		(pad "5" smd rect
			(at 1.299 -0.004)
			(size 0.7 1.2)
			(layers "B.Cu" "B.Paste" "B.Mask")
			(net 335 "/CSI/CSIA_3V3_ISET")
			(pinfunction "ISET")
			(pintype "passive")
		)
		(pad "6" smd rect
			(at 1.299 0.947)
			(size 0.7 1.2)
			(layers "B.Cu" "B.Paste" "B.Mask")
			(net 87 "+3V3")
			(pinfunction "IN")
			(pintype "power_in")
		)
	)
	(footprint "antmicro-footprints:R_0402_1005Metric"
		(layer "B.Cu")
		(at 91.81 100.59 -135)
		(descr "Resistor SMD 0402")
		(tags "resistor SMD 0402")
		(property "Reference" "R212"
			(at -1.435427 -1.308148 45)
			(layer "B.SilkS")
			(effects
				(font
					(size 0.7 0.7)
					(thickness 0.15)
				)
				(justify left bottom mirror)
			)
		)
		(property "Value" "R_499R_0402"
			(at -1.011843 -1.772046 45)
			(layer "B.Fab")
			(effects
				(font
					(size 0.7 0.7)
					(thickness 0.15)
				)
				(justify left bottom mirror)
			)
		)
		(property "Footprint" "antmicro-footprints:R_0402_1005Metric"
			(at 0 0 -135)
			(layer "F.Fab")
			(hide yes)
			(effects
				(font
					(size 1.27 1.27)
					(thickness 0.15)
				)
			)
		)
		(property "Datasheet" "https://www.mouser.com/datasheet/2/54/cr-1858361.pdf"
			(at 0 0 -135)
			(layer "F.Fab")
			(hide yes)
			(effects
				(font
					(size 1.27 1.27)
					(thickness 0.15)
				)
			)
		)
		(property "Author" "Antmicro"
			(at 85.601602 236.637345 0)
			(layer "B.Fab")
			(hide yes)
			(effects
				(font
					(size 1 1)
					(thickness 0.15)
				)
				(justify mirror)
			)
		)
		(property "License" "Apache-2.0"
			(at 85.601602 236.637345 0)
			(layer "B.Fab")
			(hide yes)
			(effects
				(font
					(size 1 1)
					(thickness 0.15)
				)
				(justify mirror)
			)
		)
		(property "MPN" "CR0402-FX-4990GLF"
			(at 85.601602 236.637345 0)
			(layer "B.Fab")
			(hide yes)
			(effects
				(font
					(size 1 1)
					(thickness 0.15)
				)
				(justify mirror)
			)
		)
		(property "Manufacturer" "Bourns"
			(at 85.601602 236.637345 0)
			(layer "B.Fab")
			(hide yes)
			(effects
				(font
					(size 1 1)
					(thickness 0.15)
				)
				(justify mirror)
			)
		)
		(property "Tolerance" "1%"
			(at 85.601602 236.637345 0)
			(layer "B.Fab")
			(hide yes)
			(effects
				(font
					(size 1 1)
					(thickness 0.15)
				)
				(justify mirror)
			)
		)
		(property "Val" "499R"
			(at 85.601602 236.637345 0)
			(layer "B.Fab")
			(hide yes)
			(effects
				(font
					(size 1 1)
					(thickness 0.15)
				)
				(justify mirror)
			)
		)
		(sheetname "HDMI")
		(sheetfile "hdmi.kicad_sch")
		(attr smd)
		(fp_poly
			(pts
				(xy -0.925 0.47) (xy 0.925 0.47) (xy 0.925 -0.47) (xy -0.925 -0.47)
			)
			(stroke
				(width 0.05)
				(type default)
			)
			(fill none)
			(layer "B.CrtYd")
		)
		(fp_poly
			(pts
				(xy -0.5 0.25) (xy 0.5 0.25) (xy 0.5 -0.25) (xy -0.5 -0.25)
			)
			(stroke
				(width 0.15)
				(type solid)
			)
			(fill none)
			(layer "B.Fab")
		)
		(fp_text user "Author: Antmicro"
			(at -0.95 -4.169 45)
			(layer "B.Fab")
			(hide yes)
			(effects
				(font
					(size 0.7 0.7)
					(thickness 0.15)
				)
				(justify left bottom mirror)
			)
		)
		(fp_text user "License: Apache-2.0"
			(at -0.949999 -5.169 45)
			(layer "B.Fab")
			(hide yes)
			(effects
				(font
					(size 0.7 0.7)
					(thickness 0.15)
				)
				(justify left bottom mirror)
			)
		)
		(fp_text user "${REFERENCE}"
			(at -0.95 -3.168 45)
			(layer "B.Fab")
			(hide yes)
			(effects
				(font
					(size 0.7 0.7)
					(thickness 0.15)
				)
				(justify left bottom mirror)
			)
		)
		(pad "1" smd roundrect
			(at -0.48 0 225)
			(size 0.59 0.64)
			(layers "B.Cu" "B.Paste" "B.Mask")
			(roundrect_rratio 0.25)
			(net 623 "Net-(Q2-D)")
			(pintype "passive")
		)
		(pad "2" smd roundrect
			(at 0.48 0 225)
			(size 0.59 0.64)
			(layers "B.Cu" "B.Paste" "B.Mask")
			(roundrect_rratio 0.25)
			(net 487 "/HDMI/HDMI_D1_N")
			(pintype "passive")
		)
	)
	(footprint "antmicro-footprints:C_0402_1005Metric"
		(layer "B.Cu")
		(at 65.3 76.5 180)
		(descr "Capacitor SMD 0402")
		(tags "capacitor SMD 0402")
		(property "Reference" "C118"
			(at -16.91 -3.45 0)
			(layer "B.SilkS")
			(effects
				(font
					(size 0.7 0.7)
					(thickness 0.15)
				)
				(justify left bottom mirror)
			)
		)
		(property "Value" "C_100n_0402"
			(at 0 -1.4 0)
			(layer "B.Fab")
			(effects
				(font
					(size 0.7 0.7)
					(thickness 0.15)
				)
				(justify left bottom mirror)
			)
		)
		(property "Footprint" "antmicro-footprints:C_0402_1005Metric"
			(at 0 0 180)
			(layer "F.Fab")
			(hide yes)
			(effects
				(font
					(size 1.27 1.27)
					(thickness 0.15)
				)
			)
		)
		(property "Datasheet" "https://www.murata.com/products/productdetail?partno=GRM155R61H104KE14%23"
			(at 0 0 180)
			(layer "F.Fab")
			(hide yes)
			(effects
				(font
					(size 1.27 1.27)
					(thickness 0.15)
				)
			)
		)
		(property "Author" "Antmicro"
			(at 130.6 153 0)
			(layer "B.Fab")
			(hide yes)
			(effects
				(font
					(size 1 1)
					(thickness 0.15)
				)
				(justify mirror)
			)
		)
		(property "Dielectric" "X5R"
			(at 130.6 153 0)
			(layer "B.Fab")
			(hide yes)
			(effects
				(font
					(size 1 1)
					(thickness 0.15)
				)
				(justify mirror)
			)
		)
		(property "License" "Apache-2.0"
			(at 130.6 153 0)
			(layer "B.Fab")
			(hide yes)
			(effects
				(font
					(size 1 1)
					(thickness 0.15)
				)
				(justify mirror)
			)
		)
		(property "MPN" "GRM155R61H104KE14D"
			(at 130.6 153 0)
			(layer "B.Fab")
			(hide yes)
			(effects
				(font
					(size 1 1)
					(thickness 0.15)
				)
				(justify mirror)
			)
		)
		(property "Manufacturer" "Murata"
			(at 130.6 153 0)
			(layer "B.Fab")
			(hide yes)
			(effects
				(font
					(size 1 1)
					(thickness 0.15)
				)
				(justify mirror)
			)
		)
		(property "Val" "100n"
			(at 130.6 153 0)
			(layer "B.Fab")
			(hide yes)
			(effects
				(font
					(size 1 1)
					(thickness 0.15)
				)
				(justify mirror)
			)
		)
		(property "Voltage" "50V"
			(at 130.6 153 0)
			(layer "B.Fab")
			(hide yes)
			(effects
				(font
					(size 1 1)
					(thickness 0.15)
				)
				(justify mirror)
			)
		)
		(sheetname "Supply")
		(sheetfile "supply.kicad_sch")
		(attr smd)
		(fp_rect
			(start -0.925 0.47)
			(end 0.925 -0.47)
			(stroke
				(width 0.05)
				(type default)
			)
			(fill none)
			(layer "B.CrtYd")
		)
		(fp_line
			(start 0.504 0.25)
			(end -0.494 0.25)
			(stroke
				(width 0.15)
				(type solid)
			)
			(layer "B.Fab")
		)
		(fp_line
			(start 0.504 -0.248)
			(end 0.504 0.25)
			(stroke
				(width 0.15)
				(type solid)
			)
			(layer "B.Fab")
		)
		(fp_line
			(start -0.494 0.25)
			(end -0.494 -0.248)
			(stroke
				(width 0.15)
				(type solid)
			)
			(layer "B.Fab")
		)
		(fp_line
			(start -0.494 -0.248)
			(end 0.504 -0.248)
			(stroke
				(width 0.15)
				(type solid)
			)
			(layer "B.Fab")
		)
		(fp_text user "License: Apache-2.0"
			(at -0.932 -5.17 0)
			(layer "B.Fab")
			(hide yes)
			(effects
				(font
					(size 0.7 0.7)
					(thickness 0.15)
				)
				(justify left bottom mirror)
			)
		)
		(fp_text user "Author: Antmicro"
			(at -0.932 -4.17 0)
			(layer "B.Fab")
			(hide yes)
			(effects
				(font
					(size 0.7 0.7)
					(thickness 0.15)
				)
				(justify left bottom mirror)
			)
		)
		(fp_text user "${REFERENCE}"
			(at -0.932 -3.168 0)
			(layer "B.Fab")
			(hide yes)
			(effects
				(font
					(size 0.7 0.7)
					(thickness 0.15)
				)
				(justify left bottom mirror)
			)
		)
		(pad "1" smd roundrect
			(at -0.48 0 180)
			(size 0.59 0.64)
			(layers "B.Cu" "B.Paste" "B.Mask")
			(roundrect_rratio 0.25)
			(net 1 "GND")
			(pintype "passive")
		)
		(pad "2" smd roundrect
			(at 0.48 0 180)
			(size 0.59 0.64)
			(layers "B.Cu" "B.Paste" "B.Mask")
			(roundrect_rratio 0.25)
			(net 117 "3V3_STDB")
			(pintype "passive")
		)
	)
	(footprint "antmicro-footprints:VQFN-20_5x5x1mm_P0.65mm"
		(layer "B.Cu")
		(at 51.2 87.4375 90)
		(property "Reference" "U22"
			(at 2.9125 3.025 0)
			(layer "B.SilkS")
			(effects
				(font
					(size 0.7 0.7)
					(thickness 0.15)
				)
				(justify left bottom mirror)
			)
		)
		(property "Value" "TPS2372-3RGWR"
			(at 0 -3.883 -90)
			(layer "B.Fab")
			(effects
				(font
					(size 0.7 0.7)
					(thickness 0.15)
				)
				(justify left bottom mirror)
			)
		)
		(property "Footprint" "antmicro-footprints:VQFN-20_5x5x1mm_P0.65mm"
			(at 0 0 90)
			(layer "F.Fab")
			(hide yes)
			(effects
				(font
					(size 1.27 1.27)
					(thickness 0.15)
				)
			)
		)
		(property "Datasheet" "https://www.ti.com/lit/ds/symlink/tps2372.pdf?ts=1679042478513&ref_url=https%253A%252F%252Fwww.google.com%252F"
			(at 0 0 90)
			(layer "F.Fab")
			(hide yes)
			(effects
				(font
					(size 1.27 1.27)
					(thickness 0.15)
				)
			)
		)
		(property "Author" "Antmicro"
			(at 138.6375 36.2375 0)
			(layer "B.Fab")
			(hide yes)
			(effects
				(font
					(size 1 1)
					(thickness 0.15)
				)
				(justify mirror)
			)
		)
		(property "License" "Apache-2.0"
			(at 138.6375 36.2375 0)
			(layer "B.Fab")
			(hide yes)
			(effects
				(font
					(size 1 1)
					(thickness 0.15)
				)
				(justify mirror)
			)
		)
		(property "MPN" "TPS2372-3RGWR"
			(at 138.6375 36.2375 0)
			(layer "B.Fab")
			(hide yes)
			(effects
				(font
					(size 1 1)
					(thickness 0.15)
				)
				(justify mirror)
			)
		)
		(property "Manufacturer" "Texas Instruments"
			(at 138.6375 36.2375 0)
			(layer "B.Fab")
			(hide yes)
			(effects
				(font
					(size 1 1)
					(thickness 0.15)
				)
				(justify mirror)
			)
		)
		(sheetname "Ethernet")
		(sheetfile "ethernet.kicad_sch")
		(attr smd)
		(fp_poly
			(pts
				(xy 0.108 -0.088) (xy 1.08 -0.088) (xy 1.08 -1.08) (xy 0.108 -1.08)
			)
			(stroke
				(width 0.01)
				(type solid)
			)
			(fill solid)
			(layer "B.Paste")
		)
		(fp_poly
			(pts
				(xy -1.081 -0.088) (xy -0.11 -0.088) (xy -0.11 -1.08) (xy -1.081 -1.08)
			)
			(stroke
				(width 0.01)
				(type solid)
			)
			(fill solid)
			(layer "B.Paste")
		)
		(fp_poly
			(pts
				(xy 0.108 1.081) (xy 1.08 1.081) (xy 1.08 0.09) (xy 0.108 0.09)
			)
			(stroke
				(width 0.01)
				(type solid)
			)
			(fill solid)
			(layer "B.Paste")
		)
		(fp_poly
			(pts
				(xy -1.081 1.081) (xy -0.11 1.081) (xy -0.11 0.09) (xy -1.081 0.09)
			)
			(stroke
				(width 0.01)
				(type solid)
			)
			(fill solid)
			(layer "B.Paste")
		)
		(fp_line
			(start 1.789 -2.499)
			(end 2.499 -2.499)
			(stroke
				(width 0.15)
				(type solid)
			)
			(layer "B.SilkS")
		)
		(fp_line
			(start -1.79 -2.499)
			(end -2.5 -2.499)
			(stroke
				(width 0.15)
				(type solid)
			)
			(layer "B.SilkS")
		)
		(fp_line
			(start 2.499 -1.789)
			(end 2.499 -2.499)
			(stroke
				(width 0.15)
				(type solid)
			)
			(layer "B.SilkS")
		)
		(fp_line
			(start -2.5 -1.789)
			(end -2.5 -2.499)
			(stroke
				(width 0.15)
				(type solid)
			)
			(layer "B.SilkS")
		)
		(fp_line
			(start 2.499 1.79)
			(end 2.499 2.5)
			(stroke
				(width 0.15)
				(type solid)
			)
			(layer "B.SilkS")
		)
		(fp_line
			(start 1.789 2.5)
			(end 2.499 2.5)
			(stroke
				(width 0.15)
				(type solid)
			)
			(layer "B.SilkS")
		)
		(fp_line
			(start -2.5 2.5)
			(end -1.625 2.5)
			(stroke
				(width 0.15)
				(type solid)
			)
			(layer "B.SilkS")
		)
		(fp_circle
			(center -2.775 1.875)
			(end -2.725 1.825)
			(stroke
				(width 0.15)
				(type solid)
			)
			(fill solid)
			(layer "B.SilkS")
		)
		(fp_rect
			(start -2.95 2.95)
			(end 2.95 -2.95)
			(stroke
				(width 0.05)
				(type solid)
			)
			(fill none)
			(layer "B.CrtYd")
		)
		(fp_line
			(start -2.5 -2.499)
			(end 2.499 -2.499)
			(stroke
				(width 0.15)
				(type solid)
			)
			(layer "B.Fab")
		)
		(fp_line
			(start -2.5 1.65)
			(end -2.5 -2.499)
			(stroke
				(width 0.15)
				(type solid)
			)
			(layer "B.Fab")
		)
		(fp_line
			(start 2.499 2.5)
			(end 2.499 -2.499)
			(stroke
				(width 0.15)
				(type solid)
			)
			(layer "B.Fab")
		)
		(fp_line
			(start -1.65 2.5)
			(end -2.5 1.65)
			(stroke
				(width 0.15)
				(type solid)
			)
			(layer "B.Fab")
		)
		(fp_line
			(start -1.65 2.5)
			(end 2.499 2.5)
			(stroke
				(width 0.15)
				(type solid)
			)
			(layer "B.Fab")
		)
		(fp_text user "Author: Antmicro"
			(at -2.5 -6.884 -90)
			(layer "B.Fab")
			(hide yes)
			(effects
				(font
					(size 0.7 0.7)
					(thickness 0.15)
				)
				(justify left bottom mirror)
			)
		)
		(fp_text user "License: Apache-2.0"
			(at -2.5 -7.884 -90)
			(layer "B.Fab")
			(hide yes)
			(effects
				(font
					(size 0.7 0.7)
					(thickness 0.15)
				)
				(justify left bottom mirror)
			)
		)
		(fp_text user "${REFERENCE}"
			(at -2.5 -5.884 -90)
			(layer "B.Fab")
			(hide yes)
			(effects
				(font
					(size 0.7 0.7)
					(thickness 0.15)
				)
				(justify left bottom mirror)
			)
		)
		(pad "1" smd roundrect
			(at -2.327 1.301 90)
			(size 0.75 0.31)
			(layers "B.Cu" "B.Paste" "B.Mask")
			(roundrect_rratio 0.25)
			(net 105 "/Ethernet/VDD")
			(pinfunction "VDD")
			(pintype "power_in")
		)
		(pad "2" smd roundrect
			(at -2.327 0.652 90)
			(size 0.75 0.31)
			(layers "B.Cu" "B.Paste" "B.Mask")
			(roundrect_rratio 0.25)
			(net 570 "/Ethernet/DEN")
			(pinfunction "DEN")
			(pintype "input")
		)
		(pad "3" smd roundrect
			(at -2.327 0 90)
			(size 0.75 0.31)
			(layers "B.Cu" "B.Paste" "B.Mask")
			(roundrect_rratio 0.25)
			(net 568 "/Ethernet/CLSA")
			(pinfunction "CLSA")
			(pintype "input")
		)
		(pad "4" smd roundrect
			(at -2.327 -0.65 90)
			(size 0.75 0.31)
			(layers "B.Cu" "B.Paste" "B.Mask")
			(roundrect_rratio 0.25)
			(net 499 "/Ethernet/VSS")
			(pinfunction "VSSA")
			(pintype "power_in")
		)
		(pad "5" smd roundrect
			(at -2.327 -1.3 90)
			(size 0.75 0.31)
			(layers "B.Cu" "B.Paste" "B.Mask")
			(roundrect_rratio 0.25)
			(net 499 "/Ethernet/VSS")
			(pinfunction "VSSB")
			(pintype "power_in")
		)
		(pad "6" smd roundrect
			(at -1.301 -2.325 90)
			(size 0.31 0.75)
			(layers "B.Cu" "B.Paste" "B.Mask")
			(roundrect_rratio 0.25)
			(net 569 "/Ethernet/CLSB")
			(pinfunction "CLSB")
			(pintype "input")
		)
		(pad "7" smd roundrect
			(at -0.652 -2.325 90)
			(size 0.31 0.75)
			(layers "B.Cu" "B.Paste" "B.Mask")
			(roundrect_rratio 0.25)
			(net 566 "/Ethernet/REF")
			(pinfunction "REF")
			(pintype "input")
		)
		(pad "8" smd roundrect
			(at 0 -2.325 90)
			(size 0.31 0.75)
			(layers "B.Cu" "B.Paste" "B.Mask")
			(roundrect_rratio 0.25)
			(net 565 "/Ethernet/AMPS_CTL")
			(pinfunction "AMPS_CTL")
			(pintype "input")
		)
		(pad "9" smd roundrect
			(at 0.65 -2.325 90)
			(size 0.31 0.75)
			(layers "B.Cu" "B.Paste" "B.Mask")
			(roundrect_rratio 0.25)
			(net 567 "/Ethernet/MPS_DUTY")
			(pinfunction "MPS_DUTY")
			(pintype "input")
		)
		(pad "10" smd roundrect
			(at 1.3 -2.325 90)
			(size 0.31 0.75)
			(layers "B.Cu" "B.Paste" "B.Mask")
			(roundrect_rratio 0.25)
			(net 704 "unconnected-(U22-~{AUTCLS}-Pad10)")
			(pinfunction "~{AUTCLS}")
			(pintype "input+no_connect")
		)
		(pad "11" smd roundrect
			(at 2.325 -1.3 90)
			(size 0.75 0.31)
			(layers "B.Cu" "B.Paste" "B.Mask")
			(roundrect_rratio 0.25)
			(net 106 "GNDD")
			(pinfunction "RTNA")
			(pintype "power_out")
		)
		(pad "12" smd roundrect
			(at 2.325 -0.65 90)
			(size 0.75 0.31)
			(layers "B.Cu" "B.Paste" "B.Mask")
			(roundrect_rratio 0.25)
			(net 106 "GNDD")
			(pinfunction "RTNB")
			(pintype "power_out")
		)
		(pad "13" smd roundrect
			(at 2.325 0 90)
			(size 0.75 0.31)
			(layers "B.Cu" "B.Paste" "B.Mask")
			(roundrect_rratio 0.25)
			(net 571 "/Ethernet/PG")
			(pinfunction "PG")
			(pintype "output")
		)
		(pad "14" smd roundrect
			(at 2.325 0.652 90)
			(size 0.75 0.31)
			(layers "B.Cu" "B.Paste" "B.Mask")
			(roundrect_rratio 0.25)
			(net 705 "unconnected-(U22-NC-Pad14)")
			(pinfunction "NC")
			(pintype "no_connect")
		)
		(pad "15" smd roundrect
			(at 2.325 1.301 90)
			(size 0.75 0.31)
			(layers "B.Cu" "B.Paste" "B.Mask")
			(roundrect_rratio 0.25)
			(net 706 "unconnected-(U22-NC-Pad15)")
			(pinfunction "NC")
			(pintype "no_connect")
		)
		(pad "16" smd roundrect
			(at 1.3 2.327 90)
			(size 0.31 0.75)
			(layers "B.Cu" "B.Paste" "B.Mask")
			(roundrect_rratio 0.25)
			(net 707 "unconnected-(U22-IRSHDL_EN-Pad16)")
			(pinfunction "IRSHDL_EN")
			(pintype "output+no_connect")
		)
		(pad "17" smd roundrect
			(at 0.65 2.327 90)
			(size 0.31 0.75)
			(layers "B.Cu" "B.Paste" "B.Mask")
			(roundrect_rratio 0.25)
			(net 573 "/Ethernet/TPL")
			(pinfunction "TPL")
			(pintype "output")
		)
		(pad "18" smd roundrect
			(at 0 2.327 90)
			(size 0.31 0.75)
			(layers "B.Cu" "B.Paste" "B.Mask")
			(roundrect_rratio 0.25)
			(net 572 "/Ethernet/TPH")
			(pinfunction "TPH")
			(pintype "output")
		)
		(pad "19" smd roundrect
			(at -0.652 2.327 90)
			(size 0.31 0.75)
			(layers "B.Cu" "B.Paste" "B.Mask")
			(roundrect_rratio 0.25)
			(net 574 "/Ethernet/~{BT}")
			(pinfunction "~{BT}")
			(pintype "output")
		)
		(pad "20" smd roundrect
			(at -1.301 2.327 90)
			(size 0.31 0.75)
			(layers "B.Cu" "B.Paste" "B.Mask")
			(roundrect_rratio 0.25)
			(net 709 "unconnected-(U22-NC-Pad20)")
			(pinfunction "NC")
			(pintype "no_connect")
		)
		(pad "21" smd rect
			(at 0 0 90)
			(size 2.2 2.2)
			(layers "B.Cu" "B.Mask")
			(net 499 "/Ethernet/VSS")
			(pinfunction "PAD_VSSC")
			(pintype "power_in")
		)
	)
	(footprint "antmicro-footprints:LED_0603_1608Metric_G"
		(layer "B.Cu")
		(at 60.55 127.2 90)
		(descr "LED SMD 0603 Green")
		(tags "LED SMD 0603 Green")
		(property "Reference" "D8"
			(at -0.7 1.65 90)
			(layer "B.SilkS")
			(effects
				(font
					(size 0.7 0.7)
					(thickness 0.15)
				)
				(justify right bottom mirror)
			)
		)
		(property "Value" "LED_G_0603_LTST-C190GKT"
			(at -0.001 -1.599 90)
			(layer "B.Fab")
			(effects
				(font
					(size 0.7 0.7)
					(thickness 0.15)
				)
				(justify right bottom mirror)
			)
		)
		(property "Footprint" "antmicro-footprints:LED_0603_1608Metric_G"
			(at 0 0 90)
			(layer "F.Fab")
			(hide yes)
			(effects
				(font
					(size 1.27 1.27)
					(thickness 0.15)
				)
			)
		)
		(property "Datasheet" "https://media.digikey.com/pdf/Data%20Sheets/Lite-On%20PDFs/LTST-C190GKT.pdf"
			(at 0 0 90)
			(layer "F.Fab")
			(hide yes)
			(effects
				(font
					(size 1.27 1.27)
					(thickness 0.15)
				)
			)
		)
		(property "Author" "Antmicro"
			(at 187.75 66.65 0)
			(layer "B.Fab")
			(hide yes)
			(effects
				(font
					(size 1 1)
					(thickness 0.15)
				)
				(justify mirror)
			)
		)
		(property "Color" "Green"
			(at 187.75 66.65 0)
			(layer "B.Fab")
			(hide yes)
			(effects
				(font
					(size 1 1)
					(thickness 0.15)
				)
				(justify mirror)
			)
		)
		(property "License" "Apache-2.0"
			(at 187.75 66.65 0)
			(layer "B.Fab")
			(hide yes)
			(effects
				(font
					(size 1 1)
					(thickness 0.15)
				)
				(justify mirror)
			)
		)
		(property "MPN" "LTST-C190GKT"
			(at 187.75 66.65 0)
			(layer "B.Fab")
			(hide yes)
			(effects
				(font
					(size 1 1)
					(thickness 0.15)
				)
				(justify mirror)
			)
		)
		(property "Manufacturer" "Lite-On"
			(at 187.75 66.65 0)
			(layer "B.Fab")
			(hide yes)
			(effects
				(font
					(size 1 1)
					(thickness 0.15)
				)
				(justify mirror)
			)
		)
		(sheetname "USB Debug, DP")
		(sheetfile "usb.kicad_sch")
		(attr smd)
		(fp_line
			(start -0.22 -0.35)
			(end 0.22 -0.35)
			(stroke
				(width 0.15)
				(type solid)
			)
			(layer "B.SilkS")
		)
		(fp_line
			(start -1.18 -0.321)
			(end -1.18 0.319)
			(stroke
				(width 0.15)
				(type solid)
			)
			(layer "B.SilkS")
		)
		(fp_line
			(start -0.094672 -0.001008)
			(end 0.105328 -0.201008)
			(stroke
				(width 0.1)
				(type solid)
			)
			(layer "B.SilkS")
		)
		(fp_line
			(start -0.24 -0.001008)
			(end -0.094672 -0.001008)
			(stroke
				(width 0.1)
				(type solid)
			)
			(layer "B.SilkS")
		)
		(fp_line
			(start 0.24 -0.001)
			(end 0.105328 -0.001008)
			(stroke
				(width 0.1)
				(type solid)
			)
			(layer "B.SilkS")
		)
		(fp_line
			(start 0.105328 0.198992)
			(end 0.105328 -0.201008)
			(stroke
				(width 0.1)
				(type solid)
			)
			(layer "B.SilkS")
		)
		(fp_line
			(start 0.105328 0.198992)
			(end -0.094672 -0.001008)
			(stroke
				(width 0.1)
				(type solid)
			)
			(layer "B.SilkS")
		)
		(fp_line
			(start -0.094672 0.198992)
			(end -0.094672 -0.201008)
			(stroke
				(width 0.1)
				(type solid)
			)
			(layer "B.SilkS")
		)
		(fp_line
			(start -0.22 0.35)
			(end 0.22 0.35)
			(stroke
				(width 0.15)
				(type solid)
			)
			(layer "B.SilkS")
		)
		(fp_rect
			(start 1.25 -0.65)
			(end -1.25 0.65)
			(stroke
				(width 0.05)
				(type solid)
			)
			(fill none)
			(layer "B.CrtYd")
		)
		(fp_line
			(start 0.201 -0.2)
			(end -0.101 0)
			(stroke
				(width 0.15)
				(type solid)
			)
			(layer "B.Fab")
		)
		(fp_line
			(start -0.199 -0.1)
			(end -0.199 -0.2)
			(stroke
				(width 0.15)
				(type solid)
			)
			(layer "B.Fab")
		)
		(fp_line
			(start -0.199 -0.1)
			(end -0.199 0.202)
			(stroke
				(width 0.15)
				(type solid)
			)
			(layer "B.Fab")
		)
		(fp_line
			(start 0.201 0)
			(end 0.201 -0.2)
			(stroke
				(width 0.15)
				(type solid)
			)
			(layer "B.Fab")
		)
		(fp_line
			(start 0.201 0)
			(end 0.599 0)
			(stroke
				(width 0.15)
				(type solid)
			)
			(layer "B.Fab")
		)
		(fp_line
			(start -0.101 0)
			(end 0.201 0.202)
			(stroke
				(width 0.15)
				(type solid)
			)
			(layer "B.Fab")
		)
		(fp_line
			(start -0.597 0)
			(end -0.199 0)
			(stroke
				(width 0.15)
				(type solid)
			)
			(layer "B.Fab")
		)
		(fp_line
			(start 0.201 0.202)
			(end 0.201 0)
			(stroke
				(width 0.15)
				(type solid)
			)
			(layer "B.Fab")
		)
		(fp_rect
			(start 0.848 -0.4)
			(end -0.85 0.402)
			(stroke
				(width 0.15)
				(type solid)
			)
			(fill none)
			(layer "B.Fab")
		)
		(fp_text user "License: Apache-2.0"
			(at -1.4224 -3.599 90)
			(layer "B.Fab")
			(hide yes)
			(effects
				(font
					(size 0.7 0.7)
					(thickness 0.15)
				)
				(justify right bottom mirror)
			)
		)
		(fp_text user "${REFERENCE}"
			(at -1.4224 -5.999 90)
			(layer "B.Fab")
			(hide yes)
			(effects
				(font
					(size 0.7 0.7)
					(thickness 0.15)
				)
				(justify right bottom mirror)
			)
		)
		(fp_text user "Author: Antmicro"
			(at -1.4224 -4.799 90)
			(layer "B.Fab")
			(hide yes)
			(effects
				(font
					(size 0.7 0.7)
					(thickness 0.15)
				)
				(justify right bottom mirror)
			)
		)
		(pad "1" smd roundrect
			(at -0.7 0 270)
			(size 0.8 1)
			(layers "B.Cu" "B.Paste" "B.Mask")
			(roundrect_rratio 0.2)
			(net 1 "GND")
			(pinfunction "C")
			(pintype "passive")
		)
		(pad "2" smd roundrect
			(at 0.7 0 270)
			(size 0.8 1)
			(layers "B.Cu" "B.Paste" "B.Mask")
			(roundrect_rratio 0.2)
			(net 146 "Net-(D8-A)")
			(pinfunction "A")
			(pintype "passive")
		)
	)
	(footprint "antmicro-footprints:R_0402_1005Metric"
		(layer "B.Cu")
		(at 57.55 112.45 180)
		(descr "Resistor SMD 0402")
		(tags "resistor SMD 0402")
		(property "Reference" "R57"
			(at -3.02 -0.34 0)
			(layer "B.SilkS")
			(effects
				(font
					(size 0.7 0.7)
					(thickness 0.15)
				)
				(justify left bottom mirror)
			)
		)
		(property "Value" "R_0R_0402"
			(at 0 -1.4 0)
			(layer "B.Fab")
			(effects
				(font
					(size 0.7 0.7)
					(thickness 0.15)
				)
				(justify left bottom mirror)
			)
		)
		(property "Footprint" "antmicro-footprints:R_0402_1005Metric"
			(at 0 0 180)
			(layer "F.Fab")
			(hide yes)
			(effects
				(font
					(size 1.27 1.27)
					(thickness 0.15)
				)
			)
		)
		(property "Datasheet" "https://industrial.panasonic.com/cdbs/www-data/pdf/RDA0000/AOA0000C301.pdf"
			(at 0 0 180)
			(layer "F.Fab")
			(hide yes)
			(effects
				(font
					(size 1.27 1.27)
					(thickness 0.15)
				)
			)
		)
		(property "Author" "Antmicro"
			(at 115.1 224.9 0)
			(layer "B.Fab")
			(hide yes)
			(effects
				(font
					(size 1 1)
					(thickness 0.15)
				)
				(justify mirror)
			)
		)
		(property "Current" "1A"
			(at 115.1 224.9 0)
			(layer "B.Fab")
			(hide yes)
			(effects
				(font
					(size 1 1)
					(thickness 0.15)
				)
				(justify mirror)
			)
		)
		(property "License" "Apache-2.0"
			(at 115.1 224.9 0)
			(layer "B.Fab")
			(hide yes)
			(effects
				(font
					(size 1 1)
					(thickness 0.15)
				)
				(justify mirror)
			)
		)
		(property "MPN" "ERJ2GE0R00X"
			(at 115.1 224.9 0)
			(layer "B.Fab")
			(hide yes)
			(effects
				(font
					(size 1 1)
					(thickness 0.15)
				)
				(justify mirror)
			)
		)
		(property "Manufacturer" "Panasonic"
			(at 115.1 224.9 0)
			(layer "B.Fab")
			(hide yes)
			(effects
				(font
					(size 1 1)
					(thickness 0.15)
				)
				(justify mirror)
			)
		)
		(property "Tolerance" ""
			(at 115.1 224.9 0)
			(layer "B.Fab")
			(hide yes)
			(effects
				(font
					(size 1 1)
					(thickness 0.15)
				)
				(justify mirror)
			)
		)
		(property "Val" "0R"
			(at 115.1 224.9 0)
			(layer "B.Fab")
			(hide yes)
			(effects
				(font
					(size 1 1)
					(thickness 0.15)
				)
				(justify mirror)
			)
		)
		(sheetname "USB Debug, DP")
		(sheetfile "usb.kicad_sch")
		(attr smd)
		(fp_rect
			(start -0.925 0.47)
			(end 0.925 -0.47)
			(stroke
				(width 0.05)
				(type default)
			)
			(fill none)
			(layer "B.CrtYd")
		)
		(fp_rect
			(start -0.5 0.25)
			(end 0.5 -0.25)
			(stroke
				(width 0.15)
				(type solid)
			)
			(fill none)
			(layer "B.Fab")
		)
		(fp_text user "${REFERENCE}"
			(at -0.95 -3.168 0)
			(layer "B.Fab")
			(hide yes)
			(effects
				(font
					(size 0.7 0.7)
					(thickness 0.15)
				)
				(justify left bottom mirror)
			)
		)
		(fp_text user "License: Apache-2.0"
			(at -0.95 -5.169 0)
			(layer "B.Fab")
			(hide yes)
			(effects
				(font
					(size 0.7 0.7)
					(thickness 0.15)
				)
				(justify left bottom mirror)
			)
		)
		(fp_text user "Author: Antmicro"
			(at -0.95 -4.169 0)
			(layer "B.Fab")
			(hide yes)
			(effects
				(font
					(size 0.7 0.7)
					(thickness 0.15)
				)
				(justify left bottom mirror)
			)
		)
		(pad "1" smd roundrect
			(at -0.48 0 180)
			(size 0.59 0.64)
			(layers "B.Cu" "B.Paste" "B.Mask")
			(roundrect_rratio 0.25)
			(net 475 "DEBUG_TXD")
			(pintype "passive")
		)
		(pad "2" smd roundrect
			(at 0.48 0 180)
			(size 0.59 0.64)
			(layers "B.Cu" "B.Paste" "B.Mask")
			(roundrect_rratio 0.25)
			(net 647 "Net-(U5-RXD)")
			(pintype "passive")
		)
	)
	(footprint "antmicro-footprints:R_0402_1005Metric"
		(layer "B.Cu")
		(at 108.9 104.4)
		(descr "Resistor SMD 0402")
		(tags "resistor SMD 0402")
		(property "Reference" "R266"
			(at -0.95 0.31 180)
			(layer "B.SilkS")
			(effects
				(font
					(size 0.7 0.7)
					(thickness 0.15)
				)
				(justify left bottom mirror)
			)
		)
		(property "Value" "R_200k_0402"
			(at 0 -1.4 180)
			(layer "B.Fab")
			(effects
				(font
					(size 0.7 0.7)
					(thickness 0.15)
				)
				(justify left bottom mirror)
			)
		)
		(property "Footprint" "antmicro-footprints:R_0402_1005Metric"
			(at 0 0 0)
			(layer "F.Fab")
			(hide yes)
			(effects
				(font
					(size 1.27 1.27)
					(thickness 0.15)
				)
			)
		)
		(property "Datasheet" "https://www.bourns.com/docs/product-datasheets/cr.pdf"
			(at 0 0 0)
			(layer "F.Fab")
			(hide yes)
			(effects
				(font
					(size 1.27 1.27)
					(thickness 0.15)
				)
			)
		)
		(property "Author" "Antmicro"
			(at 0 0 0)
			(layer "B.Fab")
			(hide yes)
			(effects
				(font
					(size 1 1)
					(thickness 0.15)
				)
				(justify mirror)
			)
		)
		(property "License" "Apache-2.0"
			(at 0 0 0)
			(layer "B.Fab")
			(hide yes)
			(effects
				(font
					(size 1 1)
					(thickness 0.15)
				)
				(justify mirror)
			)
		)
		(property "MPN" "CR0402-FX-2003GLF"
			(at 0 0 0)
			(layer "B.Fab")
			(hide yes)
			(effects
				(font
					(size 1 1)
					(thickness 0.15)
				)
				(justify mirror)
			)
		)
		(property "Manufacturer" "Bourns"
			(at 0 0 0)
			(layer "B.Fab")
			(hide yes)
			(effects
				(font
					(size 1 1)
					(thickness 0.15)
				)
				(justify mirror)
			)
		)
		(property "Tolerance" "1%"
			(at 0 0 0)
			(layer "B.Fab")
			(hide yes)
			(effects
				(font
					(size 1 1)
					(thickness 0.15)
				)
				(justify mirror)
			)
		)
		(property "Val" "200k"
			(at 0 0 0)
			(layer "B.Fab")
			(hide yes)
			(effects
				(font
					(size 1 1)
					(thickness 0.15)
				)
				(justify mirror)
			)
		)
		(sheetname "USB3")
		(sheetfile "usb3.kicad_sch")
		(attr smd)
		(fp_rect
			(start -0.925 0.47)
			(end 0.925 -0.47)
			(stroke
				(width 0.05)
				(type default)
			)
			(fill none)
			(layer "B.CrtYd")
		)
		(fp_rect
			(start -0.5 0.25)
			(end 0.5 -0.25)
			(stroke
				(width 0.15)
				(type solid)
			)
			(fill none)
			(layer "B.Fab")
		)
		(fp_text user "${REFERENCE}"
			(at -0.95 -3.168 180)
			(layer "B.Fab")
			(hide yes)
			(effects
				(font
					(size 0.7 0.7)
					(thickness 0.15)
				)
				(justify left bottom mirror)
			)
		)
		(fp_text user "License: Apache-2.0"
			(at -0.95 -5.169 180)
			(layer "B.Fab")
			(hide yes)
			(effects
				(font
					(size 0.7 0.7)
					(thickness 0.15)
				)
				(justify left bottom mirror)
			)
		)
		(fp_text user "Author: Antmicro"
			(at -0.95 -4.169 180)
			(layer "B.Fab")
			(hide yes)
			(effects
				(font
					(size 0.7 0.7)
					(thickness 0.15)
				)
				(justify left bottom mirror)
			)
		)
		(pad "1" smd roundrect
			(at -0.48 0)
			(size 0.59 0.64)
			(layers "B.Cu" "B.Paste" "B.Mask")
			(roundrect_rratio 0.25)
			(net 87 "+3V3")
			(pintype "passive")
		)
		(pad "2" smd roundrect
			(at 0.48 0)
			(size 0.59 0.64)
			(layers "B.Cu" "B.Paste" "B.Mask")
			(roundrect_rratio 0.25)
			(net 363 "/USB3/USBC1_ISC_SCL")
			(pintype "passive")
		)
	)
	(footprint "antmicro-footprints:C_0402_1005Metric"
		(layer "B.Cu")
		(at 65.55 108.1875 90)
		(descr "Capacitor SMD 0402")
		(tags "capacitor SMD 0402")
		(property "Reference" "C30"
			(at 1.1175 -0.35 -90)
			(layer "B.SilkS")
			(effects
				(font
					(size 0.7 0.7)
					(thickness 0.15)
				)
				(justify left bottom mirror)
			)
		)
		(property "Value" "C_10u_0402"
			(at -1.022927 -2.155213 -90)
			(layer "B.Fab")
			(effects
				(font
					(size 0.7 0.7)
					(thickness 0.15)
				)
				(justify left bottom mirror)
			)
		)
		(property "Footprint" "antmicro-footprints:C_0402_1005Metric"
			(at 0 0 90)
			(layer "F.Fab")
			(hide yes)
			(effects
				(font
					(size 1.27 1.27)
					(thickness 0.15)
				)
			)
		)
		(property "Datasheet" "https://www.yageo.com/en/Chart/Download/pdf/CC0402MRX5R5BB106"
			(at 0 0 90)
			(layer "F.Fab")
			(hide yes)
			(effects
				(font
					(size 1.27 1.27)
					(thickness 0.15)
				)
			)
		)
		(property "Author" "Antmicro"
			(at 173.7375 42.6375 0)
			(layer "B.Fab")
			(hide yes)
			(effects
				(font
					(size 1 1)
					(thickness 0.15)
				)
				(justify mirror)
			)
		)
		(property "Dielectric" ""
			(at 173.7375 42.6375 0)
			(layer "B.Fab")
			(hide yes)
			(effects
				(font
					(size 1 1)
					(thickness 0.15)
				)
				(justify mirror)
			)
		)
		(property "License" "Apache-2.0"
			(at 173.7375 42.6375 0)
			(layer "B.Fab")
			(hide yes)
			(effects
				(font
					(size 1 1)
					(thickness 0.15)
				)
				(justify mirror)
			)
		)
		(property "MPN" "CC0402MRX5R5BB106"
			(at 173.7375 42.6375 0)
			(layer "B.Fab")
			(hide yes)
			(effects
				(font
					(size 1 1)
					(thickness 0.15)
				)
				(justify mirror)
			)
		)
		(property "Manufacturer" "YAGEO"
			(at 173.7375 42.6375 0)
			(layer "B.Fab")
			(hide yes)
			(effects
				(font
					(size 1 1)
					(thickness 0.15)
				)
				(justify mirror)
			)
		)
		(property "Val" "10u"
			(at 173.7375 42.6375 0)
			(layer "B.Fab")
			(hide yes)
			(effects
				(font
					(size 1 1)
					(thickness 0.15)
				)
				(justify mirror)
			)
		)
		(property "Voltage" ""
			(at 173.7375 42.6375 0)
			(layer "B.Fab")
			(hide yes)
			(effects
				(font
					(size 1 1)
					(thickness 0.15)
				)
				(justify mirror)
			)
		)
		(sheetname "USB Debug, DP")
		(sheetfile "usb.kicad_sch")
		(attr smd)
		(fp_rect
			(start -0.925 0.47)
			(end 0.925 -0.47)
			(stroke
				(width 0.05)
				(type default)
			)
			(fill none)
			(layer "B.CrtYd")
		)
		(fp_line
			(start 0.504 -0.248)
			(end 0.504 0.25)
			(stroke
				(width 0.15)
				(type solid)
			)
			(layer "B.Fab")
		)
		(fp_line
			(start -0.494 -0.248)
			(end 0.504 -0.248)
			(stroke
				(width 0.15)
				(type solid)
			)
			(layer "B.Fab")
		)
		(fp_line
			(start 0.504 0.25)
			(end -0.494 0.25)
			(stroke
				(width 0.15)
				(type solid)
			)
			(layer "B.Fab")
		)
		(fp_line
			(start -0.494 0.25)
			(end -0.494 -0.248)
			(stroke
				(width 0.15)
				(type solid)
			)
			(layer "B.Fab")
		)
		(fp_text user "License: Apache-2.0"
			(at -0.939 -5.799 -90)
			(layer "B.Fab")
			(hide yes)
			(effects
				(font
					(size 0.7 0.7)
					(thickness 0.15)
				)
				(justify left bottom mirror)
			)
		)
		(fp_text user "Author: Antmicro"
			(at -0.939 -3.399 -90)
			(layer "B.Fab")
			(hide yes)
			(effects
				(font
					(size 0.7 0.7)
					(thickness 0.15)
				)
				(justify left bottom mirror)
			)
		)
		(fp_text user "${REFERENCE}"
			(at -0.939 -4.599 -90)
			(layer "B.Fab")
			(hide yes)
			(effects
				(font
					(size 0.7 0.7)
					(thickness 0.15)
				)
				(justify left bottom mirror)
			)
		)
		(pad "1" smd roundrect
			(at -0.48 0 90)
			(size 0.59 0.64)
			(layers "B.Cu" "B.Paste" "B.Mask")
			(roundrect_rratio 0.25)
			(net 1 "GND")
			(pintype "passive")
		)
		(pad "2" smd roundrect
			(at 0.48 0 90)
			(size 0.59 0.64)
			(layers "B.Cu" "B.Paste" "B.Mask")
			(roundrect_rratio 0.25)
			(net 134 "/USB Debug, DP/PDC_LDO_3V3")
			(pintype "passive")
		)
	)
	(footprint "antmicro-footprints:Oscillator_SMD_ECS_2520MV_2.5x2mm"
		(layer "B.Cu")
		(at 112.014 83.058 90)
		(descr "Miniature Crystal Clock Oscillator ECS 2520MV series")
		(tags "Crystal Clock Oscillator ECS 2520MV SMD")
		(property "Reference" "Y1"
			(at 0.308 -1.464 0)
			(layer "B.SilkS")
			(effects
				(font
					(size 0.7 0.7)
					(thickness 0.15)
				)
				(justify left bottom mirror)
			)
		)
		(property "Value" "Oscillator_32.768kHz_ECS_2520MV"
			(at 0 -2.499 -90)
			(layer "B.Fab")
			(effects
				(font
					(size 0.7 0.7)
					(thickness 0.15)
				)
				(justify left bottom mirror)
			)
		)
		(property "Footprint" "antmicro-footprints:Oscillator_SMD_ECS_2520MV_2.5x2mm"
			(at 0 0 90)
			(layer "F.Fab")
			(hide yes)
			(effects
				(font
					(size 1.27 1.27)
					(thickness 0.15)
				)
			)
		)
		(property "Datasheet" "https://ecsxtal.com/store/pdf/ECS-327MVATX.pdf"
			(at 0 0 90)
			(layer "F.Fab")
			(hide yes)
			(effects
				(font
					(size 1.27 1.27)
					(thickness 0.15)
				)
			)
		)
		(property "Author" "Antmicro"
			(at 195.072 -28.956 0)
			(layer "B.Fab")
			(hide yes)
			(effects
				(font
					(size 1 1)
					(thickness 0.15)
				)
				(justify mirror)
			)
		)
		(property "License" "Apache-2.0"
			(at 195.072 -28.956 0)
			(layer "B.Fab")
			(hide yes)
			(effects
				(font
					(size 1 1)
					(thickness 0.15)
				)
				(justify mirror)
			)
		)
		(property "MPN" "ECS-327MVATX-2-CN-TR3"
			(at 195.072 -28.956 0)
			(layer "B.Fab")
			(hide yes)
			(effects
				(font
					(size 1 1)
					(thickness 0.15)
				)
				(justify mirror)
			)
		)
		(property "Manufacturer" "ECS Inc. International"
			(at 195.072 -28.956 0)
			(layer "B.Fab")
			(hide yes)
			(effects
				(font
					(size 1 1)
					(thickness 0.15)
				)
				(justify mirror)
			)
		)
		(property "Val" "32.768 kHz"
			(at 195.072 -28.956 0)
			(layer "B.Fab")
			(hide yes)
			(effects
				(font
					(size 1 1)
					(thickness 0.15)
				)
				(justify mirror)
			)
		)
		(sheetname "M.2")
		(sheetfile "m-2.kicad_sch")
		(attr smd)
		(fp_line
			(start 0.17 -1.36)
			(end -0.172 -1.36)
			(stroke
				(width 0.15)
				(type solid)
			)
			(layer "B.SilkS")
		)
		(fp_line
			(start 1.11 0.32)
			(end 1.11 -0.32)
			(stroke
				(width 0.15)
				(type solid)
			)
			(layer "B.SilkS")
		)
		(fp_line
			(start -1.111 0.32)
			(end -1.111 -0.32)
			(stroke
				(width 0.15)
				(type solid)
			)
			(layer "B.SilkS")
		)
		(fp_line
			(start 0.17 1.361)
			(end -0.16 1.361)
			(stroke
				(width 0.15)
				(type solid)
			)
			(layer "B.SilkS")
		)
		(fp_circle
			(center -1.1 1.5)
			(end -1.049 1.5)
			(stroke
				(width 0.15)
				(type solid)
			)
			(fill solid)
			(layer "B.SilkS")
		)
		(fp_rect
			(start -1.25 1.5)
			(end 1.25 -1.5)
			(stroke
				(width 0.05)
				(type solid)
			)
			(fill none)
			(layer "B.CrtYd")
		)
		(fp_line
			(start -0.5 1.25)
			(end -1 0.75)
			(stroke
				(width 0.15)
				(type solid)
			)
			(layer "B.Fab")
		)
		(fp_rect
			(start 1 -1.249)
			(end -1 1.25)
			(stroke
				(width 0.15)
				(type solid)
			)
			(fill none)
			(layer "B.Fab")
		)
		(fp_text user "${REFERENCE}"
			(at -1.25 -3.9 -90)
			(layer "B.Fab")
			(hide yes)
			(effects
				(font
					(size 0.7 0.7)
					(thickness 0.15)
				)
				(justify left bottom mirror)
			)
		)
		(fp_text user "Author: Antmicro"
			(at -1.25 -5.102 -90)
			(layer "B.Fab")
			(hide yes)
			(effects
				(font
					(size 0.7 0.7)
					(thickness 0.15)
				)
				(justify left bottom mirror)
			)
		)
		(fp_text user "License: Apache-2.0"
			(at -1.25 -6.302 -90)
			(layer "B.Fab")
			(hide yes)
			(effects
				(font
					(size 0.7 0.7)
					(thickness 0.15)
				)
				(justify left bottom mirror)
			)
		)
		(pad "1" smd roundrect
			(at -0.725 0.927 90)
			(size 0.8 0.9)
			(layers "B.Cu" "B.Paste" "B.Mask")
			(roundrect_rratio 0.25)
			(net 87 "+3V3")
			(pinfunction "EN")
			(pintype "input")
		)
		(pad "2" smd roundrect
			(at -0.725 -0.925 90)
			(size 0.8 0.9)
			(layers "B.Cu" "B.Paste" "B.Mask")
			(roundrect_rratio 0.25)
			(net 1 "GND")
			(pinfunction "GND")
			(pintype "power_in")
		)
		(pad "3" smd roundrect
			(at 0.723 -0.925 90)
			(size 0.8 0.9)
			(layers "B.Cu" "B.Paste" "B.Mask")
			(roundrect_rratio 0.25)
			(net 456 "/M.2/32.7KHZ_OUT")
			(pinfunction "OUT")
			(pintype "output")
		)
		(pad "4" smd roundrect
			(at 0.723 0.927 90)
			(size 0.8 0.9)
			(layers "B.Cu" "B.Paste" "B.Mask")
			(roundrect_rratio 0.25)
			(net 87 "+3V3")
			(pinfunction "VDD")
			(pintype "power_in")
		)
	)
	(footprint "antmicro-footprints:R_0402_1005Metric"
		(layer "B.Cu")
		(at 108.15175 95.525 90)
		(descr "Resistor SMD 0402")
		(tags "resistor SMD 0402")
		(property "Reference" "R179"
			(at 1.425 1.29825 -90)
			(layer "B.SilkS")
			(effects
				(font
					(size 0.7 0.7)
					(thickness 0.15)
				)
				(justify left bottom mirror)
			)
		)
		(property "Value" "R_0R_0402"
			(at 0 -1.4 -90)
			(layer "B.Fab")
			(effects
				(font
					(size 0.7 0.7)
					(thickness 0.15)
				)
				(justify left bottom mirror)
			)
		)
		(property "Footprint" "antmicro-footprints:R_0402_1005Metric"
			(at 0 0 90)
			(layer "F.Fab")
			(hide yes)
			(effects
				(font
					(size 1.27 1.27)
					(thickness 0.15)
				)
			)
		)
		(property "Datasheet" "https://industrial.panasonic.com/cdbs/www-data/pdf/RDA0000/AOA0000C301.pdf"
			(at 0 0 90)
			(layer "F.Fab")
			(hide yes)
			(effects
				(font
					(size 1.27 1.27)
					(thickness 0.15)
				)
			)
		)
		(property "Author" "Antmicro"
			(at 203.67675 -12.62675 0)
			(layer "B.Fab")
			(hide yes)
			(effects
				(font
					(size 1 1)
					(thickness 0.15)
				)
				(justify mirror)
			)
		)
		(property "Current" "1A"
			(at 203.67675 -12.62675 0)
			(layer "B.Fab")
			(hide yes)
			(effects
				(font
					(size 1 1)
					(thickness 0.15)
				)
				(justify mirror)
			)
		)
		(property "License" "Apache-2.0"
			(at 203.67675 -12.62675 0)
			(layer "B.Fab")
			(hide yes)
			(effects
				(font
					(size 1 1)
					(thickness 0.15)
				)
				(justify mirror)
			)
		)
		(property "MPN" "ERJ2GE0R00X"
			(at 203.67675 -12.62675 0)
			(layer "B.Fab")
			(hide yes)
			(effects
				(font
					(size 1 1)
					(thickness 0.15)
				)
				(justify mirror)
			)
		)
		(property "Manufacturer" "Panasonic"
			(at 203.67675 -12.62675 0)
			(layer "B.Fab")
			(hide yes)
			(effects
				(font
					(size 1 1)
					(thickness 0.15)
				)
				(justify mirror)
			)
		)
		(property "Tolerance" ""
			(at 203.67675 -12.62675 0)
			(layer "B.Fab")
			(hide yes)
			(effects
				(font
					(size 1 1)
					(thickness 0.15)
				)
				(justify mirror)
			)
		)
		(property "Val" "0R"
			(at 203.67675 -12.62675 0)
			(layer "B.Fab")
			(hide yes)
			(effects
				(font
					(size 1 1)
					(thickness 0.15)
				)
				(justify mirror)
			)
		)
		(sheetname "CSI")
		(sheetfile "csi.kicad_sch")
		(attr smd exclude_from_pos_files exclude_from_bom dnp)
		(fp_rect
			(start -0.925 0.47)
			(end 0.925 -0.47)
			(stroke
				(width 0.05)
				(type default)
			)
			(fill none)
			(layer "B.CrtYd")
		)
		(fp_rect
			(start -0.5 0.25)
			(end 0.5 -0.25)
			(stroke
				(width 0.15)
				(type solid)
			)
			(fill none)
			(layer "B.Fab")
		)
		(fp_text user "${REFERENCE}"
			(at -0.95 -3.168 -90)
			(layer "B.Fab")
			(hide yes)
			(effects
				(font
					(size 0.7 0.7)
					(thickness 0.15)
				)
				(justify left bottom mirror)
			)
		)
		(fp_text user "Author: Antmicro"
			(at -0.95 -4.169 -90)
			(layer "B.Fab")
			(hide yes)
			(effects
				(font
					(size 0.7 0.7)
					(thickness 0.15)
				)
				(justify left bottom mirror)
			)
		)
		(fp_text user "License: Apache-2.0"
			(at -0.95 -5.169 -90)
			(layer "B.Fab")
			(hide yes)
			(effects
				(font
					(size 0.7 0.7)
					(thickness 0.15)
				)
				(justify left bottom mirror)
			)
		)
		(pad "1" smd roundrect
			(at -0.48 0 90)
			(size 0.59 0.64)
			(layers "B.Cu" "B.Paste" "B.Mask")
			(roundrect_rratio 0.25)
			(net 636 "/CSI/CSIB_I2C_VCC")
			(pintype "passive")
		)
		(pad "2" smd roundrect
			(at 0.48 0 90)
			(size 0.59 0.64)
			(layers "B.Cu" "B.Paste" "B.Mask")
			(roundrect_rratio 0.25)
			(net 112 "+1V8")
			(pintype "passive")
		)
	)
	(footprint "antmicro-footprints:C_0402_1005Metric"
		(layer "B.Cu")
		(at 62.03 84.36 90)
		(descr "Capacitor SMD 0402")
		(tags "capacitor SMD 0402")
		(property "Reference" "C142"
			(at -3.76 0.48 90)
			(layer "B.SilkS")
			(effects
				(font
					(size 0.7 0.7)
					(thickness 0.15)
				)
				(justify right bottom mirror)
			)
		)
		(property "Value" "C_1u_0402"
			(at 0 -1.4 90)
			(layer "B.Fab")
			(effects
				(font
					(size 0.7 0.7)
					(thickness 0.15)
				)
				(justify right bottom mirror)
			)
		)
		(property "Footprint" "antmicro-footprints:C_0402_1005Metric"
			(at 0 0 90)
			(layer "F.Fab")
			(hide yes)
			(effects
				(font
					(size 1.27 1.27)
					(thickness 0.15)
				)
			)
		)
		(property "Datasheet" "https://product.tdk.com/en/search/capacitor/ceramic/mlcc/info?part_no=C1005X6S1A105K050BC"
			(at 0 0 90)
			(layer "F.Fab")
			(hide yes)
			(effects
				(font
					(size 1.27 1.27)
					(thickness 0.15)
				)
			)
		)
		(property "Author" "Antmicro"
			(at 146.39 22.33 0)
			(layer "B.Fab")
			(hide yes)
			(effects
				(font
					(size 1 1)
					(thickness 0.15)
				)
				(justify mirror)
			)
		)
		(property "Dielectric" ""
			(at 146.39 22.33 0)
			(layer "B.Fab")
			(hide yes)
			(effects
				(font
					(size 1 1)
					(thickness 0.15)
				)
				(justify mirror)
			)
		)
		(property "License" "Apache-2.0"
			(at 146.39 22.33 0)
			(layer "B.Fab")
			(hide yes)
			(effects
				(font
					(size 1 1)
					(thickness 0.15)
				)
				(justify mirror)
			)
		)
		(property "MPN" "C1005X6S1A105K050BC"
			(at 146.39 22.33 0)
			(layer "B.Fab")
			(hide yes)
			(effects
				(font
					(size 1 1)
					(thickness 0.15)
				)
				(justify mirror)
			)
		)
		(property "Manufacturer" "TDK"
			(at 146.39 22.33 0)
			(layer "B.Fab")
			(hide yes)
			(effects
				(font
					(size 1 1)
					(thickness 0.15)
				)
				(justify mirror)
			)
		)
		(property "Val" "1u"
			(at 146.39 22.33 0)
			(layer "B.Fab")
			(hide yes)
			(effects
				(font
					(size 1 1)
					(thickness 0.15)
				)
				(justify mirror)
			)
		)
		(property "Voltage" ""
			(at 146.39 22.33 0)
			(layer "B.Fab")
			(hide yes)
			(effects
				(font
					(size 1 1)
					(thickness 0.15)
				)
				(justify mirror)
			)
		)
		(sheetname "Supply")
		(sheetfile "supply.kicad_sch")
		(attr smd)
		(fp_rect
			(start -0.925 0.47)
			(end 0.925 -0.47)
			(stroke
				(width 0.05)
				(type default)
			)
			(fill none)
			(layer "B.CrtYd")
		)
		(fp_line
			(start 0.504 -0.248)
			(end 0.504 0.25)
			(stroke
				(width 0.15)
				(type solid)
			)
			(layer "B.Fab")
		)
		(fp_line
			(start -0.494 -0.248)
			(end 0.504 -0.248)
			(stroke
				(width 0.15)
				(type solid)
			)
			(layer "B.Fab")
		)
		(fp_line
			(start 0.504 0.25)
			(end -0.494 0.25)
			(stroke
				(width 0.15)
				(type solid)
			)
			(layer "B.Fab")
		)
		(fp_line
			(start -0.494 0.25)
			(end -0.494 -0.248)
			(stroke
				(width 0.15)
				(type solid)
			)
			(layer "B.Fab")
		)
		(fp_text user "Author: Antmicro"
			(at -0.932 -4.17 90)
			(layer "B.Fab")
			(hide yes)
			(effects
				(font
					(size 0.7 0.7)
					(thickness 0.15)
				)
				(justify right bottom mirror)
			)
		)
		(fp_text user "${REFERENCE}"
			(at -0.932 -3.168 90)
			(layer "B.Fab")
			(hide yes)
			(effects
				(font
					(size 0.7 0.7)
					(thickness 0.15)
				)
				(justify right bottom mirror)
			)
		)
		(fp_text user "License: Apache-2.0"
			(at -0.932 -5.17 90)
			(layer "B.Fab")
			(hide yes)
			(effects
				(font
					(size 0.7 0.7)
					(thickness 0.15)
				)
				(justify right bottom mirror)
			)
		)
		(pad "1" smd roundrect
			(at -0.48 0 90)
			(size 0.59 0.64)
			(layers "B.Cu" "B.Paste" "B.Mask")
			(roundrect_rratio 0.25)
			(net 1 "GND")
			(pintype "passive")
		)
		(pad "2" smd roundrect
			(at 0.48 0 90)
			(size 0.59 0.64)
			(layers "B.Cu" "B.Paste" "B.Mask")
			(roundrect_rratio 0.25)
			(net 139 "/Supply/1V8_LDO")
			(pintype "passive")
		)
	)
	(footprint "antmicro-footprints:R_0402_1005Metric"
		(layer "B.Cu")
		(at 112.4 103.1)
		(descr "Resistor SMD 0402")
		(tags "resistor SMD 0402")
		(property "Reference" "R135"
			(at 3.68 0.35 180)
			(layer "B.SilkS")
			(effects
				(font
					(size 0.7 0.7)
					(thickness 0.15)
				)
				(justify left bottom mirror)
			)
		)
		(property "Value" "R_10k_0402"
			(at 0 -1.4 180)
			(layer "B.Fab")
			(effects
				(font
					(size 0.7 0.7)
					(thickness 0.15)
				)
				(justify left bottom mirror)
			)
		)
		(property "Footprint" "antmicro-footprints:R_0402_1005Metric"
			(at 0 0 0)
			(layer "F.Fab")
			(hide yes)
			(effects
				(font
					(size 1.27 1.27)
					(thickness 0.15)
				)
			)
		)
		(property "Datasheet" "https://www.bourns.com/docs/product-datasheets/cr.pdf"
			(at 0 0 0)
			(layer "F.Fab")
			(hide yes)
			(effects
				(font
					(size 1.27 1.27)
					(thickness 0.15)
				)
			)
		)
		(property "Author" "Antmicro"
			(at 0 0 0)
			(layer "B.Fab")
			(hide yes)
			(effects
				(font
					(size 1 1)
					(thickness 0.15)
				)
				(justify mirror)
			)
		)
		(property "License" "Apache-2.0"
			(at 0 0 0)
			(layer "B.Fab")
			(hide yes)
			(effects
				(font
					(size 1 1)
					(thickness 0.15)
				)
				(justify mirror)
			)
		)
		(property "MPN" "CR0402-FX-1002GLF"
			(at 0 0 0)
			(layer "B.Fab")
			(hide yes)
			(effects
				(font
					(size 1 1)
					(thickness 0.15)
				)
				(justify mirror)
			)
		)
		(property "Manufacturer" "Bourns"
			(at 0 0 0)
			(layer "B.Fab")
			(hide yes)
			(effects
				(font
					(size 1 1)
					(thickness 0.15)
				)
				(justify mirror)
			)
		)
		(property "Tolerance" "1%"
			(at 0 0 0)
			(layer "B.Fab")
			(hide yes)
			(effects
				(font
					(size 1 1)
					(thickness 0.15)
				)
				(justify mirror)
			)
		)
		(property "Val" "10k"
			(at 0 0 0)
			(layer "B.Fab")
			(hide yes)
			(effects
				(font
					(size 1 1)
					(thickness 0.15)
				)
				(justify mirror)
			)
		)
		(sheetname "USB3")
		(sheetfile "usb3.kicad_sch")
		(attr smd)
		(fp_rect
			(start -0.925 0.47)
			(end 0.925 -0.47)
			(stroke
				(width 0.05)
				(type default)
			)
			(fill none)
			(layer "B.CrtYd")
		)
		(fp_rect
			(start -0.5 0.25)
			(end 0.5 -0.25)
			(stroke
				(width 0.15)
				(type solid)
			)
			(fill none)
			(layer "B.Fab")
		)
		(fp_text user "${REFERENCE}"
			(at -0.95 -3.168 180)
			(layer "B.Fab")
			(hide yes)
			(effects
				(font
					(size 0.7 0.7)
					(thickness 0.15)
				)
				(justify left bottom mirror)
			)
		)
		(fp_text user "Author: Antmicro"
			(at -0.95 -4.169 180)
			(layer "B.Fab")
			(hide yes)
			(effects
				(font
					(size 0.7 0.7)
					(thickness 0.15)
				)
				(justify left bottom mirror)
			)
		)
		(fp_text user "License: Apache-2.0"
			(at -0.95 -5.169 180)
			(layer "B.Fab")
			(hide yes)
			(effects
				(font
					(size 0.7 0.7)
					(thickness 0.15)
				)
				(justify left bottom mirror)
			)
		)
		(pad "1" smd roundrect
			(at -0.48 0)
			(size 0.59 0.64)
			(layers "B.Cu" "B.Paste" "B.Mask")
			(roundrect_rratio 0.25)
			(net 391 "/USB3/USBC1_FAULT_N")
			(pintype "passive")
		)
		(pad "2" smd roundrect
			(at 0.48 0)
			(size 0.59 0.64)
			(layers "B.Cu" "B.Paste" "B.Mask")
			(roundrect_rratio 0.25)
			(net 99 "+5V")
			(pintype "passive")
		)
	)
	(footprint "antmicro-footprints:C_0402_1005Metric"
		(layer "B.Cu")
		(at 98.6 75.25)
		(descr "Capacitor SMD 0402")
		(tags "capacitor SMD 0402")
		(property "Reference" "C98"
			(at 0.95 1.36 180)
			(layer "B.SilkS")
			(effects
				(font
					(size 0.7 0.7)
					(thickness 0.15)
				)
				(justify left bottom mirror)
			)
		)
		(property "Value" "C_1u_0402"
			(at 0 -1.4 180)
			(layer "B.Fab")
			(effects
				(font
					(size 0.7 0.7)
					(thickness 0.15)
				)
				(justify left bottom mirror)
			)
		)
		(property "Footprint" "antmicro-footprints:C_0402_1005Metric"
			(at 0 0 0)
			(layer "F.Fab")
			(hide yes)
			(effects
				(font
					(size 1.27 1.27)
					(thickness 0.15)
				)
			)
		)
		(property "Datasheet" "https://product.tdk.com/en/search/capacitor/ceramic/mlcc/info?part_no=C1005X6S1A105K050BC"
			(at 0 0 0)
			(layer "F.Fab")
			(hide yes)
			(effects
				(font
					(size 1.27 1.27)
					(thickness 0.15)
				)
			)
		)
		(property "Author" "Antmicro"
			(at 0 0 0)
			(layer "B.Fab")
			(hide yes)
			(effects
				(font
					(size 1 1)
					(thickness 0.15)
				)
				(justify mirror)
			)
		)
		(property "Dielectric" ""
			(at 0 0 0)
			(layer "B.Fab")
			(hide yes)
			(effects
				(font
					(size 1 1)
					(thickness 0.15)
				)
				(justify mirror)
			)
		)
		(property "License" "Apache-2.0"
			(at 0 0 0)
			(layer "B.Fab")
			(hide yes)
			(effects
				(font
					(size 1 1)
					(thickness 0.15)
				)
				(justify mirror)
			)
		)
		(property "MPN" "C1005X6S1A105K050BC"
			(at 0 0 0)
			(layer "B.Fab")
			(hide yes)
			(effects
				(font
					(size 1 1)
					(thickness 0.15)
				)
				(justify mirror)
			)
		)
		(property "Manufacturer" "TDK"
			(at 0 0 0)
			(layer "B.Fab")
			(hide yes)
			(effects
				(font
					(size 1 1)
					(thickness 0.15)
				)
				(justify mirror)
			)
		)
		(property "Val" "1u"
			(at 0 0 0)
			(layer "B.Fab")
			(hide yes)
			(effects
				(font
					(size 1 1)
					(thickness 0.15)
				)
				(justify mirror)
			)
		)
		(property "Voltage" ""
			(at 0 0 0)
			(layer "B.Fab")
			(hide yes)
			(effects
				(font
					(size 1 1)
					(thickness 0.15)
				)
				(justify mirror)
			)
		)
		(sheetname "CSI")
		(sheetfile "csi.kicad_sch")
		(attr smd)
		(fp_rect
			(start -0.925 0.47)
			(end 0.925 -0.47)
			(stroke
				(width 0.05)
				(type default)
			)
			(fill none)
			(layer "B.CrtYd")
		)
		(fp_line
			(start -0.494 -0.248)
			(end 0.504 -0.248)
			(stroke
				(width 0.15)
				(type solid)
			)
			(layer "B.Fab")
		)
		(fp_line
			(start -0.494 0.25)
			(end -0.494 -0.248)
			(stroke
				(width 0.15)
				(type solid)
			)
			(layer "B.Fab")
		)
		(fp_line
			(start 0.504 -0.248)
			(end 0.504 0.25)
			(stroke
				(width 0.15)
				(type solid)
			)
			(layer "B.Fab")
		)
		(fp_line
			(start 0.504 0.25)
			(end -0.494 0.25)
			(stroke
				(width 0.15)
				(type solid)
			)
			(layer "B.Fab")
		)
		(fp_text user "License: Apache-2.0"
			(at -0.932 -5.17 180)
			(layer "B.Fab")
			(hide yes)
			(effects
				(font
					(size 0.7 0.7)
					(thickness 0.15)
				)
				(justify left bottom mirror)
			)
		)
		(fp_text user "Author: Antmicro"
			(at -0.932 -4.17 180)
			(layer "B.Fab")
			(hide yes)
			(effects
				(font
					(size 0.7 0.7)
					(thickness 0.15)
				)
				(justify left bottom mirror)
			)
		)
		(fp_text user "${REFERENCE}"
			(at -0.932 -3.168 180)
			(layer "B.Fab")
			(hide yes)
			(effects
				(font
					(size 0.7 0.7)
					(thickness 0.15)
				)
				(justify left bottom mirror)
			)
		)
		(pad "1" smd roundrect
			(at -0.48 0)
			(size 0.59 0.64)
			(layers "B.Cu" "B.Paste" "B.Mask")
			(roundrect_rratio 0.25)
			(net 1 "GND")
			(pintype "passive")
		)
		(pad "2" smd roundrect
			(at 0.48 0)
			(size 0.59 0.64)
			(layers "B.Cu" "B.Paste" "B.Mask")
			(roundrect_rratio 0.25)
			(net 110 "/CSI/CSIB_3V3")
			(pintype "passive")
		)
	)
	(footprint "antmicro-footprints:R_0402_1005Metric"
		(layer "B.Cu")
		(at 135.8 99.4)
		(descr "Resistor SMD 0402")
		(tags "resistor SMD 0402")
		(property "Reference" "R11"
			(at -0.75 0.45 180)
			(layer "B.SilkS")
			(effects
				(font
					(size 0.7 0.7)
					(thickness 0.15)
				)
				(justify left bottom mirror)
			)
		)
		(property "Value" "R_0R_0402"
			(at 0 -1.4 180)
			(layer "B.Fab")
			(effects
				(font
					(size 0.7 0.7)
					(thickness 0.15)
				)
				(justify left bottom mirror)
			)
		)
		(property "Footprint" "antmicro-footprints:R_0402_1005Metric"
			(at 0 0 0)
			(layer "F.Fab")
			(hide yes)
			(effects
				(font
					(size 1.27 1.27)
					(thickness 0.15)
				)
			)
		)
		(property "Datasheet" "https://industrial.panasonic.com/cdbs/www-data/pdf/RDA0000/AOA0000C301.pdf"
			(at 0 0 0)
			(layer "F.Fab")
			(hide yes)
			(effects
				(font
					(size 1.27 1.27)
					(thickness 0.15)
				)
			)
		)
		(property "Author" "Antmicro"
			(at 0 0 0)
			(layer "B.Fab")
			(hide yes)
			(effects
				(font
					(size 1 1)
					(thickness 0.15)
				)
				(justify mirror)
			)
		)
		(property "Current" "1A"
			(at 0 0 0)
			(layer "B.Fab")
			(hide yes)
			(effects
				(font
					(size 1 1)
					(thickness 0.15)
				)
				(justify mirror)
			)
		)
		(property "License" "Apache-2.0"
			(at 0 0 0)
			(layer "B.Fab")
			(hide yes)
			(effects
				(font
					(size 1 1)
					(thickness 0.15)
				)
				(justify mirror)
			)
		)
		(property "MPN" "ERJ2GE0R00X"
			(at 0 0 0)
			(layer "B.Fab")
			(hide yes)
			(effects
				(font
					(size 1 1)
					(thickness 0.15)
				)
				(justify mirror)
			)
		)
		(property "Manufacturer" "Panasonic"
			(at 0 0 0)
			(layer "B.Fab")
			(hide yes)
			(effects
				(font
					(size 1 1)
					(thickness 0.15)
				)
				(justify mirror)
			)
		)
		(property "Tolerance" ""
			(at 0 0 0)
			(layer "B.Fab")
			(hide yes)
			(effects
				(font
					(size 1 1)
					(thickness 0.15)
				)
				(justify mirror)
			)
		)
		(property "Val" "0R"
			(at 0 0 0)
			(layer "B.Fab")
			(hide yes)
			(effects
				(font
					(size 1 1)
					(thickness 0.15)
				)
				(justify mirror)
			)
		)
		(sheetname "SoM")
		(sheetfile "som.kicad_sch")
		(attr smd)
		(fp_rect
			(start -0.925 0.47)
			(end 0.925 -0.47)
			(stroke
				(width 0.05)
				(type default)
			)
			(fill none)
			(layer "B.CrtYd")
		)
		(fp_rect
			(start -0.5 0.25)
			(end 0.5 -0.25)
			(stroke
				(width 0.15)
				(type solid)
			)
			(fill none)
			(layer "B.Fab")
		)
		(fp_text user "Author: Antmicro"
			(at -0.95 -4.169 180)
			(layer "B.Fab")
			(hide yes)
			(effects
				(font
					(size 0.7 0.7)
					(thickness 0.15)
				)
				(justify left bottom mirror)
			)
		)
		(fp_text user "License: Apache-2.0"
			(at -0.95 -5.169 180)
			(layer "B.Fab")
			(hide yes)
			(effects
				(font
					(size 0.7 0.7)
					(thickness 0.15)
				)
				(justify left bottom mirror)
			)
		)
		(fp_text user "${REFERENCE}"
			(at -0.95 -3.168 180)
			(layer "B.Fab")
			(hide yes)
			(effects
				(font
					(size 0.7 0.7)
					(thickness 0.15)
				)
				(justify left bottom mirror)
			)
		)
		(pad "1" smd roundrect
			(at -0.48 0)
			(size 0.59 0.64)
			(layers "B.Cu" "B.Paste" "B.Mask")
			(roundrect_rratio 0.25)
			(net 745 "Net-(J15B-CAM1_PWDN)")
			(pintype "passive")
		)
		(pad "2" smd roundrect
			(at 0.48 0)
			(size 0.59 0.64)
			(layers "B.Cu" "B.Paste" "B.Mask")
			(roundrect_rratio 0.25)
			(net 219 "VSYNC_CAM1")
			(pintype "passive")
		)
	)
	(footprint "antmicro-footprints:R_0402_1005Metric"
		(layer "B.Cu")
		(at 71.8 100.95 180)
		(descr "Resistor SMD 0402")
		(tags "resistor SMD 0402")
		(property "Reference" "R41"
			(at -0.72 1.54 0)
			(layer "B.SilkS")
			(effects
				(font
					(size 0.7 0.7)
					(thickness 0.15)
				)
				(justify left bottom mirror)
			)
		)
		(property "Value" "R_0R_0402"
			(at 0 -1.4 0)
			(layer "B.Fab")
			(effects
				(font
					(size 0.7 0.7)
					(thickness 0.15)
				)
				(justify left bottom mirror)
			)
		)
		(property "Footprint" "antmicro-footprints:R_0402_1005Metric"
			(at 0 0 180)
			(layer "F.Fab")
			(hide yes)
			(effects
				(font
					(size 1.27 1.27)
					(thickness 0.15)
				)
			)
		)
		(property "Datasheet" "https://industrial.panasonic.com/cdbs/www-data/pdf/RDA0000/AOA0000C301.pdf"
			(at 0 0 180)
			(layer "F.Fab")
			(hide yes)
			(effects
				(font
					(size 1.27 1.27)
					(thickness 0.15)
				)
			)
		)
		(property "Author" "Antmicro"
			(at 143.6 201.9 0)
			(layer "B.Fab")
			(hide yes)
			(effects
				(font
					(size 1 1)
					(thickness 0.15)
				)
				(justify mirror)
			)
		)
		(property "Current" "1A"
			(at 143.6 201.9 0)
			(layer "B.Fab")
			(hide yes)
			(effects
				(font
					(size 1 1)
					(thickness 0.15)
				)
				(justify mirror)
			)
		)
		(property "License" "Apache-2.0"
			(at 143.6 201.9 0)
			(layer "B.Fab")
			(hide yes)
			(effects
				(font
					(size 1 1)
					(thickness 0.15)
				)
				(justify mirror)
			)
		)
		(property "MPN" "ERJ2GE0R00X"
			(at 143.6 201.9 0)
			(layer "B.Fab")
			(hide yes)
			(effects
				(font
					(size 1 1)
					(thickness 0.15)
				)
				(justify mirror)
			)
		)
		(property "Manufacturer" "Panasonic"
			(at 143.6 201.9 0)
			(layer "B.Fab")
			(hide yes)
			(effects
				(font
					(size 1 1)
					(thickness 0.15)
				)
				(justify mirror)
			)
		)
		(property "Tolerance" ""
			(at 143.6 201.9 0)
			(layer "B.Fab")
			(hide yes)
			(effects
				(font
					(size 1 1)
					(thickness 0.15)
				)
				(justify mirror)
			)
		)
		(property "Val" "0R"
			(at 143.6 201.9 0)
			(layer "B.Fab")
			(hide yes)
			(effects
				(font
					(size 1 1)
					(thickness 0.15)
				)
				(justify mirror)
			)
		)
		(sheetname "USB Debug, DP")
		(sheetfile "usb.kicad_sch")
		(attr smd)
		(fp_rect
			(start -0.925 0.47)
			(end 0.925 -0.47)
			(stroke
				(width 0.05)
				(type default)
			)
			(fill none)
			(layer "B.CrtYd")
		)
		(fp_rect
			(start -0.5 0.25)
			(end 0.5 -0.25)
			(stroke
				(width 0.15)
				(type solid)
			)
			(fill none)
			(layer "B.Fab")
		)
		(fp_text user "License: Apache-2.0"
			(at -0.95 -5.169 0)
			(layer "B.Fab")
			(hide yes)
			(effects
				(font
					(size 0.7 0.7)
					(thickness 0.15)
				)
				(justify left bottom mirror)
			)
		)
		(fp_text user "${REFERENCE}"
			(at -0.95 -3.168 0)
			(layer "B.Fab")
			(hide yes)
			(effects
				(font
					(size 0.7 0.7)
					(thickness 0.15)
				)
				(justify left bottom mirror)
			)
		)
		(fp_text user "Author: Antmicro"
			(at -0.95 -4.169 0)
			(layer "B.Fab")
			(hide yes)
			(effects
				(font
					(size 0.7 0.7)
					(thickness 0.15)
				)
				(justify left bottom mirror)
			)
		)
		(pad "1" smd roundrect
			(at -0.48 0 180)
			(size 0.59 0.64)
			(layers "B.Cu" "B.Paste" "B.Mask")
			(roundrect_rratio 0.25)
			(net 1 "GND")
			(pintype "passive")
		)
		(pad "2" smd roundrect
			(at 0.48 0 180)
			(size 0.59 0.64)
			(layers "B.Cu" "B.Paste" "B.Mask")
			(roundrect_rratio 0.25)
			(net 285 "/USB Debug, DP/PDC_RESET")
			(pintype "passive")
		)
	)
	(footprint "antmicro-footprints:C_0402_1005Metric"
		(layer "B.Cu")
		(at 95.55 93.95)
		(descr "Capacitor SMD 0402")
		(tags "capacitor SMD 0402")
		(property "Reference" "C135"
			(at 5.82 0.69 180)
			(layer "B.SilkS")
			(effects
				(font
					(size 0.7 0.7)
					(thickness 0.15)
				)
				(justify left bottom mirror)
			)
		)
		(property "Value" "C_100n_0402"
			(at 0 -1.4 180)
			(layer "B.Fab")
			(effects
				(font
					(size 0.7 0.7)
					(thickness 0.15)
				)
				(justify left bottom mirror)
			)
		)
		(property "Footprint" "antmicro-footprints:C_0402_1005Metric"
			(at 0 0 0)
			(layer "F.Fab")
			(hide yes)
			(effects
				(font
					(size 1.27 1.27)
					(thickness 0.15)
				)
			)
		)
		(property "Datasheet" "https://www.murata.com/products/productdetail?partno=GRM155R61H104KE14%23"
			(at 0 0 0)
			(layer "F.Fab")
			(hide yes)
			(effects
				(font
					(size 1.27 1.27)
					(thickness 0.15)
				)
			)
		)
		(property "Author" "Antmicro"
			(at 0 0 0)
			(layer "B.Fab")
			(hide yes)
			(effects
				(font
					(size 1 1)
					(thickness 0.15)
				)
				(justify mirror)
			)
		)
		(property "Dielectric" "X5R"
			(at 0 0 0)
			(layer "B.Fab")
			(hide yes)
			(effects
				(font
					(size 1 1)
					(thickness 0.15)
				)
				(justify mirror)
			)
		)
		(property "License" "Apache-2.0"
			(at 0 0 0)
			(layer "B.Fab")
			(hide yes)
			(effects
				(font
					(size 1 1)
					(thickness 0.15)
				)
				(justify mirror)
			)
		)
		(property "MPN" "GRM155R61H104KE14D"
			(at 0 0 0)
			(layer "B.Fab")
			(hide yes)
			(effects
				(font
					(size 1 1)
					(thickness 0.15)
				)
				(justify mirror)
			)
		)
		(property "Manufacturer" "Murata"
			(at 0 0 0)
			(layer "B.Fab")
			(hide yes)
			(effects
				(font
					(size 1 1)
					(thickness 0.15)
				)
				(justify mirror)
			)
		)
		(property "Val" "100n"
			(at 0 0 0)
			(layer "B.Fab")
			(hide yes)
			(effects
				(font
					(size 1 1)
					(thickness 0.15)
				)
				(justify mirror)
			)
		)
		(property "Voltage" "50V"
			(at 0 0 0)
			(layer "B.Fab")
			(hide yes)
			(effects
				(font
					(size 1 1)
					(thickness 0.15)
				)
				(justify mirror)
			)
		)
		(sheetname "HDMI")
		(sheetfile "hdmi.kicad_sch")
		(attr smd)
		(fp_rect
			(start -0.925 0.47)
			(end 0.925 -0.47)
			(stroke
				(width 0.05)
				(type default)
			)
			(fill none)
			(layer "B.CrtYd")
		)
		(fp_line
			(start -0.494 -0.248)
			(end 0.504 -0.248)
			(stroke
				(width 0.15)
				(type solid)
			)
			(layer "B.Fab")
		)
		(fp_line
			(start -0.494 0.25)
			(end -0.494 -0.248)
			(stroke
				(width 0.15)
				(type solid)
			)
			(layer "B.Fab")
		)
		(fp_line
			(start 0.504 -0.248)
			(end 0.504 0.25)
			(stroke
				(width 0.15)
				(type solid)
			)
			(layer "B.Fab")
		)
		(fp_line
			(start 0.504 0.25)
			(end -0.494 0.25)
			(stroke
				(width 0.15)
				(type solid)
			)
			(layer "B.Fab")
		)
		(fp_text user "Author: Antmicro"
			(at -0.932 -4.17 180)
			(layer "B.Fab")
			(hide yes)
			(effects
				(font
					(size 0.7 0.7)
					(thickness 0.15)
				)
				(justify left bottom mirror)
			)
		)
		(fp_text user "License: Apache-2.0"
			(at -0.932 -5.17 180)
			(layer "B.Fab")
			(hide yes)
			(effects
				(font
					(size 0.7 0.7)
					(thickness 0.15)
				)
				(justify left bottom mirror)
			)
		)
		(fp_text user "${REFERENCE}"
			(at -0.932 -3.168 180)
			(layer "B.Fab")
			(hide yes)
			(effects
				(font
					(size 0.7 0.7)
					(thickness 0.15)
				)
				(justify left bottom mirror)
			)
		)
		(pad "1" smd roundrect
			(at -0.48 0)
			(size 0.59 0.64)
			(layers "B.Cu" "B.Paste" "B.Mask")
			(roundrect_rratio 0.25)
			(net 700 "/HDMI/DP_MUX_D3+")
			(pintype "passive")
		)
		(pad "2" smd roundrect
			(at 0.48 0)
			(size 0.59 0.64)
			(layers "B.Cu" "B.Paste" "B.Mask")
			(roundrect_rratio 0.25)
			(net 367 "DP1_TXD0_HDMI_TX2_P")
			(pintype "passive")
		)
	)
	(footprint "antmicro-footprints:WSON-6-1EP_2x2mm_P0.65mm"
		(layer "B.Cu")
		(at 47.175 123.945 -90)
		(property "Reference" "U8"
			(at 2.315 -1.315 180)
			(layer "B.SilkS")
			(effects
				(font
					(size 0.7 0.7)
					(thickness 0.15)
				)
				(justify left bottom mirror)
			)
		)
		(property "Value" "NCP730BMT330_WSON"
			(at 0 -2.2 90)
			(layer "B.Fab")
			(effects
				(font
					(size 0.7 0.7)
					(thickness 0.15)
				)
				(justify left bottom mirror)
			)
		)
		(property "Footprint" "antmicro-footprints:WSON-6-1EP_2x2mm_P0.65mm"
			(at 0 0 -90)
			(layer "F.Fab")
			(hide yes)
			(effects
				(font
					(size 1.27 1.27)
					(thickness 0.15)
				)
			)
		)
		(property "Datasheet" "https://www.onsemi.com/download/data-sheet/pdf/ncp730-d.pdf"
			(at 0 0 -90)
			(layer "F.Fab")
			(hide yes)
			(effects
				(font
					(size 1.27 1.27)
					(thickness 0.15)
				)
			)
		)
		(property "Author" "Antmicro"
			(at -76.77 171.12 0)
			(layer "B.Fab")
			(hide yes)
			(effects
				(font
					(size 1 1)
					(thickness 0.15)
				)
				(justify mirror)
			)
		)
		(property "License" "Apache-2.0"
			(at -76.77 171.12 0)
			(layer "B.Fab")
			(hide yes)
			(effects
				(font
					(size 1 1)
					(thickness 0.15)
				)
				(justify mirror)
			)
		)
		(property "MPN" "NCP730BMT330TBG"
			(at -76.77 171.12 0)
			(layer "B.Fab")
			(hide yes)
			(effects
				(font
					(size 1 1)
					(thickness 0.15)
				)
				(justify mirror)
			)
		)
		(property "Manufacturer" "ON Semiconductor"
			(at -76.77 171.12 0)
			(layer "B.Fab")
			(hide yes)
			(effects
				(font
					(size 1 1)
					(thickness 0.15)
				)
				(justify mirror)
			)
		)
		(sheetname "USB Debug, DP")
		(sheetfile "usb.kicad_sch")
		(attr smd)
		(fp_line
			(start -1.05 1)
			(end 1 1)
			(stroke
				(width 0.12)
				(type solid)
			)
			(layer "B.SilkS")
		)
		(fp_line
			(start 1 -1)
			(end -1 -1)
			(stroke
				(width 0.12)
				(type solid)
			)
			(layer "B.SilkS")
		)
		(fp_circle
			(center -1.275 1.075)
			(end -1.224 1.075)
			(stroke
				(width 0.15)
				(type solid)
			)
			(fill solid)
			(layer "B.SilkS")
		)
		(fp_rect
			(start -1.45 1.25)
			(end 1.45 -1.25)
			(stroke
				(width 0.05)
				(type solid)
			)
			(fill none)
			(layer "B.CrtYd")
		)
		(fp_text user "Author: Antmicro"
			(at -1.01 -5.2 90)
			(layer "B.Fab")
			(hide yes)
			(effects
				(font
					(size 0.7 0.7)
					(thickness 0.15)
				)
				(justify left bottom mirror)
			)
		)
		(fp_text user "License: Apache-2.0"
			(at -1.01 -6.4 90)
			(layer "B.Fab")
			(hide yes)
			(effects
				(font
					(size 0.7 0.7)
					(thickness 0.15)
				)
				(justify left bottom mirror)
			)
		)
		(fp_text user "${REFERENCE}"
			(at -1.01 -3.999 90)
			(layer "B.Fab")
			(hide yes)
			(effects
				(font
					(size 0.7 0.7)
					(thickness 0.15)
				)
				(justify left bottom mirror)
			)
		)
		(pad "1" smd roundrect
			(at -0.975 0.652 270)
			(size 0.45 0.4)
			(layers "B.Cu" "B.Paste" "B.Mask")
			(roundrect_rratio 0.25)
			(net 185 "/USB Debug, DP/FTDI_3V3")
			(pinfunction "V_{OUT}")
			(pintype "power_out")
		)
		(pad "2" smd roundrect
			(at -0.975 0 270)
			(size 0.45 0.4)
			(layers "B.Cu" "B.Paste" "B.Mask")
			(roundrect_rratio 0.25)
			(net 702 "unconnected-(U8-NC-Pad2)")
			(pinfunction "NC")
			(pintype "no_connect")
		)
		(pad "3" smd roundrect
			(at -0.975 -0.65 270)
			(size 0.45 0.4)
			(layers "B.Cu" "B.Paste" "B.Mask")
			(roundrect_rratio 0.25)
			(net 1 "GND")
			(pinfunction "GND")
			(pintype "power_in")
		)
		(pad "4" smd roundrect
			(at 0.973 -0.65 270)
			(size 0.45 0.4)
			(layers "B.Cu" "B.Paste" "B.Mask")
			(roundrect_rratio 0.25)
			(net 196 "/USB Debug, DP/USBC3_VBUS")
			(pinfunction "EN")
			(pintype "input")
		)
		(pad "5" smd roundrect
			(at 0.973 0 270)
			(size 0.45 0.4)
			(layers "B.Cu" "B.Paste" "B.Mask")
			(roundrect_rratio 0.25)
			(net 1 "GND")
			(pinfunction "PG")
			(pintype "open_collector")
		)
		(pad "6" smd roundrect
			(at 0.973 0.652 270)
			(size 0.45 0.4)
			(layers "B.Cu" "B.Paste" "B.Mask")
			(roundrect_rratio 0.25)
			(net 196 "/USB Debug, DP/USBC3_VBUS")
			(pinfunction "V_{IN}")
			(pintype "power_in")
		)
		(pad "7" smd roundrect
			(at 0 0 270)
			(size 1.12 1.72)
			(layers "B.Cu" "B.Paste" "B.Mask")
			(roundrect_rratio 0.1)
			(net 1 "GND")
			(pinfunction "GND")
			(pintype "passive")
		)
	)
	(footprint "antmicro-footprints:Spacer_Drill3.7mm_H6.5mm_9774065151R"
		(locked yes)
		(layer "B.Cu")
		(at 144.75 123.75 180)
		(descr "Spacer M=3 h=6.5mm fi=5.1mm")
		(property "Reference" "H3"
			(at 1.05 -3.85 0)
			(layer "B.SilkS")
			(effects
				(font
					(size 0.7 0.7)
					(thickness 0.15)
				)
				(justify left bottom mirror)
			)
		)
		(property "Value" "Spacer_Drill3.7mm_H6.5mm_9774065151R"
			(at 0 -4 0)
			(layer "B.Fab")
			(effects
				(font
					(size 0.7 0.7)
					(thickness 0.15)
				)
				(justify left bottom mirror)
			)
		)
		(property "Footprint" "antmicro-footprints:Spacer_Drill3.7mm_H6.5mm_9774065151R"
			(at 0 0 180)
			(layer "F.Fab")
			(hide yes)
			(effects
				(font
					(size 1.27 1.27)
					(thickness 0.15)
				)
			)
		)
		(property "Datasheet" "https://www.we-online.com/components/products/datasheet/9774065151R.pdf"
			(at 0 0 180)
			(layer "F.Fab")
			(hide yes)
			(effects
				(font
					(size 1.27 1.27)
					(thickness 0.15)
				)
			)
		)
		(property "Author" "Antmicro"
			(at 289.5 247.5 0)
			(layer "B.Fab")
			(hide yes)
			(effects
				(font
					(size 1 1)
					(thickness 0.15)
				)
				(justify mirror)
			)
		)
		(property "License" "Apache-2.0"
			(at 289.5 247.5 0)
			(layer "B.Fab")
			(hide yes)
			(effects
				(font
					(size 1 1)
					(thickness 0.15)
				)
				(justify mirror)
			)
		)
		(property "MPN" "9774065151R"
			(at 289.5 247.5 0)
			(layer "B.Fab")
			(hide yes)
			(effects
				(font
					(size 1 1)
					(thickness 0.15)
				)
				(justify mirror)
			)
		)
		(property "Manufacturer" "Würth Elektronik"
			(at 289.5 247.5 0)
			(layer "B.Fab")
			(hide yes)
			(effects
				(font
					(size 1 1)
					(thickness 0.15)
				)
				(justify mirror)
			)
		)
		(sheetname "Root")
		(sheetfile "jetson-orin-baseboard.kicad_sch")
		(solder_paste_ratio -1)
		(attr smd)
		(fp_circle
			(center 0 0)
			(end 3.05 0)
			(stroke
				(width 0.05)
				(type solid)
			)
			(fill none)
			(layer "B.CrtYd")
		)
		(fp_circle
			(center 0 0)
			(end 2.6 0)
			(stroke
				(width 0.15)
				(type solid)
			)
			(fill none)
			(layer "B.Fab")
		)
		(fp_text user "License: Apache-2.0"
			(at -9.6 -8.9 0)
			(layer "B.Fab")
			(hide yes)
			(effects
				(font
					(size 0.7 0.7)
					(thickness 0.15)
				)
				(justify left bottom mirror)
			)
		)
		(fp_text user "Author: Antmicro"
			(at -9.6 -7.7 0)
			(layer "B.Fab")
			(hide yes)
			(effects
				(font
					(size 0.7 0.7)
					(thickness 0.15)
				)
				(justify left bottom mirror)
			)
		)
		(fp_text user "${REFERENCE}"
			(at -9.6 -6.5 0)
			(layer "B.Fab")
			(hide yes)
			(effects
				(font
					(size 0.7 0.7)
					(thickness 0.15)
				)
				(justify left bottom mirror)
			)
		)
		(pad "" smd custom
			(at -1.7 -1.7 90)
			(size 0.62 0.62)
			(layers "B.Paste")
			(thermal_bridge_angle 90)
			(options
				(clearance outline)
				(anchor circle)
			)
			(primitives
				(gr_arc
					(start 1.266786 0.24747)
					(mid 0.285453 -0.29439)
					(end -0.250195 -1.279127)
					(width 0.2)
				)
				(gr_arc
					(start 1.259603 0.339191)
					(mid 0.218448 -0.232561)
					(end -0.34334 -1.279127)
					(width 0.2)
				)
				(gr_arc
					(start 1.255279 0.431435)
					(mid 0.152481 -0.169693)
					(end -0.436309 -1.279127)
					(width 0.2)
				)
				(gr_arc
					(start 1.253811 0.524161)
					(mid 0.087542 -0.105784)
					(end -0.529126 -1.279127)
					(width 0.2)
				)
				(gr_arc
					(start 1.275473 0.621136)
					(mid 0.0309 -0.033527)
					(end -0.621807 -1.279127)
					(width 0.2)
				)
				(gr_arc
					(start 1.263664 0.711602)
					(mid -0.037759 0.026651)
					(end -0.71437 -1.279127)
					(width 0.2)
				)
				(gr_arc
					(start 1.253435 0.802342)
					(mid -0.105837 0.087395)
					(end -0.806826 -1.279127)
					(width 0.2)
				)
				(gr_arc
					(start 1.267475 0.897258)
					(mid -0.165236 0.156885)
					(end -0.899187 -1.279127)
					(width 0.2)
				)
				(gr_arc
					(start 1.270645 0.990112)
					(mid -0.228522 0.222449)
					(end -0.991463 -1.279127)
					(width 0.2)
				)
				(gr_arc
					(start 1.266278 1.081674)
					(mid -0.294507 0.285313)
					(end -1.083663 -1.279127)
					(width 0.2)
				)
				(gr_line
					(start 1.279127 1.083663)
					(end 1.279127 0.250195)
					(width 0.2)
				)
				(gr_line
					(start -1.083663 -1.279127)
					(end -0.250195 -1.279127)
					(width 0.2)
				)
			)
		)
		(pad "" smd custom
			(at -1.7 1.7 180)
			(size 0.62 0.62)
			(layers "B.Paste")
			(thermal_bridge_angle 90)
			(options
				(clearance outline)
				(anchor circle)
			)
			(primitives
				(gr_arc
					(start 1.266786 0.24747)
					(mid 0.285453 -0.29439)
					(end -0.250195 -1.279127)
					(width 0.2)
				)
				(gr_arc
					(start 1.259603 0.339191)
					(mid 0.218448 -0.232561)
					(end -0.34334 -1.279127)
					(width 0.2)
				)
				(gr_arc
					(start 1.255279 0.431435)
					(mid 0.152481 -0.169693)
					(end -0.436309 -1.279127)
					(width 0.2)
				)
				(gr_arc
					(start 1.253811 0.524161)
					(mid 0.087542 -0.105784)
					(end -0.529126 -1.279127)
					(width 0.2)
				)
				(gr_arc
					(start 1.275473 0.621136)
					(mid 0.0309 -0.033527)
					(end -0.621807 -1.279127)
					(width 0.2)
				)
				(gr_arc
					(start 1.263664 0.711602)
					(mid -0.037759 0.026651)
					(end -0.71437 -1.279127)
					(width 0.2)
				)
				(gr_arc
					(start 1.253435 0.802342)
					(mid -0.105837 0.087395)
					(end -0.806826 -1.279127)
					(width 0.2)
				)
				(gr_arc
					(start 1.267475 0.897258)
					(mid -0.165236 0.156885)
					(end -0.899187 -1.279127)
					(width 0.2)
				)
				(gr_arc
					(start 1.270645 0.990112)
					(mid -0.228522 0.222449)
					(end -0.991463 -1.279127)
					(width 0.2)
				)
				(gr_arc
					(start 1.266278 1.081674)
					(mid -0.294507 0.285313)
					(end -1.083663 -1.279127)
					(width 0.2)
				)
				(gr_line
					(start 1.279127 1.083663)
					(end 1.279127 0.250195)
					(width 0.2)
				)
				(gr_line
					(start -1.083663 -1.279127)
					(end -0.250195 -1.279127)
					(width 0.2)
				)
			)
		)
		(pad "" smd custom
			(at 1.7 -1.7)
			(size 0.62 0.62)
			(layers "B.Paste")
			(thermal_bridge_angle 90)
			(options
				(clearance outline)
				(anchor circle)
			)
			(primitives
				(gr_arc
					(start 1.266786 0.24747)
					(mid 0.285453 -0.29439)
					(end -0.250195 -1.279127)
					(width 0.2)
				)
				(gr_arc
					(start 1.259603 0.339191)
					(mid 0.218448 -0.232561)
					(end -0.34334 -1.279127)
					(width 0.2)
				)
				(gr_arc
					(start 1.255279 0.431435)
					(mid 0.152481 -0.169693)
					(end -0.436309 -1.279127)
					(width 0.2)
				)
				(gr_arc
					(start 1.253811 0.524161)
					(mid 0.087542 -0.105784)
					(end -0.529126 -1.279127)
					(width 0.2)
				)
				(gr_arc
					(start 1.275473 0.621136)
					(mid 0.0309 -0.033527)
					(end -0.621807 -1.279127)
					(width 0.2)
				)
				(gr_arc
					(start 1.263664 0.711602)
					(mid -0.037759 0.026651)
					(end -0.71437 -1.279127)
					(width 0.2)
				)
				(gr_arc
					(start 1.253435 0.802342)
					(mid -0.105837 0.087395)
					(end -0.806826 -1.279127)
					(width 0.2)
				)
				(gr_arc
					(start 1.267475 0.897258)
					(mid -0.165236 0.156885)
					(end -0.899187 -1.279127)
					(width 0.2)
				)
				(gr_arc
					(start 1.270645 0.990112)
					(mid -0.228522 0.222449)
					(end -0.991463 -1.279127)
					(width 0.2)
				)
				(gr_arc
					(start 1.266278 1.081674)
					(mid -0.294507 0.285313)
					(end -1.083663 -1.279127)
					(width 0.2)
				)
				(gr_line
					(start 1.279127 1.083663)
					(end 1.279127 0.250195)
					(width 0.2)
				)
				(gr_line
					(start -1.083663 -1.279127)
					(end -0.250195 -1.279127)
					(width 0.2)
				)
			)
		)
		(pad "" smd custom
			(at 1.7 1.7 270)
			(size 0.62 0.62)
			(layers "B.Paste")
			(thermal_bridge_angle 90)
			(options
				(clearance outline)
				(anchor circle)
			)
			(primitives
				(gr_arc
					(start 1.266786 0.24747)
					(mid 0.285453 -0.29439)
					(end -0.250195 -1.279127)
					(width 0.2)
				)
				(gr_arc
					(start 1.259603 0.339191)
					(mid 0.218448 -0.232561)
					(end -0.34334 -1.279127)
					(width 0.2)
				)
				(gr_arc
					(start 1.255279 0.431435)
					(mid 0.152481 -0.169693)
					(end -0.436309 -1.279127)
					(width 0.2)
				)
				(gr_arc
					(start 1.253811 0.524161)
					(mid 0.087542 -0.105784)
					(end -0.529126 -1.279127)
					(width 0.2)
				)
				(gr_arc
					(start 1.275473 0.621136)
					(mid 0.0309 -0.033527)
					(end -0.621807 -1.279127)
					(width 0.2)
				)
				(gr_arc
					(start 1.263664 0.711602)
					(mid -0.037759 0.026651)
					(end -0.71437 -1.279127)
					(width 0.2)
				)
				(gr_arc
					(start 1.253435 0.802342)
					(mid -0.105837 0.087395)
					(end -0.806826 -1.279127)
					(width 0.2)
				)
				(gr_arc
					(start 1.267475 0.897258)
					(mid -0.165236 0.156885)
					(end -0.899187 -1.279127)
					(width 0.2)
				)
				(gr_arc
					(start 1.270645 0.990112)
					(mid -0.228522 0.222449)
					(end -0.991463 -1.279127)
					(width 0.2)
				)
				(gr_arc
					(start 1.266278 1.081674)
					(mid -0.294507 0.285313)
					(end -1.083663 -1.279127)
					(width 0.2)
				)
				(gr_line
					(start 1.279127 1.083663)
					(end 1.279127 0.250195)
					(width 0.2)
				)
				(gr_line
					(start -1.083663 -1.279127)
					(end -0.250195 -1.279127)
					(width 0.2)
				)
			)
		)
		(pad "1" thru_hole circle
			(at 0 0 180)
			(size 6 6)
			(drill 3.7)
			(layers "*.Cu" "*.Mask")
			(remove_unused_layers no)
			(net 1 "GND")
			(pintype "passive")
		)
	)
	(footprint "antmicro-footprints:C_0402_1005Metric"
		(layer "B.Cu")
		(at 51.9 116.8 -90)
		(descr "Capacitor SMD 0402")
		(tags "capacitor SMD 0402")
		(property "Reference" "C145"
			(at 0.7 1.2 90)
			(layer "B.SilkS")
			(effects
				(font
					(size 0.7 0.7)
					(thickness 0.15)
				)
				(justify left bottom mirror)
			)
		)
		(property "Value" "C_47p_0402"
			(at 0 -1.4 90)
			(layer "B.Fab")
			(effects
				(font
					(size 0.7 0.7)
					(thickness 0.15)
				)
				(justify left bottom mirror)
			)
		)
		(property "Footprint" "antmicro-footprints:C_0402_1005Metric"
			(at 0 0 -90)
			(layer "F.Fab")
			(hide yes)
			(effects
				(font
					(size 1.27 1.27)
					(thickness 0.15)
				)
			)
		)
		(property "Datasheet" "https://www.kemet.com/en/us/capacitors/product/C0402C470J5GACTU.html"
			(at 0 0 -90)
			(layer "F.Fab")
			(hide yes)
			(effects
				(font
					(size 1.27 1.27)
					(thickness 0.15)
				)
			)
		)
		(property "Author" "Antmicro"
			(at -64.9 168.7 0)
			(layer "B.Fab")
			(hide yes)
			(effects
				(font
					(size 1 1)
					(thickness 0.15)
				)
				(justify mirror)
			)
		)
		(property "Dielectric" "C0G"
			(at -64.9 168.7 0)
			(layer "B.Fab")
			(hide yes)
			(effects
				(font
					(size 1 1)
					(thickness 0.15)
				)
				(justify mirror)
			)
		)
		(property "License" "Apache-2.0"
			(at -64.9 168.7 0)
			(layer "B.Fab")
			(hide yes)
			(effects
				(font
					(size 1 1)
					(thickness 0.15)
				)
				(justify mirror)
			)
		)
		(property "MPN" "C0402C470J5GACTU"
			(at -64.9 168.7 0)
			(layer "B.Fab")
			(hide yes)
			(effects
				(font
					(size 1 1)
					(thickness 0.15)
				)
				(justify mirror)
			)
		)
		(property "Manufacturer" "KEMET"
			(at -64.9 168.7 0)
			(layer "B.Fab")
			(hide yes)
			(effects
				(font
					(size 1 1)
					(thickness 0.15)
				)
				(justify mirror)
			)
		)
		(property "Val" "47p"
			(at -64.9 168.7 0)
			(layer "B.Fab")
			(hide yes)
			(effects
				(font
					(size 1 1)
					(thickness 0.15)
				)
				(justify mirror)
			)
		)
		(property "Voltage" ""
			(at -64.9 168.7 0)
			(layer "B.Fab")
			(hide yes)
			(effects
				(font
					(size 1 1)
					(thickness 0.15)
				)
				(justify mirror)
			)
		)
		(sheetname "USB Debug, DP")
		(sheetfile "usb.kicad_sch")
		(attr smd)
		(fp_rect
			(start -0.925 0.47)
			(end 0.925 -0.47)
			(stroke
				(width 0.05)
				(type default)
			)
			(fill none)
			(layer "B.CrtYd")
		)
		(fp_line
			(start -0.494 0.25)
			(end -0.494 -0.248)
			(stroke
				(width 0.15)
				(type solid)
			)
			(layer "B.Fab")
		)
		(fp_line
			(start 0.504 0.25)
			(end -0.494 0.25)
			(stroke
				(width 0.15)
				(type solid)
			)
			(layer "B.Fab")
		)
		(fp_line
			(start -0.494 -0.248)
			(end 0.504 -0.248)
			(stroke
				(width 0.15)
				(type solid)
			)
			(layer "B.Fab")
		)
		(fp_line
			(start 0.504 -0.248)
			(end 0.504 0.25)
			(stroke
				(width 0.15)
				(type solid)
			)
			(layer "B.Fab")
		)
		(fp_text user "License: Apache-2.0"
			(at -0.932 -5.17 90)
			(layer "B.Fab")
			(hide yes)
			(effects
				(font
					(size 0.7 0.7)
					(thickness 0.15)
				)
				(justify left bottom mirror)
			)
		)
		(fp_text user "${REFERENCE}"
			(at -0.932 -3.168 90)
			(layer "B.Fab")
			(hide yes)
			(effects
				(font
					(size 0.7 0.7)
					(thickness 0.15)
				)
				(justify left bottom mirror)
			)
		)
		(fp_text user "Author: Antmicro"
			(at -0.932 -4.17 90)
			(layer "B.Fab")
			(hide yes)
			(effects
				(font
					(size 0.7 0.7)
					(thickness 0.15)
				)
				(justify left bottom mirror)
			)
		)
		(pad "1" smd roundrect
			(at -0.48 0 270)
			(size 0.59 0.64)
			(layers "B.Cu" "B.Paste" "B.Mask")
			(roundrect_rratio 0.25)
			(net 1 "GND")
			(pintype "passive")
		)
		(pad "2" smd roundrect
			(at 0.48 0 270)
			(size 0.59 0.64)
			(layers "B.Cu" "B.Paste" "B.Mask")
			(roundrect_rratio 0.25)
			(net 275 "/USB Debug, DP/USBC3_D_N")
			(pintype "passive")
		)
	)
	(footprint "antmicro-footprints:R_0402_1005Metric"
		(layer "B.Cu")
		(at 91 81.4)
		(descr "Resistor SMD 0402")
		(tags "resistor SMD 0402")
		(property "Reference" "R10"
			(at 1.05 -0.45 180)
			(layer "B.SilkS")
			(effects
				(font
					(size 0.7 0.7)
					(thickness 0.15)
				)
				(justify left bottom mirror)
			)
		)
		(property "Value" "R_4k7_0402"
			(at 0 -1.4 180)
			(layer "B.Fab")
			(effects
				(font
					(size 0.7 0.7)
					(thickness 0.15)
				)
				(justify left bottom mirror)
			)
		)
		(property "Footprint" "antmicro-footprints:R_0402_1005Metric"
			(at 0 0 0)
			(layer "F.Fab")
			(hide yes)
			(effects
				(font
					(size 1.27 1.27)
					(thickness 0.15)
				)
			)
		)
		(property "Datasheet" "https://www.bourns.com/docs/product-datasheets/cr.pdf"
			(at 0 0 0)
			(layer "F.Fab")
			(hide yes)
			(effects
				(font
					(size 1.27 1.27)
					(thickness 0.15)
				)
			)
		)
		(property "Author" "Antmicro"
			(at 0 0 0)
			(layer "B.Fab")
			(hide yes)
			(effects
				(font
					(size 1 1)
					(thickness 0.15)
				)
				(justify mirror)
			)
		)
		(property "License" "Apache-2.0"
			(at 0 0 0)
			(layer "B.Fab")
			(hide yes)
			(effects
				(font
					(size 1 1)
					(thickness 0.15)
				)
				(justify mirror)
			)
		)
		(property "MPN" "CR0402-FX-4701GLF"
			(at 0 0 0)
			(layer "B.Fab")
			(hide yes)
			(effects
				(font
					(size 1 1)
					(thickness 0.15)
				)
				(justify mirror)
			)
		)
		(property "Manufacturer" "Bourns"
			(at 0 0 0)
			(layer "B.Fab")
			(hide yes)
			(effects
				(font
					(size 1 1)
					(thickness 0.15)
				)
				(justify mirror)
			)
		)
		(property "Tolerance" "1%"
			(at 0 0 0)
			(layer "B.Fab")
			(hide yes)
			(effects
				(font
					(size 1 1)
					(thickness 0.15)
				)
				(justify mirror)
			)
		)
		(property "Val" "4k7"
			(at 0 0 0)
			(layer "B.Fab")
			(hide yes)
			(effects
				(font
					(size 1 1)
					(thickness 0.15)
				)
				(justify mirror)
			)
		)
		(sheetname "CSI")
		(sheetfile "csi.kicad_sch")
		(attr smd)
		(fp_rect
			(start -0.925 0.47)
			(end 0.925 -0.47)
			(stroke
				(width 0.05)
				(type default)
			)
			(fill none)
			(layer "B.CrtYd")
		)
		(fp_rect
			(start -0.5 0.25)
			(end 0.5 -0.25)
			(stroke
				(width 0.15)
				(type solid)
			)
			(fill none)
			(layer "B.Fab")
		)
		(fp_text user "License: Apache-2.0"
			(at -0.95 -5.169 180)
			(layer "B.Fab")
			(hide yes)
			(effects
				(font
					(size 0.7 0.7)
					(thickness 0.15)
				)
				(justify left bottom mirror)
			)
		)
		(fp_text user "${REFERENCE}"
			(at -0.95 -3.168 180)
			(layer "B.Fab")
			(hide yes)
			(effects
				(font
					(size 0.7 0.7)
					(thickness 0.15)
				)
				(justify left bottom mirror)
			)
		)
		(fp_text user "Author: Antmicro"
			(at -0.95 -4.169 180)
			(layer "B.Fab")
			(hide yes)
			(effects
				(font
					(size 0.7 0.7)
					(thickness 0.15)
				)
				(justify left bottom mirror)
			)
		)
		(pad "1" smd roundrect
			(at -0.48 0)
			(size 0.59 0.64)
			(layers "B.Cu" "B.Paste" "B.Mask")
			(roundrect_rratio 0.25)
			(net 1 "GND")
			(pintype "passive")
		)
		(pad "2" smd roundrect
			(at 0.48 0)
			(size 0.59 0.64)
			(layers "B.Cu" "B.Paste" "B.Mask")
			(roundrect_rratio 0.25)
			(net 344 "/CSI/CSIB_3V3_ISET")
			(pintype "passive")
		)
	)
	(footprint "antmicro-footprints:R_0402_1005Metric"
		(layer "B.Cu")
		(at 89.9 118 90)
		(descr "Resistor SMD 0402")
		(tags "resistor SMD 0402")
		(property "Reference" "R281"
			(at 1.65 5.15 -90)
			(layer "B.SilkS")
			(effects
				(font
					(size 0.7 0.7)
					(thickness 0.15)
				)
				(justify left bottom mirror)
			)
		)
		(property "Value" "R_2k2_0402"
			(at 0 -1.4 -90)
			(layer "B.Fab")
			(effects
				(font
					(size 0.7 0.7)
					(thickness 0.15)
				)
				(justify left bottom mirror)
			)
		)
		(property "Footprint" "antmicro-footprints:R_0402_1005Metric"
			(at 0 0 90)
			(layer "F.Fab")
			(hide yes)
			(effects
				(font
					(size 1.27 1.27)
					(thickness 0.15)
				)
			)
		)
		(property "Datasheet" "https://www.bourns.com/docs/product-datasheets/cr.pdf"
			(at 0 0 90)
			(layer "F.Fab")
			(hide yes)
			(effects
				(font
					(size 1.27 1.27)
					(thickness 0.15)
				)
			)
		)
		(property "Author" "Antmicro"
			(at 207.9 28.1 0)
			(layer "B.Fab")
			(hide yes)
			(effects
				(font
					(size 1 1)
					(thickness 0.15)
				)
				(justify mirror)
			)
		)
		(property "License" "Apache-2.0"
			(at 207.9 28.1 0)
			(layer "B.Fab")
			(hide yes)
			(effects
				(font
					(size 1 1)
					(thickness 0.15)
				)
				(justify mirror)
			)
		)
		(property "MPN" "CR0402-FX-2201GLF"
			(at 207.9 28.1 0)
			(layer "B.Fab")
			(hide yes)
			(effects
				(font
					(size 1 1)
					(thickness 0.15)
				)
				(justify mirror)
			)
		)
		(property "Manufacturer" "Bourns"
			(at 207.9 28.1 0)
			(layer "B.Fab")
			(hide yes)
			(effects
				(font
					(size 1 1)
					(thickness 0.15)
				)
				(justify mirror)
			)
		)
		(property "Tolerance" "1%"
			(at 207.9 28.1 0)
			(layer "B.Fab")
			(hide yes)
			(effects
				(font
					(size 1 1)
					(thickness 0.15)
				)
				(justify mirror)
			)
		)
		(property "Val" "2k2"
			(at 207.9 28.1 0)
			(layer "B.Fab")
			(hide yes)
			(effects
				(font
					(size 1 1)
					(thickness 0.15)
				)
				(justify mirror)
			)
		)
		(sheetname "HDMI")
		(sheetfile "hdmi.kicad_sch")
		(attr smd exclude_from_pos_files exclude_from_bom dnp)
		(fp_rect
			(start -0.925 0.47)
			(end 0.925 -0.47)
			(stroke
				(width 0.05)
				(type default)
			)
			(fill none)
			(layer "B.CrtYd")
		)
		(fp_rect
			(start -0.5 0.25)
			(end 0.5 -0.25)
			(stroke
				(width 0.15)
				(type solid)
			)
			(fill none)
			(layer "B.Fab")
		)
		(fp_text user "${REFERENCE}"
			(at -0.95 -3.168 -90)
			(layer "B.Fab")
			(hide yes)
			(effects
				(font
					(size 0.7 0.7)
					(thickness 0.15)
				)
				(justify left bottom mirror)
			)
		)
		(fp_text user "Author: Antmicro"
			(at -0.95 -4.169 -90)
			(layer "B.Fab")
			(hide yes)
			(effects
				(font
					(size 0.7 0.7)
					(thickness 0.15)
				)
				(justify left bottom mirror)
			)
		)
		(fp_text user "License: Apache-2.0"
			(at -0.95 -5.169 -90)
			(layer "B.Fab")
			(hide yes)
			(effects
				(font
					(size 0.7 0.7)
					(thickness 0.15)
				)
				(justify left bottom mirror)
			)
		)
		(pad "1" smd roundrect
			(at -0.48 0 90)
			(size 0.59 0.64)
			(layers "B.Cu" "B.Paste" "B.Mask")
			(roundrect_rratio 0.25)
			(net 518 "/HDMI/HDMI_SDA_5V")
			(pintype "passive")
		)
		(pad "2" smd roundrect
			(at 0.48 0 90)
			(size 0.59 0.64)
			(layers "B.Cu" "B.Paste" "B.Mask")
			(roundrect_rratio 0.25)
			(net 498 "/HDMI/5V_HDMI")
			(pintype "passive")
		)
	)
	(footprint "antmicro-footprints:R_Array_4x0201_Panasonic_EXB18V"
		(layer "B.Cu")
		(at 108.88 74.66 -90)
		(property "Reference" "R122"
			(at 1.54 0.68 90)
			(layer "B.SilkS")
			(effects
				(font
					(size 0.7 0.7)
					(thickness 0.15)
				)
				(justify right bottom mirror)
			)
		)
		(property "Value" "R_4x0R_0201_array"
			(at -1.1 -1.8 90)
			(layer "B.Fab")
			(effects
				(font
					(size 0.7 0.7)
					(thickness 0.15)
				)
				(justify left bottom mirror)
			)
		)
		(property "Footprint" "antmicro-footprints:R_Array_4x0201_Panasonic_EXB18V"
			(at 0 0 -90)
			(layer "F.Fab")
			(hide yes)
			(effects
				(font
					(size 1.27 1.27)
					(thickness 0.15)
				)
			)
		)
		(property "Datasheet" "http://industrial.panasonic.com/cdbs/www-data/pdf/AOC0000/AOC0000C14.pdf"
			(at 0 0 -90)
			(layer "F.Fab")
			(hide yes)
			(effects
				(font
					(size 1.27 1.27)
					(thickness 0.15)
				)
			)
		)
		(property "Author" "Antmicro"
			(at 34.22 183.54 0)
			(layer "B.Fab")
			(hide yes)
			(effects
				(font
					(size 1 1)
					(thickness 0.15)
				)
				(justify mirror)
			)
		)
		(property "License" "Apache-2.0"
			(at 34.22 183.54 0)
			(layer "B.Fab")
			(hide yes)
			(effects
				(font
					(size 1 1)
					(thickness 0.15)
				)
				(justify mirror)
			)
		)
		(property "MPN" "EXB-18VR000X"
			(at 34.22 183.54 0)
			(layer "B.Fab")
			(hide yes)
			(effects
				(font
					(size 1 1)
					(thickness 0.15)
				)
				(justify mirror)
			)
		)
		(property "Manufacturer" "Panasonic"
			(at 34.22 183.54 0)
			(layer "B.Fab")
			(hide yes)
			(effects
				(font
					(size 1 1)
					(thickness 0.15)
				)
				(justify mirror)
			)
		)
		(property "Val" "4x0R_0201"
			(at 34.22 183.54 0)
			(layer "B.Fab")
			(hide yes)
			(effects
				(font
					(size 1 1)
					(thickness 0.15)
				)
				(justify mirror)
			)
		)
		(sheetname "CSI")
		(sheetfile "csi.kicad_sch")
		(attr smd exclude_from_pos_files exclude_from_bom dnp)
		(fp_line
			(start -0.8 -0.45)
			(end -0.8 0.45)
			(stroke
				(width 0.12)
				(type solid)
			)
			(layer "B.SilkS")
		)
		(fp_line
			(start 0.8 -0.45)
			(end 0.8 0.45)
			(stroke
				(width 0.12)
				(type solid)
			)
			(layer "B.SilkS")
		)
		(fp_rect
			(start -0.898 0.66)
			(end 0.898 -0.65)
			(stroke
				(width 0.05)
				(type solid)
			)
			(fill none)
			(layer "B.CrtYd")
		)
		(fp_text user "License: Apache-2.0"
			(at -1.051 -6 90)
			(layer "B.Fab")
			(hide yes)
			(effects
				(font
					(size 0.7 0.7)
					(thickness 0.15)
				)
				(justify left bottom mirror)
			)
		)
		(fp_text user "Author: Antmicro"
			(at -1.051 -4.599 90)
			(layer "B.Fab")
			(hide yes)
			(effects
				(font
					(size 0.7 0.7)
					(thickness 0.15)
				)
				(justify left bottom mirror)
			)
		)
		(fp_text user "${REFERENCE}"
			(at -1.051 -3.2 90)
			(layer "B.Fab")
			(hide yes)
			(effects
				(font
					(size 0.7 0.7)
					(thickness 0.15)
				)
				(justify left bottom mirror)
			)
		)
		(pad "1" smd roundrect
			(at -0.6 -0.298 270)
			(size 0.2 0.4)
			(layers "B.Cu" "B.Paste" "B.Mask")
			(roundrect_rratio 0.25)
			(net 24 "CSI3_D1_P")
			(pinfunction "R1.1")
			(pintype "passive")
		)
		(pad "2" smd roundrect
			(at -0.202 -0.298 270)
			(size 0.2 0.4)
			(layers "B.Cu" "B.Paste" "B.Mask")
			(roundrect_rratio 0.25)
			(net 22 "CSI3_D1_N")
			(pinfunction "R2.1")
			(pintype "passive")
		)
		(pad "3" smd roundrect
			(at 0.2 -0.298 270)
			(size 0.2 0.4)
			(layers "B.Cu" "B.Paste" "B.Mask")
			(roundrect_rratio 0.25)
			(net 16 "CSI3_D0_P")
			(pinfunction "R3.1")
			(pintype "passive")
		)
		(pad "4" smd roundrect
			(at 0.598 -0.298 270)
			(size 0.2 0.4)
			(layers "B.Cu" "B.Paste" "B.Mask")
			(roundrect_rratio 0.25)
			(net 14 "CSI3_D0_N")
			(pinfunction "R4.1")
			(pintype "passive")
		)
		(pad "5" smd roundrect
			(at 0.598 0.3 270)
			(size 0.2 0.4)
			(layers "B.Cu" "B.Paste" "B.Mask")
			(roundrect_rratio 0.25)
			(net 240 "/CSI/CSI3_1_D0_N")
			(pinfunction "R4.2")
			(pintype "passive")
		)
		(pad "6" smd roundrect
			(at 0.2 0.3 270)
			(size 0.2 0.4)
			(layers "B.Cu" "B.Paste" "B.Mask")
			(roundrect_rratio 0.25)
			(net 241 "/CSI/CSI3_1_D0_P")
			(pinfunction "R3.2")
			(pintype "passive")
		)
		(pad "7" smd roundrect
			(at -0.202 0.3 270)
			(size 0.2 0.4)
			(layers "B.Cu" "B.Paste" "B.Mask")
			(roundrect_rratio 0.25)
			(net 238 "/CSI/CSI3_1_D1_N")
			(pinfunction "R2.2")
			(pintype "passive")
		)
		(pad "8" smd roundrect
			(at -0.6 0.3 270)
			(size 0.2 0.4)
			(layers "B.Cu" "B.Paste" "B.Mask")
			(roundrect_rratio 0.25)
			(net 239 "/CSI/CSI3_1_D1_P")
			(pinfunction "R1.2")
			(pintype "passive")
		)
	)
	(footprint "antmicro-footprints:C_0402_1005Metric"
		(layer "B.Cu")
		(at 49.75 115 180)
		(descr "Capacitor SMD 0402")
		(tags "capacitor SMD 0402")
		(property "Reference" "C31"
			(at 13.147849 -9.408333 0)
			(layer "B.SilkS")
			(effects
				(font
					(size 0.7 0.7)
					(thickness 0.15)
				)
				(justify left bottom mirror)
			)
		)
		(property "Value" "C_100n_0402"
			(at 0 -1.4 0)
			(layer "B.Fab")
			(effects
				(font
					(size 0.7 0.7)
					(thickness 0.15)
				)
				(justify left bottom mirror)
			)
		)
		(property "Footprint" "antmicro-footprints:C_0402_1005Metric"
			(at 0 0 180)
			(layer "F.Fab")
			(hide yes)
			(effects
				(font
					(size 1.27 1.27)
					(thickness 0.15)
				)
			)
		)
		(property "Datasheet" "https://www.murata.com/products/productdetail?partno=GRM155R61H104KE14%23"
			(at 0 0 180)
			(layer "F.Fab")
			(hide yes)
			(effects
				(font
					(size 1.27 1.27)
					(thickness 0.15)
				)
			)
		)
		(property "Author" "Antmicro"
			(at 99.5 230 0)
			(layer "B.Fab")
			(hide yes)
			(effects
				(font
					(size 1 1)
					(thickness 0.15)
				)
				(justify mirror)
			)
		)
		(property "Dielectric" "X5R"
			(at 99.5 230 0)
			(layer "B.Fab")
			(hide yes)
			(effects
				(font
					(size 1 1)
					(thickness 0.15)
				)
				(justify mirror)
			)
		)
		(property "License" "Apache-2.0"
			(at 99.5 230 0)
			(layer "B.Fab")
			(hide yes)
			(effects
				(font
					(size 1 1)
					(thickness 0.15)
				)
				(justify mirror)
			)
		)
		(property "MPN" "GRM155R61H104KE14D"
			(at 99.5 230 0)
			(layer "B.Fab")
			(hide yes)
			(effects
				(font
					(size 1 1)
					(thickness 0.15)
				)
				(justify mirror)
			)
		)
		(property "Manufacturer" "Murata"
			(at 99.5 230 0)
			(layer "B.Fab")
			(hide yes)
			(effects
				(font
					(size 1 1)
					(thickness 0.15)
				)
				(justify mirror)
			)
		)
		(property "Val" "100n"
			(at 99.5 230 0)
			(layer "B.Fab")
			(hide yes)
			(effects
				(font
					(size 1 1)
					(thickness 0.15)
				)
				(justify mirror)
			)
		)
		(property "Voltage" "50V"
			(at 99.5 230 0)
			(layer "B.Fab")
			(hide yes)
			(effects
				(font
					(size 1 1)
					(thickness 0.15)
				)
				(justify mirror)
			)
		)
		(sheetname "USB Debug, DP")
		(sheetfile "usb.kicad_sch")
		(attr smd)
		(fp_rect
			(start -0.925 0.47)
			(end 0.925 -0.47)
			(stroke
				(width 0.05)
				(type default)
			)
			(fill none)
			(layer "B.CrtYd")
		)
		(fp_line
			(start 0.504 0.25)
			(end -0.494 0.25)
			(stroke
				(width 0.15)
				(type solid)
			)
			(layer "B.Fab")
		)
		(fp_line
			(start 0.504 -0.248)
			(end 0.504 0.25)
			(stroke
				(width 0.15)
				(type solid)
			)
			(layer "B.Fab")
		)
		(fp_line
			(start -0.494 0.25)
			(end -0.494 -0.248)
			(stroke
				(width 0.15)
				(type solid)
			)
			(layer "B.Fab")
		)
		(fp_line
			(start -0.494 -0.248)
			(end 0.504 -0.248)
			(stroke
				(width 0.15)
				(type solid)
			)
			(layer "B.Fab")
		)
		(fp_text user "${REFERENCE}"
			(at -0.932 -3.168 0)
			(layer "B.Fab")
			(hide yes)
			(effects
				(font
					(size 0.7 0.7)
					(thickness 0.15)
				)
				(justify left bottom mirror)
			)
		)
		(fp_text user "License: Apache-2.0"
			(at -0.932 -5.17 0)
			(layer "B.Fab")
			(hide yes)
			(effects
				(font
					(size 0.7 0.7)
					(thickness 0.15)
				)
				(justify left bottom mirror)
			)
		)
		(fp_text user "Author: Antmicro"
			(at -0.932 -4.17 0)
			(layer "B.Fab")
			(hide yes)
			(effects
				(font
					(size 0.7 0.7)
					(thickness 0.15)
				)
				(justify left bottom mirror)
			)
		)
		(pad "1" smd roundrect
			(at -0.48 0 180)
			(size 0.59 0.64)
			(layers "B.Cu" "B.Paste" "B.Mask")
			(roundrect_rratio 0.25)
			(net 126 "Net-(U5-~{RESET})")
			(pintype "passive")
		)
		(pad "2" smd roundrect
			(at 0.48 0 180)
			(size 0.59 0.64)
			(layers "B.Cu" "B.Paste" "B.Mask")
			(roundrect_rratio 0.25)
			(net 1 "GND")
			(pintype "passive")
		)
	)
	(footprint "antmicro-footprints:R_0402_1005Metric"
		(layer "B.Cu")
		(at 55.125 86.475)
		(descr "Resistor SMD 0402")
		(tags "resistor SMD 0402")
		(property "Reference" "R150"
			(at -1.245 2.525 0)
			(layer "B.SilkS")
			(effects
				(font
					(size 0.7 0.7)
					(thickness 0.15)
				)
				(justify right top mirror)
			)
		)
		(property "Value" "R_10k_0402"
			(at 0 -1.4 0)
			(layer "B.Fab")
			(effects
				(font
					(size 0.7 0.7)
					(thickness 0.15)
				)
				(justify right top mirror)
			)
		)
		(property "Footprint" "antmicro-footprints:R_0402_1005Metric"
			(at 0 0 0)
			(layer "F.Fab")
			(hide yes)
			(effects
				(font
					(size 1.27 1.27)
					(thickness 0.15)
				)
			)
		)
		(property "Datasheet" "https://www.bourns.com/docs/product-datasheets/cr.pdf"
			(at 0 0 0)
			(layer "F.Fab")
			(hide yes)
			(effects
				(font
					(size 1.27 1.27)
					(thickness 0.15)
				)
			)
		)
		(property "Author" "Antmicro"
			(at -31.575 145.225 90)
			(layer "B.Fab")
			(hide yes)
			(effects
				(font
					(size 1 1)
					(thickness 0.15)
				)
				(justify mirror)
			)
		)
		(property "License" "Apache-2.0"
			(at -31.575 145.225 90)
			(layer "B.Fab")
			(hide yes)
			(effects
				(font
					(size 1 1)
					(thickness 0.15)
				)
				(justify mirror)
			)
		)
		(property "MPN" "CR0402-FX-1002GLF"
			(at -31.575 145.225 90)
			(layer "B.Fab")
			(hide yes)
			(effects
				(font
					(size 1 1)
					(thickness 0.15)
				)
				(justify mirror)
			)
		)
		(property "Manufacturer" "Bourns"
			(at -31.575 145.225 90)
			(layer "B.Fab")
			(hide yes)
			(effects
				(font
					(size 1 1)
					(thickness 0.15)
				)
				(justify mirror)
			)
		)
		(property "Tolerance" "1%"
			(at -31.575 145.225 90)
			(layer "B.Fab")
			(hide yes)
			(effects
				(font
					(size 1 1)
					(thickness 0.15)
				)
				(justify mirror)
			)
		)
		(property "Val" "10k"
			(at -31.575 145.225 90)
			(layer "B.Fab")
			(hide yes)
			(effects
				(font
					(size 1 1)
					(thickness 0.15)
				)
				(justify mirror)
			)
		)
		(sheetname "Ethernet")
		(sheetfile "ethernet.kicad_sch")
		(attr smd exclude_from_pos_files exclude_from_bom dnp)
		(fp_rect
			(start -0.925 0.47)
			(end 0.925 -0.47)
			(stroke
				(width 0.05)
				(type default)
			)
			(fill none)
			(layer "B.CrtYd")
		)
		(fp_rect
			(start -0.5 0.25)
			(end 0.5 -0.25)
			(stroke
				(width 0.15)
				(type solid)
			)
			(fill none)
			(layer "B.Fab")
		)
		(fp_text user "Author: Antmicro"
			(at -0.95 -4.169 0)
			(layer "B.Fab")
			(hide yes)
			(effects
				(font
					(size 0.7 0.7)
					(thickness 0.15)
				)
				(justify right top mirror)
			)
		)
		(fp_text user "License: Apache-2.0"
			(at -0.95 -5.169 0)
			(layer "B.Fab")
			(hide yes)
			(effects
				(font
					(size 0.7 0.7)
					(thickness 0.15)
				)
				(justify right top mirror)
			)
		)
		(fp_text user "${REFERENCE}"
			(at -0.95 -3.168 0)
			(layer "B.Fab")
			(hide yes)
			(effects
				(font
					(size 0.7 0.7)
					(thickness 0.15)
				)
				(justify right top mirror)
			)
		)
		(pad "1" smd roundrect
			(at -0.48 0)
			(size 0.59 0.64)
			(layers "B.Cu" "B.Paste" "B.Mask")
			(roundrect_rratio 0.25)
			(net 573 "/Ethernet/TPL")
			(pintype "passive")
		)
		(pad "2" smd roundrect
			(at 0.48 0)
			(size 0.59 0.64)
			(layers "B.Cu" "B.Paste" "B.Mask")
			(roundrect_rratio 0.25)
			(net 105 "/Ethernet/VDD")
			(pintype "passive")
		)
	)
	(footprint "antmicro-footprints:R_0402_1005Metric"
		(layer "B.Cu")
		(at 108.15 106.9)
		(descr "Resistor SMD 0402")
		(tags "resistor SMD 0402")
		(property "Reference" "R23"
			(at -0.88 0.42 180)
			(layer "B.SilkS")
			(effects
				(font
					(size 0.7 0.7)
					(thickness 0.15)
				)
				(justify left bottom mirror)
			)
		)
		(property "Value" "R_0R_0402"
			(at 0 -1.4 180)
			(layer "B.Fab")
			(effects
				(font
					(size 0.7 0.7)
					(thickness 0.15)
				)
				(justify left bottom mirror)
			)
		)
		(property "Footprint" "antmicro-footprints:R_0402_1005Metric"
			(at 0 0 0)
			(layer "F.Fab")
			(hide yes)
			(effects
				(font
					(size 1.27 1.27)
					(thickness 0.15)
				)
			)
		)
		(property "Datasheet" "https://industrial.panasonic.com/cdbs/www-data/pdf/RDA0000/AOA0000C301.pdf"
			(at 0 0 0)
			(layer "F.Fab")
			(hide yes)
			(effects
				(font
					(size 1.27 1.27)
					(thickness 0.15)
				)
			)
		)
		(property "Author" "Antmicro"
			(at 0 0 0)
			(layer "B.Fab")
			(hide yes)
			(effects
				(font
					(size 1 1)
					(thickness 0.15)
				)
				(justify mirror)
			)
		)
		(property "Current" "1A"
			(at 0 0 0)
			(layer "B.Fab")
			(hide yes)
			(effects
				(font
					(size 1 1)
					(thickness 0.15)
				)
				(justify mirror)
			)
		)
		(property "License" "Apache-2.0"
			(at 0 0 0)
			(layer "B.Fab")
			(hide yes)
			(effects
				(font
					(size 1 1)
					(thickness 0.15)
				)
				(justify mirror)
			)
		)
		(property "MPN" "ERJ2GE0R00X"
			(at 0 0 0)
			(layer "B.Fab")
			(hide yes)
			(effects
				(font
					(size 1 1)
					(thickness 0.15)
				)
				(justify mirror)
			)
		)
		(property "Manufacturer" "Panasonic"
			(at 0 0 0)
			(layer "B.Fab")
			(hide yes)
			(effects
				(font
					(size 1 1)
					(thickness 0.15)
				)
				(justify mirror)
			)
		)
		(property "Tolerance" ""
			(at 0 0 0)
			(layer "B.Fab")
			(hide yes)
			(effects
				(font
					(size 1 1)
					(thickness 0.15)
				)
				(justify mirror)
			)
		)
		(property "Val" "0R"
			(at 0 0 0)
			(layer "B.Fab")
			(hide yes)
			(effects
				(font
					(size 1 1)
					(thickness 0.15)
				)
				(justify mirror)
			)
		)
		(sheetname "USB3")
		(sheetfile "usb3.kicad_sch")
		(attr smd exclude_from_pos_files exclude_from_bom dnp)
		(fp_rect
			(start -0.925 0.47)
			(end 0.925 -0.47)
			(stroke
				(width 0.05)
				(type default)
			)
			(fill none)
			(layer "B.CrtYd")
		)
		(fp_rect
			(start -0.5 0.25)
			(end 0.5 -0.25)
			(stroke
				(width 0.15)
				(type solid)
			)
			(fill none)
			(layer "B.Fab")
		)
		(fp_text user "${REFERENCE}"
			(at -0.95 -3.168 180)
			(layer "B.Fab")
			(hide yes)
			(effects
				(font
					(size 0.7 0.7)
					(thickness 0.15)
				)
				(justify left bottom mirror)
			)
		)
		(fp_text user "Author: Antmicro"
			(at -0.95 -4.169 180)
			(layer "B.Fab")
			(hide yes)
			(effects
				(font
					(size 0.7 0.7)
					(thickness 0.15)
				)
				(justify left bottom mirror)
			)
		)
		(fp_text user "License: Apache-2.0"
			(at -0.95 -5.169 180)
			(layer "B.Fab")
			(hide yes)
			(effects
				(font
					(size 0.7 0.7)
					(thickness 0.15)
				)
				(justify left bottom mirror)
			)
		)
		(pad "1" smd roundrect
			(at -0.48 0)
			(size 0.59 0.64)
			(layers "B.Cu" "B.Paste" "B.Mask")
			(roundrect_rratio 0.25)
			(net 284 "/USB3/USBC1_ID")
			(pintype "passive")
		)
		(pad "2" smd roundrect
			(at 0.48 0)
			(size 0.59 0.64)
			(layers "B.Cu" "B.Paste" "B.Mask")
			(roundrect_rratio 0.25)
			(net 116 "USB_FLASH_ID")
			(pintype "passive")
		)
	)
	(footprint "antmicro-footprints:XDFN-2_1x0.60mm"
		(layer "B.Cu")
		(at 126.25 127.15)
		(property "Reference" "D59"
			(at -1.35 -0.6 180)
			(layer "B.SilkS")
			(effects
				(font
					(size 0.7 0.7)
					(thickness 0.15)
				)
				(justify right bottom mirror)
			)
		)
		(property "Value" "TPD1E0B04_XDFN-2"
			(at 0 -1.5 180)
			(layer "B.Fab")
			(effects
				(font
					(size 0.7 0.7)
					(thickness 0.15)
				)
				(justify left bottom mirror)
			)
		)
		(property "Footprint" "antmicro-footprints:XDFN-2_1x0.60mm"
			(at 0 0 0)
			(layer "F.Fab")
			(hide yes)
			(effects
				(font
					(size 1.27 1.27)
					(thickness 0.15)
				)
			)
		)
		(property "Datasheet" "https://www.ti.com/general/docs/suppproductinfo.tsp?distId=26&gotoUrl=https://www.ti.com/lit/gpn/tpd1e0b04"
			(at 0 0 0)
			(layer "F.Fab")
			(hide yes)
			(effects
				(font
					(size 1.27 1.27)
					(thickness 0.15)
				)
			)
		)
		(property "MPN" "TPD1E0B04DPYR"
			(at 0 0 0)
			(layer "B.Fab")
			(hide yes)
			(effects
				(font
					(size 1 1)
					(thickness 0.15)
				)
				(justify mirror)
			)
		)
		(property "Manufacturer" "Texas Instruments"
			(at 0 0 0)
			(layer "B.Fab")
			(hide yes)
			(effects
				(font
					(size 1 1)
					(thickness 0.15)
				)
				(justify mirror)
			)
		)
		(property "Author" "Antmicro"
			(at 0 0 0)
			(layer "B.Fab")
			(hide yes)
			(effects
				(font
					(size 1 1)
					(thickness 0.15)
				)
				(justify mirror)
			)
		)
		(property "License" "Apache-2.0"
			(at 0 0 0)
			(layer "B.Fab")
			(hide yes)
			(effects
				(font
					(size 1 1)
					(thickness 0.15)
				)
				(justify mirror)
			)
		)
		(sheetname "Peripherals")
		(sheetfile "peripherals.kicad_sch")
		(attr smd)
		(fp_rect
			(start -0.725 0.475)
			(end 0.725 -0.475)
			(stroke
				(width 0.05)
				(type solid)
			)
			(fill none)
			(layer "B.CrtYd")
		)
		(fp_rect
			(start -0.55 0.35)
			(end 0.55 -0.35)
			(stroke
				(width 0.15)
				(type solid)
			)
			(fill none)
			(layer "B.Fab")
		)
		(fp_text user "${REFERENCE}"
			(at -0.8 -3.2 180)
			(layer "B.Fab")
			(hide yes)
			(effects
				(font
					(size 0.7 0.7)
					(thickness 0.15)
				)
				(justify left bottom mirror)
			)
		)
		(fp_text user "Author: Antmicro"
			(at -0.8 -4.4 180)
			(layer "B.Fab")
			(hide yes)
			(effects
				(font
					(size 0.7 0.7)
					(thickness 0.15)
				)
				(justify left bottom mirror)
			)
		)
		(fp_text user "License: Apache-2.0"
			(at -0.8 -5.6 180)
			(layer "B.Fab")
			(hide yes)
			(effects
				(font
					(size 0.7 0.7)
					(thickness 0.15)
				)
				(justify left bottom mirror)
			)
		)
		(pad "1" smd roundrect
			(at -0.351 0)
			(size 0.3 0.5)
			(layers "B.Cu" "B.Paste" "B.Mask")
			(roundrect_rratio 0.25)
			(net 1 "GND")
			(pinfunction "C")
			(pintype "passive")
		)
		(pad "2" smd roundrect
			(at 0.349 0)
			(size 0.3 0.5)
			(layers "B.Cu" "B.Paste" "B.Mask")
			(roundrect_rratio 0.25)
			(net 46 "USER_BTN1")
			(pinfunction "A")
			(pintype "passive")
		)
	)
	(footprint "antmicro-footprints:Fiducial_1mm_Mask2mm"
		(layer "B.Cu")
		(at 148.2 76.25 180)
		(descr "Circular Fiducial, 1mm bare copper, 3mm soldermask opening")
		(tags "fiducial")
		(property "Reference" "FID7"
			(at 0 1.4 0)
			(layer "B.SilkS")
			(hide yes)
			(effects
				(font
					(size 0.7 0.7)
					(thickness 0.15)
				)
				(justify left bottom mirror)
			)
		)
		(property "Value" "Fiducial_1mm_Mask2mm"
			(at 0 -2.2 0)
			(layer "B.Fab")
			(effects
				(font
					(size 0.7 0.7)
					(thickness 0.15)
				)
				(justify left bottom mirror)
			)
		)
		(property "Footprint" "antmicro-footprints:Fiducial_1mm_Mask2mm"
			(at 0 0 180)
			(layer "F.Fab")
			(hide yes)
			(effects
				(font
					(size 1.27 1.27)
					(thickness 0.15)
				)
			)
		)
		(attr board_only exclude_from_pos_files exclude_from_bom)
		(fp_circle
			(center 0 0)
			(end 1.24 0)
			(stroke
				(width 0.05)
				(type solid)
			)
			(fill none)
			(layer "B.CrtYd")
		)
		(fp_circle
			(center 0 0)
			(end 0.999 0)
			(stroke
				(width 0.15)
				(type solid)
			)
			(fill none)
			(layer "B.Fab")
		)
		(fp_text user "Author: Antmicro"
			(at -1.25 -5.803 0)
			(layer "B.Fab")
			(hide yes)
			(effects
				(font
					(size 0.7 0.7)
					(thickness 0.15)
				)
				(justify left bottom mirror)
			)
		)
		(fp_text user "${REFERENCE}"
			(at -1.25 -4.603 0)
			(layer "B.Fab")
			(hide yes)
			(effects
				(font
					(size 0.7 0.7)
					(thickness 0.15)
				)
				(justify left bottom mirror)
			)
		)
		(fp_text user "License: Apache-2.0"
			(at -1.25 -7.003 0)
			(layer "B.Fab")
			(hide yes)
			(effects
				(font
					(size 0.7 0.7)
					(thickness 0.15)
				)
				(justify left bottom mirror)
			)
		)
		(pad "" smd circle
			(at 0 0 180)
			(size 1 1)
			(layers "B.Cu" "B.Mask")
			(solder_mask_margin 0.5)
			(clearance 0.5)
		)
	)
	(footprint "antmicro-footprints:C_2220_5650Metric"
		(layer "B.Cu")
		(at 34.1 95.525 180)
		(descr "Capacitor SMD 2220")
		(tags "capacitor SMD 2220")
		(property "Reference" "C80"
			(at -4.51 1.72 90)
			(layer "B.SilkS")
			(effects
				(font
					(size 0.7 0.7)
					(thickness 0.15)
				)
				(justify left bottom mirror)
			)
		)
		(property "Value" "C_22u_100V_2220"
			(at 0 -3.9 0)
			(layer "B.Fab")
			(effects
				(font
					(size 0.7 0.7)
					(thickness 0.15)
				)
				(justify left bottom mirror)
			)
		)
		(property "Footprint" "antmicro-footprints:C_2220_5650Metric"
			(at 0 0 180)
			(layer "F.Fab")
			(hide yes)
			(effects
				(font
					(size 1.27 1.27)
					(thickness 0.15)
				)
			)
		)
		(property "Datasheet" "https://product.tdk.com/en/search/capacitor/ceramic/mlcc/info?part_no=C5750X7S2A226M280KB"
			(at 0 0 180)
			(layer "F.Fab")
			(hide yes)
			(effects
				(font
					(size 1.27 1.27)
					(thickness 0.15)
				)
			)
		)
		(property "Author" "Antmicro"
			(at 68.2 191.05 0)
			(layer "B.Fab")
			(hide yes)
			(effects
				(font
					(size 1 1)
					(thickness 0.15)
				)
				(justify mirror)
			)
		)
		(property "Dielectric" "X7S"
			(at 68.2 191.05 0)
			(layer "B.Fab")
			(hide yes)
			(effects
				(font
					(size 1 1)
					(thickness 0.15)
				)
				(justify mirror)
			)
		)
		(property "License" "Apache-2.0"
			(at 68.2 191.05 0)
			(layer "B.Fab")
			(hide yes)
			(effects
				(font
					(size 1 1)
					(thickness 0.15)
				)
				(justify mirror)
			)
		)
		(property "MPN" "C5750X7S2A226M280KB"
			(at 68.2 191.05 0)
			(layer "B.Fab")
			(hide yes)
			(effects
				(font
					(size 1 1)
					(thickness 0.15)
				)
				(justify mirror)
			)
		)
		(property "Manufacturer" "TDK"
			(at 68.2 191.05 0)
			(layer "B.Fab")
			(hide yes)
			(effects
				(font
					(size 1 1)
					(thickness 0.15)
				)
				(justify mirror)
			)
		)
		(property "Public" "False"
			(at 68.2 191.05 0)
			(layer "B.Fab")
			(hide yes)
			(effects
				(font
					(size 1 1)
					(thickness 0.15)
				)
				(justify mirror)
			)
		)
		(property "Val" "22u"
			(at 68.2 191.05 0)
			(layer "B.Fab")
			(hide yes)
			(effects
				(font
					(size 1 1)
					(thickness 0.15)
				)
				(justify mirror)
			)
		)
		(property "Voltage" "100V"
			(at 68.2 191.05 0)
			(layer "B.Fab")
			(hide yes)
			(effects
				(font
					(size 1 1)
					(thickness 0.15)
				)
				(justify mirror)
			)
		)
		(sheetname "Ethernet")
		(sheetfile "ethernet.kicad_sch")
		(attr smd)
		(fp_line
			(start 1.415 2.61)
			(end -1.415 2.61)
			(stroke
				(width 0.15)
				(type solid)
			)
			(layer "B.SilkS")
		)
		(fp_line
			(start 1.415 -2.61)
			(end -1.415 -2.61)
			(stroke
				(width 0.15)
				(type solid)
			)
			(layer "B.SilkS")
		)
		(fp_rect
			(start -3.7 2.95)
			(end 3.7 -2.95)
			(stroke
				(width 0.05)
				(type solid)
			)
			(fill none)
			(layer "B.CrtYd")
		)
		(fp_rect
			(start -2.85 2.5)
			(end 2.85 -2.5)
			(stroke
				(width 0.15)
				(type solid)
			)
			(fill none)
			(layer "B.Fab")
		)
		(fp_text user "Author: Antmicro"
			(at -3.7 -7.9 0)
			(layer "B.Fab")
			(hide yes)
			(effects
				(font
					(size 0.7 0.7)
					(thickness 0.15)
				)
				(justify left bottom mirror)
			)
		)
		(fp_text user "License: Apache-2.0"
			(at -3.7 -6.9 0)
			(layer "B.Fab")
			(hide yes)
			(effects
				(font
					(size 0.7 0.7)
					(thickness 0.15)
				)
				(justify left bottom mirror)
			)
		)
		(fp_text user "${REFERENCE}"
			(at -3.7 -5.9 0)
			(layer "B.Fab")
			(hide yes)
			(effects
				(font
					(size 0.7 0.7)
					(thickness 0.15)
				)
				(justify left bottom mirror)
			)
		)
		(pad "1" smd roundrect
			(at -2.55 0 180)
			(size 1.8 5.4)
			(layers "B.Cu" "B.Paste" "B.Mask")
			(roundrect_rratio 0.138889)
			(net 106 "GNDD")
			(pintype "passive")
		)
		(pad "2" smd roundrect
			(at 2.55 0 180)
			(size 1.8 5.4)
			(layers "B.Cu" "B.Paste" "B.Mask")
			(roundrect_rratio 0.138889)
			(net 105 "/Ethernet/VDD")
			(pintype "passive")
		)
	)
	(footprint "antmicro-footprints:C_0402_1005Metric"
		(layer "B.Cu")
		(at 96.5 84.75)
		(descr "Capacitor SMD 0402")
		(tags "capacitor SMD 0402")
		(property "Reference" "C90"
			(at 1.16 1.21 180)
			(layer "B.SilkS")
			(effects
				(font
					(size 0.7 0.7)
					(thickness 0.15)
				)
				(justify left bottom mirror)
			)
		)
		(property "Value" "C_100n_0402"
			(at 0 -1.4 180)
			(layer "B.Fab")
			(effects
				(font
					(size 0.7 0.7)
					(thickness 0.15)
				)
				(justify left bottom mirror)
			)
		)
		(property "Footprint" "antmicro-footprints:C_0402_1005Metric"
			(at 0 0 0)
			(layer "F.Fab")
			(hide yes)
			(effects
				(font
					(size 1.27 1.27)
					(thickness 0.15)
				)
			)
		)
		(property "Datasheet" "https://www.murata.com/products/productdetail?partno=GRM155R61H104KE14%23"
			(at 0 0 0)
			(layer "F.Fab")
			(hide yes)
			(effects
				(font
					(size 1.27 1.27)
					(thickness 0.15)
				)
			)
		)
		(property "Author" "Antmicro"
			(at 0 0 0)
			(layer "B.Fab")
			(hide yes)
			(effects
				(font
					(size 1 1)
					(thickness 0.15)
				)
				(justify mirror)
			)
		)
		(property "Dielectric" "X5R"
			(at 0 0 0)
			(layer "B.Fab")
			(hide yes)
			(effects
				(font
					(size 1 1)
					(thickness 0.15)
				)
				(justify mirror)
			)
		)
		(property "License" "Apache-2.0"
			(at 0 0 0)
			(layer "B.Fab")
			(hide yes)
			(effects
				(font
					(size 1 1)
					(thickness 0.15)
				)
				(justify mirror)
			)
		)
		(property "MPN" "GRM155R61H104KE14D"
			(at 0 0 0)
			(layer "B.Fab")
			(hide yes)
			(effects
				(font
					(size 1 1)
					(thickness 0.15)
				)
				(justify mirror)
			)
		)
		(property "Manufacturer" "Murata"
			(at 0 0 0)
			(layer "B.Fab")
			(hide yes)
			(effects
				(font
					(size 1 1)
					(thickness 0.15)
				)
				(justify mirror)
			)
		)
		(property "Val" "100n"
			(at 0 0 0)
			(layer "B.Fab")
			(hide yes)
			(effects
				(font
					(size 1 1)
					(thickness 0.15)
				)
				(justify mirror)
			)
		)
		(property "Voltage" "50V"
			(at 0 0 0)
			(layer "B.Fab")
			(hide yes)
			(effects
				(font
					(size 1 1)
					(thickness 0.15)
				)
				(justify mirror)
			)
		)
		(sheetname "CSI")
		(sheetfile "csi.kicad_sch")
		(attr smd)
		(fp_rect
			(start -0.925 0.47)
			(end 0.925 -0.47)
			(stroke
				(width 0.05)
				(type default)
			)
			(fill none)
			(layer "B.CrtYd")
		)
		(fp_line
			(start -0.494 -0.248)
			(end 0.504 -0.248)
			(stroke
				(width 0.15)
				(type solid)
			)
			(layer "B.Fab")
		)
		(fp_line
			(start -0.494 0.25)
			(end -0.494 -0.248)
			(stroke
				(width 0.15)
				(type solid)
			)
			(layer "B.Fab")
		)
		(fp_line
			(start 0.504 -0.248)
			(end 0.504 0.25)
			(stroke
				(width 0.15)
				(type solid)
			)
			(layer "B.Fab")
		)
		(fp_line
			(start 0.504 0.25)
			(end -0.494 0.25)
			(stroke
				(width 0.15)
				(type solid)
			)
			(layer "B.Fab")
		)
		(fp_text user "Author: Antmicro"
			(at -0.932 -4.17 180)
			(layer "B.Fab")
			(hide yes)
			(effects
				(font
					(size 0.7 0.7)
					(thickness 0.15)
				)
				(justify left bottom mirror)
			)
		)
		(fp_text user "License: Apache-2.0"
			(at -0.932 -5.17 180)
			(layer "B.Fab")
			(hide yes)
			(effects
				(font
					(size 0.7 0.7)
					(thickness 0.15)
				)
				(justify left bottom mirror)
			)
		)
		(fp_text user "${REFERENCE}"
			(at -0.932 -3.168 180)
			(layer "B.Fab")
			(hide yes)
			(effects
				(font
					(size 0.7 0.7)
					(thickness 0.15)
				)
				(justify left bottom mirror)
			)
		)
		(pad "1" smd roundrect
			(at -0.48 0)
			(size 0.59 0.64)
			(layers "B.Cu" "B.Paste" "B.Mask")
			(roundrect_rratio 0.25)
			(net 99 "+5V")
			(pintype "passive")
		)
		(pad "2" smd roundrect
			(at 0.48 0)
			(size 0.59 0.64)
			(layers "B.Cu" "B.Paste" "B.Mask")
			(roundrect_rratio 0.25)
			(net 1 "GND")
			(pintype "passive")
		)
	)
	(footprint "antmicro-footprints:R_0402_1005Metric"
		(layer "B.Cu")
		(at 135.8 98.4)
		(descr "Resistor SMD 0402")
		(tags "resistor SMD 0402")
		(property "Reference" "R12"
			(at -0.75 0.45 180)
			(layer "B.SilkS")
			(effects
				(font
					(size 0.7 0.7)
					(thickness 0.15)
				)
				(justify left bottom mirror)
			)
		)
		(property "Value" "R_0R_0402"
			(at 0 -1.4 180)
			(layer "B.Fab")
			(effects
				(font
					(size 0.7 0.7)
					(thickness 0.15)
				)
				(justify left bottom mirror)
			)
		)
		(property "Footprint" "antmicro-footprints:R_0402_1005Metric"
			(at 0 0 0)
			(layer "F.Fab")
			(hide yes)
			(effects
				(font
					(size 1.27 1.27)
					(thickness 0.15)
				)
			)
		)
		(property "Datasheet" "https://industrial.panasonic.com/cdbs/www-data/pdf/RDA0000/AOA0000C301.pdf"
			(at 0 0 0)
			(layer "F.Fab")
			(hide yes)
			(effects
				(font
					(size 1.27 1.27)
					(thickness 0.15)
				)
			)
		)
		(property "Author" "Antmicro"
			(at 0 0 0)
			(layer "B.Fab")
			(hide yes)
			(effects
				(font
					(size 1 1)
					(thickness 0.15)
				)
				(justify mirror)
			)
		)
		(property "Current" "1A"
			(at 0 0 0)
			(layer "B.Fab")
			(hide yes)
			(effects
				(font
					(size 1 1)
					(thickness 0.15)
				)
				(justify mirror)
			)
		)
		(property "License" "Apache-2.0"
			(at 0 0 0)
			(layer "B.Fab")
			(hide yes)
			(effects
				(font
					(size 1 1)
					(thickness 0.15)
				)
				(justify mirror)
			)
		)
		(property "MPN" "ERJ2GE0R00X"
			(at 0 0 0)
			(layer "B.Fab")
			(hide yes)
			(effects
				(font
					(size 1 1)
					(thickness 0.15)
				)
				(justify mirror)
			)
		)
		(property "Manufacturer" "Panasonic"
			(at 0 0 0)
			(layer "B.Fab")
			(hide yes)
			(effects
				(font
					(size 1 1)
					(thickness 0.15)
				)
				(justify mirror)
			)
		)
		(property "Tolerance" ""
			(at 0 0 0)
			(layer "B.Fab")
			(hide yes)
			(effects
				(font
					(size 1 1)
					(thickness 0.15)
				)
				(justify mirror)
			)
		)
		(property "Val" "0R"
			(at 0 0 0)
			(layer "B.Fab")
			(hide yes)
			(effects
				(font
					(size 1 1)
					(thickness 0.15)
				)
				(justify mirror)
			)
		)
		(sheetname "SoM")
		(sheetfile "som.kicad_sch")
		(attr smd)
		(fp_rect
			(start -0.925 0.47)
			(end 0.925 -0.47)
			(stroke
				(width 0.05)
				(type default)
			)
			(fill none)
			(layer "B.CrtYd")
		)
		(fp_rect
			(start -0.5 0.25)
			(end 0.5 -0.25)
			(stroke
				(width 0.15)
				(type solid)
			)
			(fill none)
			(layer "B.Fab")
		)
		(fp_text user "License: Apache-2.0"
			(at -0.95 -5.169 180)
			(layer "B.Fab")
			(hide yes)
			(effects
				(font
					(size 0.7 0.7)
					(thickness 0.15)
				)
				(justify left bottom mirror)
			)
		)
		(fp_text user "${REFERENCE}"
			(at -0.95 -3.168 180)
			(layer "B.Fab")
			(hide yes)
			(effects
				(font
					(size 0.7 0.7)
					(thickness 0.15)
				)
				(justify left bottom mirror)
			)
		)
		(fp_text user "Author: Antmicro"
			(at -0.95 -4.169 180)
			(layer "B.Fab")
			(hide yes)
			(effects
				(font
					(size 0.7 0.7)
					(thickness 0.15)
				)
				(justify left bottom mirror)
			)
		)
		(pad "1" smd roundrect
			(at -0.48 0)
			(size 0.59 0.64)
			(layers "B.Cu" "B.Paste" "B.Mask")
			(roundrect_rratio 0.25)
			(net 743 "Net-(J15B-CAM0_PWDN)")
			(pintype "passive")
		)
		(pad "2" smd roundrect
			(at 0.48 0)
			(size 0.59 0.64)
			(layers "B.Cu" "B.Paste" "B.Mask")
			(roundrect_rratio 0.25)
			(net 217 "VSYNC_CAM0")
			(pintype "passive")
		)
	)
	(footprint "antmicro-footprints:R_0603_1608Metric"
		(layer "B.Cu")
		(at 70.9 79.4 180)
		(descr "Resistor SMD 0603")
		(tags "resistor SMD 0603")
		(property "Reference" "R273"
			(at -2.74 0.66 0)
			(layer "B.SilkS")
			(effects
				(font
					(size 0.7 0.7)
					(thickness 0.15)
				)
				(justify left bottom mirror)
			)
		)
		(property "Value" "R_0R_0603"
			(at 0 -1.6 0)
			(layer "B.Fab")
			(effects
				(font
					(size 0.7 0.7)
					(thickness 0.15)
				)
				(justify left bottom mirror)
			)
		)
		(property "Footprint" "antmicro-footprints:R_0603_1608Metric"
			(at 0 0 180)
			(layer "F.Fab")
			(hide yes)
			(effects
				(font
					(size 1.27 1.27)
					(thickness 0.15)
				)
			)
		)
		(property "Datasheet" "https://www.bourns.com/docs/product-datasheets/cr.pdf?sfvrsn=574d41f6_14"
			(at 0 0 180)
			(layer "F.Fab")
			(hide yes)
			(effects
				(font
					(size 1.27 1.27)
					(thickness 0.15)
				)
			)
		)
		(property "Author" "Antmicro"
			(at 141.8 158.8 0)
			(layer "B.Fab")
			(hide yes)
			(effects
				(font
					(size 1 1)
					(thickness 0.15)
				)
				(justify mirror)
			)
		)
		(property "Current" "1A"
			(at 141.8 158.8 0)
			(layer "B.Fab")
			(hide yes)
			(effects
				(font
					(size 1 1)
					(thickness 0.15)
				)
				(justify mirror)
			)
		)
		(property "License" "Apache-2.0"
			(at 141.8 158.8 0)
			(layer "B.Fab")
			(hide yes)
			(effects
				(font
					(size 1 1)
					(thickness 0.15)
				)
				(justify mirror)
			)
		)
		(property "MPN" "CR0603-J/-000ELF"
			(at 141.8 158.8 0)
			(layer "B.Fab")
			(hide yes)
			(effects
				(font
					(size 1 1)
					(thickness 0.15)
				)
				(justify mirror)
			)
		)
		(property "Manufacturer" "Bourns"
			(at 141.8 158.8 0)
			(layer "B.Fab")
			(hide yes)
			(effects
				(font
					(size 1 1)
					(thickness 0.15)
				)
				(justify mirror)
			)
		)
		(property "Tolerance" ""
			(at 141.8 158.8 0)
			(layer "B.Fab")
			(hide yes)
			(effects
				(font
					(size 1 1)
					(thickness 0.15)
				)
				(justify mirror)
			)
		)
		(property "Val" "0R"
			(at 141.8 158.8 0)
			(layer "B.Fab")
			(hide yes)
			(effects
				(font
					(size 1 1)
					(thickness 0.15)
				)
				(justify mirror)
			)
		)
		(sheetname "Supply")
		(sheetfile "supply.kicad_sch")
		(attr smd)
		(fp_line
			(start 0.15 0.4)
			(end -0.15 0.4)
			(stroke
				(width 0.15)
				(type solid)
			)
			(layer "B.SilkS")
		)
		(fp_line
			(start 0.15 -0.4)
			(end -0.15 -0.4)
			(stroke
				(width 0.15)
				(type solid)
			)
			(layer "B.SilkS")
		)
		(fp_rect
			(start -1.25 0.65)
			(end 1.25 -0.65)
			(stroke
				(width 0.05)
				(type solid)
			)
			(fill none)
			(layer "B.CrtYd")
		)
		(fp_rect
			(start -0.8 0.4)
			(end 0.8 -0.4)
			(stroke
				(width 0.15)
				(type solid)
			)
			(fill none)
			(layer "B.Fab")
		)
		(fp_text user "${REFERENCE}"
			(at -1.25 -3.898 0)
			(layer "B.Fab")
			(hide yes)
			(effects
				(font
					(size 0.7 0.7)
					(thickness 0.15)
				)
				(justify left bottom mirror)
			)
		)
		(fp_text user "Author: Antmicro"
			(at -1.25 -4.9 0)
			(layer "B.Fab")
			(hide yes)
			(effects
				(font
					(size 0.7 0.7)
					(thickness 0.15)
				)
				(justify left bottom mirror)
			)
		)
		(fp_text user "License: Apache-2.0"
			(at -1.25 -5.9 0)
			(layer "B.Fab")
			(hide yes)
			(effects
				(font
					(size 0.7 0.7)
					(thickness 0.15)
				)
				(justify left bottom mirror)
			)
		)
		(pad "1" smd roundrect
			(at -0.7 0 180)
			(size 0.8 1)
			(layers "B.Cu" "B.Paste" "B.Mask")
			(roundrect_rratio 0.2)
			(net 138 "/Supply/3V3_LDO")
			(pintype "passive")
		)
		(pad "2" smd roundrect
			(at 0.7 0 180)
			(size 0.8 1)
			(layers "B.Cu" "B.Paste" "B.Mask")
			(roundrect_rratio 0.2)
			(net 117 "3V3_STDB")
			(pintype "passive")
		)
	)
	(footprint "antmicro-footprints:TP_SMD_0.75mm"
		(layer "B.Cu")
		(at 100.14999 103.5508 180)
		(property "Reference" "TP41"
			(at 0 0.6 0)
			(layer "B.SilkS")
			(hide yes)
			(effects
				(font
					(size 0.7 0.7)
					(thickness 0.15)
				)
				(justify left bottom mirror)
			)
		)
		(property "Value" "TP_0.75mm_SMD"
			(at 0 -1.2 0)
			(layer "B.Fab")
			(effects
				(font
					(size 0.7 0.7)
					(thickness 0.15)
				)
				(justify left bottom mirror)
			)
		)
		(property "Footprint" "antmicro-footprints:TP_SMD_0.75mm"
			(at 0 0 180)
			(layer "F.Fab")
			(hide yes)
			(effects
				(font
					(size 1.27 1.27)
					(thickness 0.15)
				)
			)
		)
		(property "Author" "Antmicro"
			(at 200.29998 207.1016 0)
			(layer "B.Fab")
			(hide yes)
			(effects
				(font
					(size 1 1)
					(thickness 0.15)
				)
				(justify mirror)
			)
		)
		(property "License" "Apache-2.0"
			(at 200.29998 207.1016 0)
			(layer "B.Fab")
			(hide yes)
			(effects
				(font
					(size 1 1)
					(thickness 0.15)
				)
				(justify mirror)
			)
		)
		(property "MPN" ""
			(at 200.29998 207.1016 0)
			(layer "B.Fab")
			(hide yes)
			(effects
				(font
					(size 1 1)
					(thickness 0.15)
				)
				(justify mirror)
			)
		)
		(property "Manufacturer" ""
			(at 200.29998 207.1016 0)
			(layer "B.Fab")
			(hide yes)
			(effects
				(font
					(size 1 1)
					(thickness 0.15)
				)
				(justify mirror)
			)
		)
		(sheetname "CSI")
		(sheetfile "csi.kicad_sch")
		(attr exclude_from_pos_files exclude_from_bom)
		(fp_circle
			(center 0 0)
			(end 0.475 0)
			(stroke
				(width 0.05)
				(type default)
			)
			(fill none)
			(layer "B.CrtYd")
		)
		(fp_text user "License: Apache-2.0"
			(at -0.4 -5.101 0)
			(layer "B.Fab")
			(hide yes)
			(effects
				(font
					(size 0.7 0.7)
					(thickness 0.15)
				)
				(justify left bottom mirror)
			)
		)
		(fp_text user "Author: Antmicro"
			(at -0.4 -3.901 0)
			(layer "B.Fab")
			(hide yes)
			(effects
				(font
					(size 0.7 0.7)
					(thickness 0.15)
				)
				(justify left bottom mirror)
			)
		)
		(fp_text user "${REFERENCE}"
			(at -0.4 -2.7 0)
			(layer "B.Fab")
			(hide yes)
			(effects
				(font
					(size 0.7 0.7)
					(thickness 0.15)
				)
				(justify left bottom mirror)
			)
		)
		(pad "1" smd circle
			(at 0 0 180)
			(size 0.75 0.75)
			(layers "B.Cu" "B.Mask")
			(net 542 "/CSI/MUX_I2C_6_SCL")
			(pinfunction "1")
			(pintype "passive")
		)
	)
	(footprint "antmicro-footprints:C_0402_1005Metric"
		(layer "B.Cu")
		(at 90.025 82.55)
		(descr "Capacitor SMD 0402")
		(tags "capacitor SMD 0402")
		(property "Reference" "C139"
			(at -0.875 0.47 180)
			(layer "B.SilkS")
			(effects
				(font
					(size 0.7 0.7)
					(thickness 0.15)
				)
				(justify left bottom mirror)
			)
		)
		(property "Value" "C_100n_0402"
			(at 0 -1.4 180)
			(layer "B.Fab")
			(effects
				(font
					(size 0.7 0.7)
					(thickness 0.15)
				)
				(justify left bottom mirror)
			)
		)
		(property "Footprint" "antmicro-footprints:C_0402_1005Metric"
			(at 0 0 0)
			(layer "F.Fab")
			(hide yes)
			(effects
				(font
					(size 1.27 1.27)
					(thickness 0.15)
				)
			)
		)
		(property "Datasheet" "https://www.murata.com/products/productdetail?partno=GRM155R61H104KE14%23"
			(at 0 0 0)
			(layer "F.Fab")
			(hide yes)
			(effects
				(font
					(size 1.27 1.27)
					(thickness 0.15)
				)
			)
		)
		(property "Author" "Antmicro"
			(at 0 0 0)
			(layer "B.Fab")
			(hide yes)
			(effects
				(font
					(size 1 1)
					(thickness 0.15)
				)
				(justify mirror)
			)
		)
		(property "Dielectric" "X5R"
			(at 0 0 0)
			(layer "B.Fab")
			(hide yes)
			(effects
				(font
					(size 1 1)
					(thickness 0.15)
				)
				(justify mirror)
			)
		)
		(property "License" "Apache-2.0"
			(at 0 0 0)
			(layer "B.Fab")
			(hide yes)
			(effects
				(font
					(size 1 1)
					(thickness 0.15)
				)
				(justify mirror)
			)
		)
		(property "MPN" "GRM155R61H104KE14D"
			(at 0 0 0)
			(layer "B.Fab")
			(hide yes)
			(effects
				(font
					(size 1 1)
					(thickness 0.15)
				)
				(justify mirror)
			)
		)
		(property "Manufacturer" "Murata"
			(at 0 0 0)
			(layer "B.Fab")
			(hide yes)
			(effects
				(font
					(size 1 1)
					(thickness 0.15)
				)
				(justify mirror)
			)
		)
		(property "Val" "100n"
			(at 0 0 0)
			(layer "B.Fab")
			(hide yes)
			(effects
				(font
					(size 1 1)
					(thickness 0.15)
				)
				(justify mirror)
			)
		)
		(property "Voltage" "50V"
			(at 0 0 0)
			(layer "B.Fab")
			(hide yes)
			(effects
				(font
					(size 1 1)
					(thickness 0.15)
				)
				(justify mirror)
			)
		)
		(sheetname "HDMI")
		(sheetfile "hdmi.kicad_sch")
		(attr smd)
		(fp_rect
			(start -0.925 0.47)
			(end 0.925 -0.47)
			(stroke
				(width 0.05)
				(type default)
			)
			(fill none)
			(layer "B.CrtYd")
		)
		(fp_line
			(start -0.494 -0.248)
			(end 0.504 -0.248)
			(stroke
				(width 0.15)
				(type solid)
			)
			(layer "B.Fab")
		)
		(fp_line
			(start -0.494 0.25)
			(end -0.494 -0.248)
			(stroke
				(width 0.15)
				(type solid)
			)
			(layer "B.Fab")
		)
		(fp_line
			(start 0.504 -0.248)
			(end 0.504 0.25)
			(stroke
				(width 0.15)
				(type solid)
			)
			(layer "B.Fab")
		)
		(fp_line
			(start 0.504 0.25)
			(end -0.494 0.25)
			(stroke
				(width 0.15)
				(type solid)
			)
			(layer "B.Fab")
		)
		(fp_text user "${REFERENCE}"
			(at -0.932 -3.168 180)
			(layer "B.Fab")
			(hide yes)
			(effects
				(font
					(size 0.7 0.7)
					(thickness 0.15)
				)
				(justify left bottom mirror)
			)
		)
		(fp_text user "Author: Antmicro"
			(at -0.932 -4.17 180)
			(layer "B.Fab")
			(hide yes)
			(effects
				(font
					(size 0.7 0.7)
					(thickness 0.15)
				)
				(justify left bottom mirror)
			)
		)
		(fp_text user "License: Apache-2.0"
			(at -0.932 -5.17 180)
			(layer "B.Fab")
			(hide yes)
			(effects
				(font
					(size 0.7 0.7)
					(thickness 0.15)
				)
				(justify left bottom mirror)
			)
		)
		(pad "1" smd roundrect
			(at -0.48 0)
			(size 0.59 0.64)
			(layers "B.Cu" "B.Paste" "B.Mask")
			(roundrect_rratio 0.25)
			(net 36 "DP1_AUX_P")
			(pintype "passive")
		)
		(pad "2" smd roundrect
			(at 0.48 0)
			(size 0.59 0.64)
			(layers "B.Cu" "B.Paste" "B.Mask")
			(roundrect_rratio 0.25)
			(net 669 "/HDMI/DP_MUX_AUX_B+")
			(pintype "passive")
		)
	)
	(footprint "antmicro-footprints:R_0402_1005Metric"
		(layer "B.Cu")
		(at 103.25 113.5 -90)
		(descr "Resistor SMD 0402")
		(tags "resistor SMD 0402")
		(property "Reference" "R128"
			(at -1.4 0.45 90)
			(layer "B.SilkS")
			(effects
				(font
					(size 0.7 0.7)
					(thickness 0.15)
				)
				(justify left bottom mirror)
			)
		)
		(property "Value" "R_887k_0402"
			(at 0 -1.4 90)
			(layer "B.Fab")
			(effects
				(font
					(size 0.7 0.7)
					(thickness 0.15)
				)
				(justify left bottom mirror)
			)
		)
		(property "Footprint" "antmicro-footprints:R_0402_1005Metric"
			(at 0 0 -90)
			(layer "F.Fab")
			(hide yes)
			(effects
				(font
					(size 1.27 1.27)
					(thickness 0.15)
				)
			)
		)
		(property "Datasheet" "https://eu.mouser.com/datasheet/2/315/AOA0000C304-1149620.pdf"
			(at 0 0 -90)
			(layer "F.Fab")
			(hide yes)
			(effects
				(font
					(size 1.27 1.27)
					(thickness 0.15)
				)
			)
		)
		(property "Author" "Antmicro"
			(at -10.25 216.75 0)
			(layer "B.Fab")
			(hide yes)
			(effects
				(font
					(size 1 1)
					(thickness 0.15)
				)
				(justify mirror)
			)
		)
		(property "License" "Apache-2.0"
			(at -10.25 216.75 0)
			(layer "B.Fab")
			(hide yes)
			(effects
				(font
					(size 1 1)
					(thickness 0.15)
				)
				(justify mirror)
			)
		)
		(property "MPN" "ERJ-2RKF8873X"
			(at -10.25 216.75 0)
			(layer "B.Fab")
			(hide yes)
			(effects
				(font
					(size 1 1)
					(thickness 0.15)
				)
				(justify mirror)
			)
		)
		(property "Manufacturer" "Panasonic"
			(at -10.25 216.75 0)
			(layer "B.Fab")
			(hide yes)
			(effects
				(font
					(size 1 1)
					(thickness 0.15)
				)
				(justify mirror)
			)
		)
		(property "Tolerance" "1%"
			(at -10.25 216.75 0)
			(layer "B.Fab")
			(hide yes)
			(effects
				(font
					(size 1 1)
					(thickness 0.15)
				)
				(justify mirror)
			)
		)
		(property "Val" "887k"
			(at -10.25 216.75 0)
			(layer "B.Fab")
			(hide yes)
			(effects
				(font
					(size 1 1)
					(thickness 0.15)
				)
				(justify mirror)
			)
		)
		(sheetname "USB3")
		(sheetfile "usb3.kicad_sch")
		(attr smd)
		(fp_rect
			(start -0.925 0.47)
			(end 0.925 -0.47)
			(stroke
				(width 0.05)
				(type default)
			)
			(fill none)
			(layer "B.CrtYd")
		)
		(fp_rect
			(start -0.5 0.25)
			(end 0.5 -0.25)
			(stroke
				(width 0.15)
				(type solid)
			)
			(fill none)
			(layer "B.Fab")
		)
		(fp_text user "${REFERENCE}"
			(at -0.95 -3.168 90)
			(layer "B.Fab")
			(hide yes)
			(effects
				(font
					(size 0.7 0.7)
					(thickness 0.15)
				)
				(justify left bottom mirror)
			)
		)
		(fp_text user "License: Apache-2.0"
			(at -0.95 -5.169 90)
			(layer "B.Fab")
			(hide yes)
			(effects
				(font
					(size 0.7 0.7)
					(thickness 0.15)
				)
				(justify left bottom mirror)
			)
		)
		(fp_text user "Author: Antmicro"
			(at -0.95 -4.169 90)
			(layer "B.Fab")
			(hide yes)
			(effects
				(font
					(size 0.7 0.7)
					(thickness 0.15)
				)
				(justify left bottom mirror)
			)
		)
		(pad "1" smd roundrect
			(at -0.48 0 270)
			(size 0.59 0.64)
			(layers "B.Cu" "B.Paste" "B.Mask")
			(roundrect_rratio 0.25)
			(net 365 "/USB3/USBC1_VBUS_DET")
			(pintype "passive")
		)
		(pad "2" smd roundrect
			(at 0.48 0 270)
			(size 0.59 0.64)
			(layers "B.Cu" "B.Paste" "B.Mask")
			(roundrect_rratio 0.25)
			(net 270 "/USB3/USBC1_VBUS")
			(pintype "passive")
		)
	)
	(footprint "antmicro-footprints:C_0402_1005Metric"
		(layer "B.Cu")
		(at 47.54 111.25 -90)
		(descr "Capacitor SMD 0402")
		(tags "capacitor SMD 0402")
		(property "Reference" "C158"
			(at -2 0.7 -90)
			(layer "B.SilkS")
			(effects
				(font
					(size 0.7 0.7)
					(thickness 0.15)
				)
				(justify left bottom mirror)
			)
		)
		(property "Value" "C_100n_0402"
			(at -1.022927 -2.155213 90)
			(layer "B.Fab")
			(effects
				(font
					(size 0.7 0.7)
					(thickness 0.15)
				)
				(justify left bottom mirror)
			)
		)
		(property "Footprint" "antmicro-footprints:C_0402_1005Metric"
			(at 0 0 -90)
			(layer "F.Fab")
			(hide yes)
			(effects
				(font
					(size 1.27 1.27)
					(thickness 0.15)
				)
			)
		)
		(property "Datasheet" "https://www.murata.com/products/productdetail?partno=GRM155R61H104KE14%23"
			(at 0 0 -90)
			(layer "F.Fab")
			(hide yes)
			(effects
				(font
					(size 1.27 1.27)
					(thickness 0.15)
				)
			)
		)
		(property "Author" "Antmicro"
			(at -63.71 158.79 0)
			(layer "B.Fab")
			(hide yes)
			(effects
				(font
					(size 1 1)
					(thickness 0.15)
				)
				(justify mirror)
			)
		)
		(property "Dielectric" "X5R"
			(at -63.71 158.79 0)
			(layer "B.Fab")
			(hide yes)
			(effects
				(font
					(size 1 1)
					(thickness 0.15)
				)
				(justify mirror)
			)
		)
		(property "License" "Apache-2.0"
			(at -63.71 158.79 0)
			(layer "B.Fab")
			(hide yes)
			(effects
				(font
					(size 1 1)
					(thickness 0.15)
				)
				(justify mirror)
			)
		)
		(property "MPN" "GRM155R61H104KE14D"
			(at -63.71 158.79 0)
			(layer "B.Fab")
			(hide yes)
			(effects
				(font
					(size 1 1)
					(thickness 0.15)
				)
				(justify mirror)
			)
		)
		(property "Manufacturer" "Murata"
			(at -63.71 158.79 0)
			(layer "B.Fab")
			(hide yes)
			(effects
				(font
					(size 1 1)
					(thickness 0.15)
				)
				(justify mirror)
			)
		)
		(property "Val" "100n"
			(at -63.71 158.79 0)
			(layer "B.Fab")
			(hide yes)
			(effects
				(font
					(size 1 1)
					(thickness 0.15)
				)
				(justify mirror)
			)
		)
		(property "Voltage" "50V"
			(at -63.71 158.79 0)
			(layer "B.Fab")
			(hide yes)
			(effects
				(font
					(size 1 1)
					(thickness 0.15)
				)
				(justify mirror)
			)
		)
		(sheetname "USB Debug, DP")
		(sheetfile "usb.kicad_sch")
		(attr smd)
		(fp_rect
			(start -0.925 0.47)
			(end 0.925 -0.47)
			(stroke
				(width 0.05)
				(type default)
			)
			(fill none)
			(layer "B.CrtYd")
		)
		(fp_line
			(start -0.494 0.25)
			(end -0.494 -0.248)
			(stroke
				(width 0.15)
				(type solid)
			)
			(layer "B.Fab")
		)
		(fp_line
			(start 0.504 0.25)
			(end -0.494 0.25)
			(stroke
				(width 0.15)
				(type solid)
			)
			(layer "B.Fab")
		)
		(fp_line
			(start -0.494 -0.248)
			(end 0.504 -0.248)
			(stroke
				(width 0.15)
				(type solid)
			)
			(layer "B.Fab")
		)
		(fp_line
			(start 0.504 -0.248)
			(end 0.504 0.25)
			(stroke
				(width 0.15)
				(type solid)
			)
			(layer "B.Fab")
		)
		(fp_text user "Author: Antmicro"
			(at -0.939 -3.399 90)
			(layer "B.Fab")
			(hide yes)
			(effects
				(font
					(size 0.7 0.7)
					(thickness 0.15)
				)
				(justify left bottom mirror)
			)
		)
		(fp_text user "License: Apache-2.0"
			(at -0.939 -5.799 90)
			(layer "B.Fab")
			(hide yes)
			(effects
				(font
					(size 0.7 0.7)
					(thickness 0.15)
				)
				(justify left bottom mirror)
			)
		)
		(fp_text user "${REFERENCE}"
			(at -0.939 -4.599 90)
			(layer "B.Fab")
			(hide yes)
			(effects
				(font
					(size 0.7 0.7)
					(thickness 0.15)
				)
				(justify left bottom mirror)
			)
		)
		(pad "1" smd roundrect
			(at -0.48 0 270)
			(size 0.59 0.64)
			(layers "B.Cu" "B.Paste" "B.Mask")
			(roundrect_rratio 0.25)
			(net 185 "/USB Debug, DP/FTDI_3V3")
			(pintype "passive")
		)
		(pad "2" smd roundrect
			(at 0.48 0 270)
			(size 0.59 0.64)
			(layers "B.Cu" "B.Paste" "B.Mask")
			(roundrect_rratio 0.25)
			(net 1 "GND")
			(pintype "passive")
		)
	)
	(footprint "antmicro-footprints:C_0402_1005Metric"
		(layer "B.Cu")
		(at 54.9 116.8 90)
		(descr "Capacitor SMD 0402")
		(tags "capacitor SMD 0402")
		(property "Reference" "C146"
			(at 1.28 2.74 -90)
			(layer "B.SilkS")
			(effects
				(font
					(size 0.7 0.7)
					(thickness 0.15)
				)
				(justify left bottom mirror)
			)
		)
		(property "Value" "C_47p_0402"
			(at 0 -1.4 -90)
			(layer "B.Fab")
			(effects
				(font
					(size 0.7 0.7)
					(thickness 0.15)
				)
				(justify left bottom mirror)
			)
		)
		(property "Footprint" "antmicro-footprints:C_0402_1005Metric"
			(at 0 0 90)
			(layer "F.Fab")
			(hide yes)
			(effects
				(font
					(size 1.27 1.27)
					(thickness 0.15)
				)
			)
		)
		(property "Datasheet" "https://www.kemet.com/en/us/capacitors/product/C0402C470J5GACTU.html"
			(at 0 0 90)
			(layer "F.Fab")
			(hide yes)
			(effects
				(font
					(size 1.27 1.27)
					(thickness 0.15)
				)
			)
		)
		(property "Author" "Antmicro"
			(at 171.7 61.9 0)
			(layer "B.Fab")
			(hide yes)
			(effects
				(font
					(size 1 1)
					(thickness 0.15)
				)
				(justify mirror)
			)
		)
		(property "Dielectric" "C0G"
			(at 171.7 61.9 0)
			(layer "B.Fab")
			(hide yes)
			(effects
				(font
					(size 1 1)
					(thickness 0.15)
				)
				(justify mirror)
			)
		)
		(property "License" "Apache-2.0"
			(at 171.7 61.9 0)
			(layer "B.Fab")
			(hide yes)
			(effects
				(font
					(size 1 1)
					(thickness 0.15)
				)
				(justify mirror)
			)
		)
		(property "MPN" "C0402C470J5GACTU"
			(at 171.7 61.9 0)
			(layer "B.Fab")
			(hide yes)
			(effects
				(font
					(size 1 1)
					(thickness 0.15)
				)
				(justify mirror)
			)
		)
		(property "Manufacturer" "KEMET"
			(at 171.7 61.9 0)
			(layer "B.Fab")
			(hide yes)
			(effects
				(font
					(size 1 1)
					(thickness 0.15)
				)
				(justify mirror)
			)
		)
		(property "Val" "47p"
			(at 171.7 61.9 0)
			(layer "B.Fab")
			(hide yes)
			(effects
				(font
					(size 1 1)
					(thickness 0.15)
				)
				(justify mirror)
			)
		)
		(property "Voltage" ""
			(at 171.7 61.9 0)
			(layer "B.Fab")
			(hide yes)
			(effects
				(font
					(size 1 1)
					(thickness 0.15)
				)
				(justify mirror)
			)
		)
		(sheetname "USB Debug, DP")
		(sheetfile "usb.kicad_sch")
		(attr smd)
		(fp_rect
			(start -0.925 0.47)
			(end 0.925 -0.47)
			(stroke
				(width 0.05)
				(type default)
			)
			(fill none)
			(layer "B.CrtYd")
		)
		(fp_line
			(start 0.504 -0.248)
			(end 0.504 0.25)
			(stroke
				(width 0.15)
				(type solid)
			)
			(layer "B.Fab")
		)
		(fp_line
			(start -0.494 -0.248)
			(end 0.504 -0.248)
			(stroke
				(width 0.15)
				(type solid)
			)
			(layer "B.Fab")
		)
		(fp_line
			(start 0.504 0.25)
			(end -0.494 0.25)
			(stroke
				(width 0.15)
				(type solid)
			)
			(layer "B.Fab")
		)
		(fp_line
			(start -0.494 0.25)
			(end -0.494 -0.248)
			(stroke
				(width 0.15)
				(type solid)
			)
			(layer "B.Fab")
		)
		(fp_text user "${REFERENCE}"
			(at -0.932 -3.168 -90)
			(layer "B.Fab")
			(hide yes)
			(effects
				(font
					(size 0.7 0.7)
					(thickness 0.15)
				)
				(justify left bottom mirror)
			)
		)
		(fp_text user "License: Apache-2.0"
			(at -0.932 -5.17 -90)
			(layer "B.Fab")
			(hide yes)
			(effects
				(font
					(size 0.7 0.7)
					(thickness 0.15)
				)
				(justify left bottom mirror)
			)
		)
		(fp_text user "Author: Antmicro"
			(at -0.932 -4.17 -90)
			(layer "B.Fab")
			(hide yes)
			(effects
				(font
					(size 0.7 0.7)
					(thickness 0.15)
				)
				(justify left bottom mirror)
			)
		)
		(pad "1" smd roundrect
			(at -0.48 0 90)
			(size 0.59 0.64)
			(layers "B.Cu" "B.Paste" "B.Mask")
			(roundrect_rratio 0.25)
			(net 613 "/USB Debug, DP/USBC3_D_P")
			(pintype "passive")
		)
		(pad "2" smd roundrect
			(at 0.48 0 90)
			(size 0.59 0.64)
			(layers "B.Cu" "B.Paste" "B.Mask")
			(roundrect_rratio 0.25)
			(net 1 "GND")
			(pintype "passive")
		)
	)
	(footprint "antmicro-footprints:R_0402_1005Metric"
		(layer "B.Cu")
		(at 89.9 116.1 -90)
		(descr "Resistor SMD 0402")
		(tags "resistor SMD 0402")
		(property "Reference" "R279"
			(at -2.55 -5.15 90)
			(layer "B.SilkS")
			(effects
				(font
					(size 0.7 0.7)
					(thickness 0.15)
				)
				(justify left bottom mirror)
			)
		)
		(property "Value" "R_2k2_0402"
			(at 0 -1.4 90)
			(layer "B.Fab")
			(effects
				(font
					(size 0.7 0.7)
					(thickness 0.15)
				)
				(justify left bottom mirror)
			)
		)
		(property "Footprint" "antmicro-footprints:R_0402_1005Metric"
			(at 0 0 -90)
			(layer "F.Fab")
			(hide yes)
			(effects
				(font
					(size 1.27 1.27)
					(thickness 0.15)
				)
			)
		)
		(property "Datasheet" "https://www.bourns.com/docs/product-datasheets/cr.pdf"
			(at 0 0 -90)
			(layer "F.Fab")
			(hide yes)
			(effects
				(font
					(size 1.27 1.27)
					(thickness 0.15)
				)
			)
		)
		(property "Author" "Antmicro"
			(at -26.2 206 0)
			(layer "B.Fab")
			(hide yes)
			(effects
				(font
					(size 1 1)
					(thickness 0.15)
				)
				(justify mirror)
			)
		)
		(property "License" "Apache-2.0"
			(at -26.2 206 0)
			(layer "B.Fab")
			(hide yes)
			(effects
				(font
					(size 1 1)
					(thickness 0.15)
				)
				(justify mirror)
			)
		)
		(property "MPN" "CR0402-FX-2201GLF"
			(at -26.2 206 0)
			(layer "B.Fab")
			(hide yes)
			(effects
				(font
					(size 1 1)
					(thickness 0.15)
				)
				(justify mirror)
			)
		)
		(property "Manufacturer" "Bourns"
			(at -26.2 206 0)
			(layer "B.Fab")
			(hide yes)
			(effects
				(font
					(size 1 1)
					(thickness 0.15)
				)
				(justify mirror)
			)
		)
		(property "Tolerance" "1%"
			(at -26.2 206 0)
			(layer "B.Fab")
			(hide yes)
			(effects
				(font
					(size 1 1)
					(thickness 0.15)
				)
				(justify mirror)
			)
		)
		(property "Val" "2k2"
			(at -26.2 206 0)
			(layer "B.Fab")
			(hide yes)
			(effects
				(font
					(size 1 1)
					(thickness 0.15)
				)
				(justify mirror)
			)
		)
		(sheetname "HDMI")
		(sheetfile "hdmi.kicad_sch")
		(attr smd exclude_from_pos_files exclude_from_bom dnp)
		(fp_rect
			(start -0.925 0.47)
			(end 0.925 -0.47)
			(stroke
				(width 0.05)
				(type default)
			)
			(fill none)
			(layer "B.CrtYd")
		)
		(fp_rect
			(start -0.5 0.25)
			(end 0.5 -0.25)
			(stroke
				(width 0.15)
				(type solid)
			)
			(fill none)
			(layer "B.Fab")
		)
		(fp_text user "Author: Antmicro"
			(at -0.95 -4.169 90)
			(layer "B.Fab")
			(hide yes)
			(effects
				(font
					(size 0.7 0.7)
					(thickness 0.15)
				)
				(justify left bottom mirror)
			)
		)
		(fp_text user "License: Apache-2.0"
			(at -0.95 -5.169 90)
			(layer "B.Fab")
			(hide yes)
			(effects
				(font
					(size 0.7 0.7)
					(thickness 0.15)
				)
				(justify left bottom mirror)
			)
		)
		(fp_text user "${REFERENCE}"
			(at -0.95 -3.168 90)
			(layer "B.Fab")
			(hide yes)
			(effects
				(font
					(size 0.7 0.7)
					(thickness 0.15)
				)
				(justify left bottom mirror)
			)
		)
		(pad "1" smd roundrect
			(at -0.48 0 270)
			(size 0.59 0.64)
			(layers "B.Cu" "B.Paste" "B.Mask")
			(roundrect_rratio 0.25)
			(net 701 "/HDMI/HDMI_SDA_3V3")
			(pintype "passive")
		)
		(pad "2" smd roundrect
			(at 0.48 0 270)
			(size 0.59 0.64)
			(layers "B.Cu" "B.Paste" "B.Mask")
			(roundrect_rratio 0.25)
			(net 87 "+3V3")
			(pintype "passive")
		)
	)
	(footprint "antmicro-footprints:R_0402_1005Metric"
		(layer "B.Cu")
		(at 112.4 107.1 180)
		(descr "Resistor SMD 0402")
		(tags "resistor SMD 0402")
		(property "Reference" "R114"
			(at -3.72 -0.3 0)
			(layer "B.SilkS")
			(effects
				(font
					(size 0.7 0.7)
					(thickness 0.15)
				)
				(justify left bottom mirror)
			)
		)
		(property "Value" "R_0R_0402"
			(at 0 -1.4 0)
			(layer "B.Fab")
			(effects
				(font
					(size 0.7 0.7)
					(thickness 0.15)
				)
				(justify left bottom mirror)
			)
		)
		(property "Footprint" "antmicro-footprints:R_0402_1005Metric"
			(at 0 0 180)
			(layer "F.Fab")
			(hide yes)
			(effects
				(font
					(size 1.27 1.27)
					(thickness 0.15)
				)
			)
		)
		(property "Datasheet" "https://industrial.panasonic.com/cdbs/www-data/pdf/RDA0000/AOA0000C301.pdf"
			(at 0 0 180)
			(layer "F.Fab")
			(hide yes)
			(effects
				(font
					(size 1.27 1.27)
					(thickness 0.15)
				)
			)
		)
		(property "Author" "Antmicro"
			(at 224.8 214.2 0)
			(layer "B.Fab")
			(hide yes)
			(effects
				(font
					(size 1 1)
					(thickness 0.15)
				)
				(justify mirror)
			)
		)
		(property "Current" "1A"
			(at 224.8 214.2 0)
			(layer "B.Fab")
			(hide yes)
			(effects
				(font
					(size 1 1)
					(thickness 0.15)
				)
				(justify mirror)
			)
		)
		(property "License" "Apache-2.0"
			(at 224.8 214.2 0)
			(layer "B.Fab")
			(hide yes)
			(effects
				(font
					(size 1 1)
					(thickness 0.15)
				)
				(justify mirror)
			)
		)
		(property "MPN" "ERJ2GE0R00X"
			(at 224.8 214.2 0)
			(layer "B.Fab")
			(hide yes)
			(effects
				(font
					(size 1 1)
					(thickness 0.15)
				)
				(justify mirror)
			)
		)
		(property "Manufacturer" "Panasonic"
			(at 224.8 214.2 0)
			(layer "B.Fab")
			(hide yes)
			(effects
				(font
					(size 1 1)
					(thickness 0.15)
				)
				(justify mirror)
			)
		)
		(property "Tolerance" ""
			(at 224.8 214.2 0)
			(layer "B.Fab")
			(hide yes)
			(effects
				(font
					(size 1 1)
					(thickness 0.15)
				)
				(justify mirror)
			)
		)
		(property "Val" "0R"
			(at 224.8 214.2 0)
			(layer "B.Fab")
			(hide yes)
			(effects
				(font
					(size 1 1)
					(thickness 0.15)
				)
				(justify mirror)
			)
		)
		(sheetname "USB3")
		(sheetfile "usb3.kicad_sch")
		(attr smd exclude_from_pos_files exclude_from_bom dnp)
		(fp_rect
			(start -0.925 0.47)
			(end 0.925 -0.47)
			(stroke
				(width 0.05)
				(type default)
			)
			(fill none)
			(layer "B.CrtYd")
		)
		(fp_rect
			(start -0.5 0.25)
			(end 0.5 -0.25)
			(stroke
				(width 0.15)
				(type solid)
			)
			(fill none)
			(layer "B.Fab")
		)
		(fp_text user "Author: Antmicro"
			(at -0.95 -4.169 0)
			(layer "B.Fab")
			(hide yes)
			(effects
				(font
					(size 0.7 0.7)
					(thickness 0.15)
				)
				(justify left bottom mirror)
			)
		)
		(fp_text user "License: Apache-2.0"
			(at -0.95 -5.169 0)
			(layer "B.Fab")
			(hide yes)
			(effects
				(font
					(size 0.7 0.7)
					(thickness 0.15)
				)
				(justify left bottom mirror)
			)
		)
		(fp_text user "${REFERENCE}"
			(at -0.95 -3.168 0)
			(layer "B.Fab")
			(hide yes)
			(effects
				(font
					(size 0.7 0.7)
					(thickness 0.15)
				)
				(justify left bottom mirror)
			)
		)
		(pad "1" smd roundrect
			(at -0.48 0 180)
			(size 0.59 0.64)
			(layers "B.Cu" "B.Paste" "B.Mask")
			(roundrect_rratio 0.25)
			(net 1 "GND")
			(pintype "passive")
		)
		(pad "2" smd roundrect
			(at 0.48 0 180)
			(size 0.59 0.64)
			(layers "B.Cu" "B.Paste" "B.Mask")
			(roundrect_rratio 0.25)
			(net 314 "/USB3/USBC1_ADDR")
			(pintype "passive")
		)
	)
	(footprint "antmicro-footprints:R_0402_1005Metric"
		(layer "B.Cu")
		(at 90.49 101.91 45)
		(descr "Resistor SMD 0402")
		(tags "resistor SMD 0402")
		(property "Reference" "R213"
			(at -0.834386 0.424264 -135)
			(layer "B.SilkS")
			(effects
				(font
					(size 0.7 0.7)
					(thickness 0.15)
				)
				(justify left bottom mirror)
			)
		)
		(property "Value" "R_499R_0402"
			(at -1.011843 -1.772046 -135)
			(layer "B.Fab")
			(effects
				(font
					(size 0.7 0.7)
					(thickness 0.15)
				)
				(justify left bottom mirror)
			)
		)
		(property "Footprint" "antmicro-footprints:R_0402_1005Metric"
			(at 0 0 45)
			(layer "F.Fab")
			(hide yes)
			(effects
				(font
					(size 1.27 1.27)
					(thickness 0.15)
				)
			)
		)
		(property "Datasheet" "https://www.mouser.com/datasheet/2/54/cr-1858361.pdf"
			(at 0 0 45)
			(layer "F.Fab")
			(hide yes)
			(effects
				(font
					(size 1.27 1.27)
					(thickness 0.15)
				)
			)
		)
		(property "Author" "Antmicro"
			(at 98.56516 -34.137345 0)
			(layer "B.Fab")
			(hide yes)
			(effects
				(font
					(size 1 1)
					(thickness 0.15)
				)
				(justify mirror)
			)
		)
		(property "License" "Apache-2.0"
			(at 98.56516 -34.137345 0)
			(layer "B.Fab")
			(hide yes)
			(effects
				(font
					(size 1 1)
					(thickness 0.15)
				)
				(justify mirror)
			)
		)
		(property "MPN" "CR0402-FX-4990GLF"
			(at 98.56516 -34.137345 0)
			(layer "B.Fab")
			(hide yes)
			(effects
				(font
					(size 1 1)
					(thickness 0.15)
				)
				(justify mirror)
			)
		)
		(property "Manufacturer" "Bourns"
			(at 98.56516 -34.137345 0)
			(layer "B.Fab")
			(hide yes)
			(effects
				(font
					(size 1 1)
					(thickness 0.15)
				)
				(justify mirror)
			)
		)
		(property "Tolerance" "1%"
			(at 98.56516 -34.137345 0)
			(layer "B.Fab")
			(hide yes)
			(effects
				(font
					(size 1 1)
					(thickness 0.15)
				)
				(justify mirror)
			)
		)
		(property "Val" "499R"
			(at 98.56516 -34.137345 0)
			(layer "B.Fab")
			(hide yes)
			(effects
				(font
					(size 1 1)
					(thickness 0.15)
				)
				(justify mirror)
			)
		)
		(sheetname "HDMI")
		(sheetfile "hdmi.kicad_sch")
		(attr smd)
		(fp_poly
			(pts
				(xy -0.925 0.47) (xy 0.925 0.47) (xy 0.925 -0.47) (xy -0.925 -0.47)
			)
			(stroke
				(width 0.05)
				(type default)
			)
			(fill none)
			(layer "B.CrtYd")
		)
		(fp_poly
			(pts
				(xy -0.5 0.25) (xy 0.5 0.25) (xy 0.5 -0.25) (xy -0.5 -0.25)
			)
			(stroke
				(width 0.15)
				(type solid)
			)
			(fill none)
			(layer "B.Fab")
		)
		(fp_text user "${REFERENCE}"
			(at -0.95 -3.168 -135)
			(layer "B.Fab")
			(hide yes)
			(effects
				(font
					(size 0.7 0.7)
					(thickness 0.15)
				)
				(justify left bottom mirror)
			)
		)
		(fp_text user "License: Apache-2.0"
			(at -0.949999 -5.169 -135)
			(layer "B.Fab")
			(hide yes)
			(effects
				(font
					(size 0.7 0.7)
					(thickness 0.15)
				)
				(justify left bottom mirror)
			)
		)
		(fp_text user "Author: Antmicro"
			(at -0.95 -4.169 -135)
			(layer "B.Fab")
			(hide yes)
			(effects
				(font
					(size 0.7 0.7)
					(thickness 0.15)
				)
				(justify left bottom mirror)
			)
		)
		(pad "1" smd roundrect
			(at -0.48 0 45)
			(size 0.59 0.64)
			(layers "B.Cu" "B.Paste" "B.Mask")
			(roundrect_rratio 0.25)
			(net 623 "Net-(Q2-D)")
			(pintype "passive")
		)
		(pad "2" smd roundrect
			(at 0.48 0 45)
			(size 0.59 0.64)
			(layers "B.Cu" "B.Paste" "B.Mask")
			(roundrect_rratio 0.25)
			(net 493 "/HDMI/HDMI_D1_P")
			(pintype "passive")
		)
	)
	(footprint "antmicro-footprints:C_0402_1005Metric"
		(layer "B.Cu")
		(at 100.485 75.25)
		(descr "Capacitor SMD 0402")
		(tags "capacitor SMD 0402")
		(property "Reference" "C99"
			(at 1.215 1.34 180)
			(layer "B.SilkS")
			(effects
				(font
					(size 0.7 0.7)
					(thickness 0.15)
				)
				(justify left bottom mirror)
			)
		)
		(property "Value" "C_1u_0402"
			(at 0 -1.4 180)
			(layer "B.Fab")
			(effects
				(font
					(size 0.7 0.7)
					(thickness 0.15)
				)
				(justify left bottom mirror)
			)
		)
		(property "Footprint" "antmicro-footprints:C_0402_1005Metric"
			(at 0 0 0)
			(layer "F.Fab")
			(hide yes)
			(effects
				(font
					(size 1.27 1.27)
					(thickness 0.15)
				)
			)
		)
		(property "Datasheet" "https://product.tdk.com/en/search/capacitor/ceramic/mlcc/info?part_no=C1005X6S1A105K050BC"
			(at 0 0 0)
			(layer "F.Fab")
			(hide yes)
			(effects
				(font
					(size 1.27 1.27)
					(thickness 0.15)
				)
			)
		)
		(property "Author" "Antmicro"
			(at 0 0 0)
			(layer "B.Fab")
			(hide yes)
			(effects
				(font
					(size 1 1)
					(thickness 0.15)
				)
				(justify mirror)
			)
		)
		(property "Dielectric" ""
			(at 0 0 0)
			(layer "B.Fab")
			(hide yes)
			(effects
				(font
					(size 1 1)
					(thickness 0.15)
				)
				(justify mirror)
			)
		)
		(property "License" "Apache-2.0"
			(at 0 0 0)
			(layer "B.Fab")
			(hide yes)
			(effects
				(font
					(size 1 1)
					(thickness 0.15)
				)
				(justify mirror)
			)
		)
		(property "MPN" "C1005X6S1A105K050BC"
			(at 0 0 0)
			(layer "B.Fab")
			(hide yes)
			(effects
				(font
					(size 1 1)
					(thickness 0.15)
				)
				(justify mirror)
			)
		)
		(property "Manufacturer" "TDK"
			(at 0 0 0)
			(layer "B.Fab")
			(hide yes)
			(effects
				(font
					(size 1 1)
					(thickness 0.15)
				)
				(justify mirror)
			)
		)
		(property "Val" "1u"
			(at 0 0 0)
			(layer "B.Fab")
			(hide yes)
			(effects
				(font
					(size 1 1)
					(thickness 0.15)
				)
				(justify mirror)
			)
		)
		(property "Voltage" ""
			(at 0 0 0)
			(layer "B.Fab")
			(hide yes)
			(effects
				(font
					(size 1 1)
					(thickness 0.15)
				)
				(justify mirror)
			)
		)
		(sheetname "CSI")
		(sheetfile "csi.kicad_sch")
		(attr smd)
		(fp_rect
			(start -0.925 0.47)
			(end 0.925 -0.47)
			(stroke
				(width 0.05)
				(type default)
			)
			(fill none)
			(layer "B.CrtYd")
		)
		(fp_line
			(start -0.494 -0.248)
			(end 0.504 -0.248)
			(stroke
				(width 0.15)
				(type solid)
			)
			(layer "B.Fab")
		)
		(fp_line
			(start -0.494 0.25)
			(end -0.494 -0.248)
			(stroke
				(width 0.15)
				(type solid)
			)
			(layer "B.Fab")
		)
		(fp_line
			(start 0.504 -0.248)
			(end 0.504 0.25)
			(stroke
				(width 0.15)
				(type solid)
			)
			(layer "B.Fab")
		)
		(fp_line
			(start 0.504 0.25)
			(end -0.494 0.25)
			(stroke
				(width 0.15)
				(type solid)
			)
			(layer "B.Fab")
		)
		(fp_text user "Author: Antmicro"
			(at -0.932 -4.17 180)
			(layer "B.Fab")
			(hide yes)
			(effects
				(font
					(size 0.7 0.7)
					(thickness 0.15)
				)
				(justify left bottom mirror)
			)
		)
		(fp_text user "License: Apache-2.0"
			(at -0.932 -5.17 180)
			(layer "B.Fab")
			(hide yes)
			(effects
				(font
					(size 0.7 0.7)
					(thickness 0.15)
				)
				(justify left bottom mirror)
			)
		)
		(fp_text user "${REFERENCE}"
			(at -0.932 -3.168 180)
			(layer "B.Fab")
			(hide yes)
			(effects
				(font
					(size 0.7 0.7)
					(thickness 0.15)
				)
				(justify left bottom mirror)
			)
		)
		(pad "1" smd roundrect
			(at -0.48 0)
			(size 0.59 0.64)
			(layers "B.Cu" "B.Paste" "B.Mask")
			(roundrect_rratio 0.25)
			(net 1 "GND")
			(pintype "passive")
		)
		(pad "2" smd roundrect
			(at 0.48 0)
			(size 0.59 0.64)
			(layers "B.Cu" "B.Paste" "B.Mask")
			(roundrect_rratio 0.25)
			(net 111 "/CSI/CSIB_5V")
			(pintype "passive")
		)
	)
	(footprint "antmicro-footprints:R_0402_1005Metric"
		(layer "B.Cu")
		(at 55.125 87.45)
		(descr "Resistor SMD 0402")
		(tags "resistor SMD 0402")
		(property "Reference" "R149"
			(at -1.235 2.545 0)
			(layer "B.SilkS")
			(effects
				(font
					(size 0.7 0.7)
					(thickness 0.15)
				)
				(justify right top mirror)
			)
		)
		(property "Value" "R_10k_0402"
			(at 0 -1.4 0)
			(layer "B.Fab")
			(effects
				(font
					(size 0.7 0.7)
					(thickness 0.15)
				)
				(justify right top mirror)
			)
		)
		(property "Footprint" "antmicro-footprints:R_0402_1005Metric"
			(at 0 0 0)
			(layer "F.Fab")
			(hide yes)
			(effects
				(font
					(size 1.27 1.27)
					(thickness 0.15)
				)
			)
		)
		(property "Datasheet" "https://www.bourns.com/docs/product-datasheets/cr.pdf"
			(at 0 0 0)
			(layer "F.Fab")
			(hide yes)
			(effects
				(font
					(size 1.27 1.27)
					(thickness 0.15)
				)
			)
		)
		(property "Author" "Antmicro"
			(at -32.575 144.225 90)
			(layer "B.Fab")
			(hide yes)
			(effects
				(font
					(size 1 1)
					(thickness 0.15)
				)
				(justify mirror)
			)
		)
		(property "License" "Apache-2.0"
			(at -32.575 144.225 90)
			(layer "B.Fab")
			(hide yes)
			(effects
				(font
					(size 1 1)
					(thickness 0.15)
				)
				(justify mirror)
			)
		)
		(property "MPN" "CR0402-FX-1002GLF"
			(at -32.575 144.225 90)
			(layer "B.Fab")
			(hide yes)
			(effects
				(font
					(size 1 1)
					(thickness 0.15)
				)
				(justify mirror)
			)
		)
		(property "Manufacturer" "Bourns"
			(at -32.575 144.225 90)
			(layer "B.Fab")
			(hide yes)
			(effects
				(font
					(size 1 1)
					(thickness 0.15)
				)
				(justify mirror)
			)
		)
		(property "Tolerance" "1%"
			(at -32.575 144.225 90)
			(layer "B.Fab")
			(hide yes)
			(effects
				(font
					(size 1 1)
					(thickness 0.15)
				)
				(justify mirror)
			)
		)
		(property "Val" "10k"
			(at -32.575 144.225 90)
			(layer "B.Fab")
			(hide yes)
			(effects
				(font
					(size 1 1)
					(thickness 0.15)
				)
				(justify mirror)
			)
		)
		(sheetname "Ethernet")
		(sheetfile "ethernet.kicad_sch")
		(attr smd exclude_from_pos_files exclude_from_bom dnp)
		(fp_rect
			(start -0.925 0.47)
			(end 0.925 -0.47)
			(stroke
				(width 0.05)
				(type default)
			)
			(fill none)
			(layer "B.CrtYd")
		)
		(fp_rect
			(start -0.5 0.25)
			(end 0.5 -0.25)
			(stroke
				(width 0.15)
				(type solid)
			)
			(fill none)
			(layer "B.Fab")
		)
		(fp_text user "Author: Antmicro"
			(at -0.95 -4.169 0)
			(layer "B.Fab")
			(hide yes)
			(effects
				(font
					(size 0.7 0.7)
					(thickness 0.15)
				)
				(justify right top mirror)
			)
		)
		(fp_text user "License: Apache-2.0"
			(at -0.95 -5.169 0)
			(layer "B.Fab")
			(hide yes)
			(effects
				(font
					(size 0.7 0.7)
					(thickness 0.15)
				)
				(justify right top mirror)
			)
		)
		(fp_text user "${REFERENCE}"
			(at -0.95 -3.168 0)
			(layer "B.Fab")
			(hide yes)
			(effects
				(font
					(size 0.7 0.7)
					(thickness 0.15)
				)
				(justify right top mirror)
			)
		)
		(pad "1" smd roundrect
			(at -0.48 0)
			(size 0.59 0.64)
			(layers "B.Cu" "B.Paste" "B.Mask")
			(roundrect_rratio 0.25)
			(net 572 "/Ethernet/TPH")
			(pintype "passive")
		)
		(pad "2" smd roundrect
			(at 0.48 0)
			(size 0.59 0.64)
			(layers "B.Cu" "B.Paste" "B.Mask")
			(roundrect_rratio 0.25)
			(net 105 "/Ethernet/VDD")
			(pintype "passive")
		)
	)
	(footprint "antmicro-footprints:C_0603_1608Metric"
		(layer "B.Cu")
		(at 38.29 113.14 90)
		(descr "Capacitor SMD 0603")
		(tags "capacitor 0603")
		(property "Reference" "C77"
			(at -1.01 1.51 90)
			(layer "B.SilkS")
			(effects
				(font
					(size 0.7 0.7)
					(thickness 0.15)
				)
				(justify right bottom mirror)
			)
		)
		(property "Value" "C_10n_0603"
			(at -2.055717 -1.963152 90)
			(layer "B.Fab")
			(effects
				(font
					(size 0.7 0.7)
					(thickness 0.15)
				)
				(justify right bottom mirror)
			)
		)
		(property "Footprint" "antmicro-footprints:C_0603_1608Metric"
			(at 0 0 90)
			(layer "F.Fab")
			(hide yes)
			(effects
				(font
					(size 1.27 1.27)
					(thickness 0.15)
				)
			)
		)
		(property "Datasheet" "https://spicat.kyocera-avx.com/product/mlcc/chartview/06031C103JAT2A/"
			(at 0 0 90)
			(layer "F.Fab")
			(hide yes)
			(effects
				(font
					(size 1.27 1.27)
					(thickness 0.15)
				)
			)
		)
		(property "Author" "Antmicro"
			(at 151.43 74.85 0)
			(layer "B.Fab")
			(hide yes)
			(effects
				(font
					(size 1 1)
					(thickness 0.15)
				)
				(justify mirror)
			)
		)
		(property "Dielectric" ""
			(at 151.43 74.85 0)
			(layer "B.Fab")
			(hide yes)
			(effects
				(font
					(size 1 1)
					(thickness 0.15)
				)
				(justify mirror)
			)
		)
		(property "License" "Apache-2.0"
			(at 151.43 74.85 0)
			(layer "B.Fab")
			(hide yes)
			(effects
				(font
					(size 1 1)
					(thickness 0.15)
				)
				(justify mirror)
			)
		)
		(property "MPN" "06031C103JAT2A"
			(at 151.43 74.85 0)
			(layer "B.Fab")
			(hide yes)
			(effects
				(font
					(size 1 1)
					(thickness 0.15)
				)
				(justify mirror)
			)
		)
		(property "Manufacturer" "AVX"
			(at 151.43 74.85 0)
			(layer "B.Fab")
			(hide yes)
			(effects
				(font
					(size 1 1)
					(thickness 0.15)
				)
				(justify mirror)
			)
		)
		(property "Val" "10n"
			(at 151.43 74.85 0)
			(layer "B.Fab")
			(hide yes)
			(effects
				(font
					(size 1 1)
					(thickness 0.15)
				)
				(justify mirror)
			)
		)
		(property "Voltage" ""
			(at 151.43 74.85 0)
			(layer "B.Fab")
			(hide yes)
			(effects
				(font
					(size 1 1)
					(thickness 0.15)
				)
				(justify mirror)
			)
		)
		(sheetname "Ethernet")
		(sheetfile "ethernet.kicad_sch")
		(attr smd)
		(fp_line
			(start 0.15 -0.4)
			(end -0.15 -0.4)
			(stroke
				(width 0.15)
				(type solid)
			)
			(layer "B.SilkS")
		)
		(fp_line
			(start 0.15 0.4)
			(end -0.15 0.4)
			(stroke
				(width 0.15)
				(type solid)
			)
			(layer "B.SilkS")
		)
		(fp_rect
			(start -1.25 0.65)
			(end 1.25 -0.65)
			(stroke
				(width 0.05)
				(type solid)
			)
			(fill none)
			(layer "B.CrtYd")
		)
		(fp_rect
			(start -0.8 0.4)
			(end 0.8 -0.4)
			(stroke
				(width 0.15)
				(type solid)
			)
			(fill none)
			(layer "B.Fab")
		)
		(fp_text user "License: Apache-2.0"
			(at -1.9 -4.947 90)
			(layer "B.Fab")
			(hide yes)
			(effects
				(font
					(size 0.7 0.7)
					(thickness 0.15)
				)
				(justify right bottom mirror)
			)
		)
		(fp_text user "${REFERENCE}"
			(at -1.9 -3.947 90)
			(layer "B.Fab")
			(hide yes)
			(effects
				(font
					(size 0.7 0.7)
					(thickness 0.15)
				)
				(justify right bottom mirror)
			)
		)
		(fp_text user "Author: Antmicro"
			(at -1.9 -5.947 90)
			(layer "B.Fab")
			(hide yes)
			(effects
				(font
					(size 0.7 0.7)
					(thickness 0.15)
				)
				(justify right bottom mirror)
			)
		)
		(pad "1" smd roundrect
			(at -0.7 0 90)
			(size 0.8 1)
			(layers "B.Cu" "B.Paste" "B.Mask")
			(roundrect_rratio 0.2)
			(net 1 "GND")
			(pintype "passive")
		)
		(pad "2" smd roundrect
			(at 0.7 0 90)
			(size 0.8 1)
			(layers "B.Cu" "B.Paste" "B.Mask")
			(roundrect_rratio 0.2)
			(net 136 "Net-(J6-P4)")
			(pintype "passive")
		)
	)
	(footprint "antmicro-footprints:R_0402_1005Metric"
		(layer "B.Cu")
		(at 54.3 78.59 90)
		(descr "Resistor SMD 0402")
		(tags "resistor SMD 0402")
		(property "Reference" "R275"
			(at -10.51 21 -90)
			(layer "B.SilkS")
			(effects
				(font
					(size 0.7 0.7)
					(thickness 0.15)
				)
				(justify right top mirror)
			)
		)
		(property "Value" "R_10k_0402"
			(at -1.011843 -1.772047 90)
			(layer "B.Fab")
			(effects
				(font
					(size 0.7 0.7)
					(thickness 0.15)
				)
				(justify right top mirror)
			)
		)
		(property "Footprint" "antmicro-footprints:R_0402_1005Metric"
			(at 0 0 90)
			(layer "B.Fab")
			(hide yes)
			(effects
				(font
					(size 1.27 1.27)
					(thickness 0.15)
				)
				(justify mirror)
			)
		)
		(property "Datasheet" "https://www.bourns.com/docs/product-datasheets/cr.pdf"
			(at 0 0 90)
			(layer "B.Fab")
			(hide yes)
			(effects
				(font
					(size 1.27 1.27)
					(thickness 0.15)
				)
				(justify mirror)
			)
		)
		(property "Manufacturer" "Bourns"
			(at 0 0 -90)
			(unlocked yes)
			(layer "B.Fab")
			(hide yes)
			(effects
				(font
					(size 1 1)
					(thickness 0.15)
				)
				(justify mirror)
			)
		)
		(property "MPN" "CR0402-FX-1002GLF"
			(at 0 0 -90)
			(unlocked yes)
			(layer "B.Fab")
			(hide yes)
			(effects
				(font
					(size 1 1)
					(thickness 0.15)
				)
				(justify mirror)
			)
		)
		(property "Val" "10k"
			(at 0 0 -90)
			(unlocked yes)
			(layer "B.Fab")
			(hide yes)
			(effects
				(font
					(size 1 1)
					(thickness 0.15)
				)
				(justify mirror)
			)
		)
		(property "License" "Apache-2.0"
			(at 0 0 -90)
			(unlocked yes)
			(layer "B.Fab")
			(hide yes)
			(effects
				(font
					(size 1 1)
					(thickness 0.15)
				)
				(justify mirror)
			)
		)
		(property "Author" "Antmicro"
			(at 0 0 -90)
			(unlocked yes)
			(layer "B.Fab")
			(hide yes)
			(effects
				(font
					(size 1 1)
					(thickness 0.15)
				)
				(justify mirror)
			)
		)
		(property "Tolerance" "1%"
			(at 0 0 -90)
			(unlocked yes)
			(layer "B.Fab")
			(hide yes)
			(effects
				(font
					(size 1 1)
					(thickness 0.15)
				)
				(justify mirror)
			)
		)
		(sheetname "Supply")
		(sheetfile "supply.kicad_sch")
		(attr smd)
		(fp_rect
			(start -0.925 0.47)
			(end 0.925 -0.47)
			(stroke
				(width 0.05)
				(type default)
			)
			(fill none)
			(layer "B.CrtYd")
		)
		(fp_rect
			(start -0.5 0.25)
			(end 0.5 -0.25)
			(stroke
				(width 0.15)
				(type solid)
			)
			(fill none)
			(layer "B.Fab")
		)
		(fp_text user "${REFERENCE}"
			(at -0.95 -3.168 90)
			(layer "B.Fab")
			(hide yes)
			(effects
				(font
					(size 0.7 0.7)
					(thickness 0.15)
				)
				(justify right top mirror)
			)
		)
		(fp_text user "License: Apache-2.0"
			(at -0.95 -5.169 90)
			(layer "B.Fab")
			(hide yes)
			(effects
				(font
					(size 0.7 0.7)
					(thickness 0.15)
				)
				(justify right top mirror)
			)
		)
		(fp_text user "Author: Antmicro"
			(at -0.95 -4.169 90)
			(layer "B.Fab")
			(hide yes)
			(effects
				(font
					(size 0.7 0.7)
					(thickness 0.15)
				)
				(justify right top mirror)
			)
		)
		(pad "1" smd roundrect
			(at -0.48 0 90)
			(size 0.59 0.64)
			(layers "B.Cu" "B.Paste" "B.Mask")
			(roundrect_rratio 0.25)
			(net 789 "MODULE_ID")
			(pintype "passive")
		)
		(pad "2" smd roundrect
			(at 0.48 0 90)
			(size 0.59 0.64)
			(layers "B.Cu" "B.Paste" "B.Mask")
			(roundrect_rratio 0.25)
			(net 787 "+5V_SoM")
			(pintype "passive")
		)
	)
	(footprint "antmicro-footprints:R_0402_1005Metric"
		(layer "B.Cu")
		(at 84.4 101.3 90)
		(descr "Resistor SMD 0402")
		(tags "resistor SMD 0402")
		(property "Reference" "R205"
			(at 1.65 -0.4 -90)
			(layer "B.SilkS")
			(effects
				(font
					(size 0.7 0.7)
					(thickness 0.15)
				)
				(justify left bottom mirror)
			)
		)
		(property "Value" "R_100k_0402"
			(at 0 -1.4 -90)
			(layer "B.Fab")
			(effects
				(font
					(size 0.7 0.7)
					(thickness 0.15)
				)
				(justify left bottom mirror)
			)
		)
		(property "Footprint" "antmicro-footprints:R_0402_1005Metric"
			(at 0 0 90)
			(layer "F.Fab")
			(hide yes)
			(effects
				(font
					(size 1.27 1.27)
					(thickness 0.15)
				)
			)
		)
		(property "Datasheet" "https://www.bourns.com/docs/product-datasheets/cr.pdf"
			(at 0 0 90)
			(layer "F.Fab")
			(hide yes)
			(effects
				(font
					(size 1.27 1.27)
					(thickness 0.15)
				)
			)
		)
		(property "Author" "Antmicro"
			(at 185.7 16.9 0)
			(layer "B.Fab")
			(hide yes)
			(effects
				(font
					(size 1 1)
					(thickness 0.15)
				)
				(justify mirror)
			)
		)
		(property "License" "Apache-2.0"
			(at 185.7 16.9 0)
			(layer "B.Fab")
			(hide yes)
			(effects
				(font
					(size 1 1)
					(thickness 0.15)
				)
				(justify mirror)
			)
		)
		(property "MPN" "CR0402-FX-1003GLF"
			(at 185.7 16.9 0)
			(layer "B.Fab")
			(hide yes)
			(effects
				(font
					(size 1 1)
					(thickness 0.15)
				)
				(justify mirror)
			)
		)
		(property "Manufacturer" "Bourns"
			(at 185.7 16.9 0)
			(layer "B.Fab")
			(hide yes)
			(effects
				(font
					(size 1 1)
					(thickness 0.15)
				)
				(justify mirror)
			)
		)
		(property "Tolerance" "1%"
			(at 185.7 16.9 0)
			(layer "B.Fab")
			(hide yes)
			(effects
				(font
					(size 1 1)
					(thickness 0.15)
				)
				(justify mirror)
			)
		)
		(property "Val" "100k"
			(at 185.7 16.9 0)
			(layer "B.Fab")
			(hide yes)
			(effects
				(font
					(size 1 1)
					(thickness 0.15)
				)
				(justify mirror)
			)
		)
		(sheetname "USB Debug, DP")
		(sheetfile "usb.kicad_sch")
		(attr smd)
		(fp_rect
			(start -0.925 0.47)
			(end 0.925 -0.47)
			(stroke
				(width 0.05)
				(type default)
			)
			(fill none)
			(layer "B.CrtYd")
		)
		(fp_rect
			(start -0.5 0.25)
			(end 0.5 -0.25)
			(stroke
				(width 0.15)
				(type solid)
			)
			(fill none)
			(layer "B.Fab")
		)
		(fp_text user "License: Apache-2.0"
			(at -0.95 -5.169 -90)
			(layer "B.Fab")
			(hide yes)
			(effects
				(font
					(size 0.7 0.7)
					(thickness 0.15)
				)
				(justify left bottom mirror)
			)
		)
		(fp_text user "${REFERENCE}"
			(at -0.95 -3.168 -90)
			(layer "B.Fab")
			(hide yes)
			(effects
				(font
					(size 0.7 0.7)
					(thickness 0.15)
				)
				(justify left bottom mirror)
			)
		)
		(fp_text user "Author: Antmicro"
			(at -0.95 -4.169 -90)
			(layer "B.Fab")
			(hide yes)
			(effects
				(font
					(size 0.7 0.7)
					(thickness 0.15)
				)
				(justify left bottom mirror)
			)
		)
		(pad "1" smd roundrect
			(at -0.48 0 90)
			(size 0.59 0.64)
			(layers "B.Cu" "B.Paste" "B.Mask")
			(roundrect_rratio 0.25)
			(net 36 "DP1_AUX_P")
			(pintype "passive")
		)
		(pad "2" smd roundrect
			(at 0.48 0 90)
			(size 0.59 0.64)
			(layers "B.Cu" "B.Paste" "B.Mask")
			(roundrect_rratio 0.25)
			(net 1 "GND")
			(pintype "passive")
		)
	)
	(footprint "antmicro-footprints:R_0402_1005Metric"
		(layer "B.Cu")
		(at 109 85.42)
		(descr "Resistor SMD 0402")
		(tags "resistor SMD 0402")
		(property "Reference" "R17"
			(at 1 -0.42 180)
			(layer "B.SilkS")
			(effects
				(font
					(size 0.7 0.7)
					(thickness 0.15)
				)
				(justify left bottom mirror)
			)
		)
		(property "Value" "R_0R_0402"
			(at 0 -1.4 180)
			(layer "B.Fab")
			(effects
				(font
					(size 0.7 0.7)
					(thickness 0.15)
				)
				(justify left bottom mirror)
			)
		)
		(property "Footprint" "antmicro-footprints:R_0402_1005Metric"
			(at 0 0 0)
			(layer "F.Fab")
			(hide yes)
			(effects
				(font
					(size 1.27 1.27)
					(thickness 0.15)
				)
			)
		)
		(property "Datasheet" "https://industrial.panasonic.com/cdbs/www-data/pdf/RDA0000/AOA0000C301.pdf"
			(at 0 0 0)
			(layer "F.Fab")
			(hide yes)
			(effects
				(font
					(size 1.27 1.27)
					(thickness 0.15)
				)
			)
		)
		(property "Author" "Antmicro"
			(at 0 0 0)
			(layer "B.Fab")
			(hide yes)
			(effects
				(font
					(size 1 1)
					(thickness 0.15)
				)
				(justify mirror)
			)
		)
		(property "Current" "1A"
			(at 0 0 0)
			(layer "B.Fab")
			(hide yes)
			(effects
				(font
					(size 1 1)
					(thickness 0.15)
				)
				(justify mirror)
			)
		)
		(property "License" "Apache-2.0"
			(at 0 0 0)
			(layer "B.Fab")
			(hide yes)
			(effects
				(font
					(size 1 1)
					(thickness 0.15)
				)
				(justify mirror)
			)
		)
		(property "MPN" "ERJ2GE0R00X"
			(at 0 0 0)
			(layer "B.Fab")
			(hide yes)
			(effects
				(font
					(size 1 1)
					(thickness 0.15)
				)
				(justify mirror)
			)
		)
		(property "Manufacturer" "Panasonic"
			(at 0 0 0)
			(layer "B.Fab")
			(hide yes)
			(effects
				(font
					(size 1 1)
					(thickness 0.15)
				)
				(justify mirror)
			)
		)
		(property "Tolerance" ""
			(at 0 0 0)
			(layer "B.Fab")
			(hide yes)
			(effects
				(font
					(size 1 1)
					(thickness 0.15)
				)
				(justify mirror)
			)
		)
		(property "Val" "0R"
			(at 0 0 0)
			(layer "B.Fab")
			(hide yes)
			(effects
				(font
					(size 1 1)
					(thickness 0.15)
				)
				(justify mirror)
			)
		)
		(sheetname "M.2")
		(sheetfile "m-2.kicad_sch")
		(attr smd)
		(fp_rect
			(start -0.925 0.47)
			(end 0.925 -0.47)
			(stroke
				(width 0.05)
				(type default)
			)
			(fill none)
			(layer "B.CrtYd")
		)
		(fp_rect
			(start -0.5 0.25)
			(end 0.5 -0.25)
			(stroke
				(width 0.15)
				(type solid)
			)
			(fill none)
			(layer "B.Fab")
		)
		(fp_text user "License: Apache-2.0"
			(at -0.95 -5.169 180)
			(layer "B.Fab")
			(hide yes)
			(effects
				(font
					(size 0.7 0.7)
					(thickness 0.15)
				)
				(justify left bottom mirror)
			)
		)
		(fp_text user "${REFERENCE}"
			(at -0.95 -3.168 180)
			(layer "B.Fab")
			(hide yes)
			(effects
				(font
					(size 0.7 0.7)
					(thickness 0.15)
				)
				(justify left bottom mirror)
			)
		)
		(fp_text user "Author: Antmicro"
			(at -0.95 -4.169 180)
			(layer "B.Fab")
			(hide yes)
			(effects
				(font
					(size 0.7 0.7)
					(thickness 0.15)
				)
				(justify left bottom mirror)
			)
		)
		(pad "1" smd roundrect
			(at -0.48 0)
			(size 0.59 0.64)
			(layers "B.Cu" "B.Paste" "B.Mask")
			(roundrect_rratio 0.25)
			(net 454 "PCIE0_CLKREQ*")
			(pintype "passive")
		)
		(pad "2" smd roundrect
			(at 0.48 0)
			(size 0.59 0.64)
			(layers "B.Cu" "B.Paste" "B.Mask")
			(roundrect_rratio 0.25)
			(net 248 "/M.2/~{M2_M_CLKREQ0}")
			(pintype "passive")
		)
	)
	(footprint "antmicro-footprints:C_0603_1608Metric"
		(layer "B.Cu")
		(at 114.5 91.5 180)
		(descr "Capacitor SMD 0603")
		(tags "capacitor 0603")
		(property "Reference" "C22"
			(at -1.1 0.6 0)
			(layer "B.SilkS")
			(effects
				(font
					(size 0.7 0.7)
					(thickness 0.15)
				)
				(justify left bottom mirror)
			)
		)
		(property "Value" "C_10u_0603"
			(at 0 -1.6 0)
			(layer "B.Fab")
			(effects
				(font
					(size 0.7 0.7)
					(thickness 0.15)
				)
				(justify left bottom mirror)
			)
		)
		(property "Footprint" "antmicro-footprints:C_0603_1608Metric"
			(at 0 0 180)
			(layer "F.Fab")
			(hide yes)
			(effects
				(font
					(size 1.27 1.27)
					(thickness 0.15)
				)
			)
		)
		(property "Datasheet" "https://www.murata.com/products/productdetail?partno=GRM188R61A106KE69%23"
			(at 0 0 180)
			(layer "F.Fab")
			(hide yes)
			(effects
				(font
					(size 1.27 1.27)
					(thickness 0.15)
				)
			)
		)
		(property "Author" "Antmicro"
			(at 229 183 0)
			(layer "B.Fab")
			(hide yes)
			(effects
				(font
					(size 1 1)
					(thickness 0.15)
				)
				(justify mirror)
			)
		)
		(property "Dielectric" "template_dielectric"
			(at 229 183 0)
			(layer "B.Fab")
			(hide yes)
			(effects
				(font
					(size 1 1)
					(thickness 0.15)
				)
				(justify mirror)
			)
		)
		(property "License" "Apache-2.0"
			(at 229 183 0)
			(layer "B.Fab")
			(hide yes)
			(effects
				(font
					(size 1 1)
					(thickness 0.15)
				)
				(justify mirror)
			)
		)
		(property "MPN" "GRM188R61A106KE69D"
			(at 229 183 0)
			(layer "B.Fab")
			(hide yes)
			(effects
				(font
					(size 1 1)
					(thickness 0.15)
				)
				(justify mirror)
			)
		)
		(property "Manufacturer" "Murata"
			(at 229 183 0)
			(layer "B.Fab")
			(hide yes)
			(effects
				(font
					(size 1 1)
					(thickness 0.15)
				)
				(justify mirror)
			)
		)
		(property "Val" "10u"
			(at 229 183 0)
			(layer "B.Fab")
			(hide yes)
			(effects
				(font
					(size 1 1)
					(thickness 0.15)
				)
				(justify mirror)
			)
		)
		(property "Voltage" ""
			(at 229 183 0)
			(layer "B.Fab")
			(hide yes)
			(effects
				(font
					(size 1 1)
					(thickness 0.15)
				)
				(justify mirror)
			)
		)
		(sheetname "M.2")
		(sheetfile "m-2.kicad_sch")
		(attr smd)
		(fp_line
			(start 0.15 0.4)
			(end -0.15 0.4)
			(stroke
				(width 0.15)
				(type solid)
			)
			(layer "B.SilkS")
		)
		(fp_line
			(start 0.15 -0.4)
			(end -0.15 -0.4)
			(stroke
				(width 0.15)
				(type solid)
			)
			(layer "B.SilkS")
		)
		(fp_rect
			(start -1.25 0.65)
			(end 1.25 -0.65)
			(stroke
				(width 0.05)
				(type solid)
			)
			(fill none)
			(layer "B.CrtYd")
		)
		(fp_rect
			(start -0.8 0.4)
			(end 0.8 -0.4)
			(stroke
				(width 0.15)
				(type solid)
			)
			(fill none)
			(layer "B.Fab")
		)
		(fp_text user "Author: Antmicro"
			(at -1.682 -4.894 0)
			(layer "B.Fab")
			(hide yes)
			(effects
				(font
					(size 0.7 0.7)
					(thickness 0.15)
				)
				(justify left bottom mirror)
			)
		)
		(fp_text user "License: Apache-2.0"
			(at -1.682 -5.895 0)
			(layer "B.Fab")
			(hide yes)
			(effects
				(font
					(size 0.7 0.7)
					(thickness 0.15)
				)
				(justify left bottom mirror)
			)
		)
		(fp_text user "${REFERENCE}"
			(at -1.682 -3.895 0)
			(layer "B.Fab")
			(hide yes)
			(effects
				(font
					(size 0.7 0.7)
					(thickness 0.15)
				)
				(justify left bottom mirror)
			)
		)
		(pad "1" smd roundrect
			(at -0.7 0 180)
			(size 0.8 1)
			(layers "B.Cu" "B.Paste" "B.Mask")
			(roundrect_rratio 0.2)
			(net 635 "/M.2/3V3_M2")
			(pintype "passive")
		)
		(pad "2" smd roundrect
			(at 0.7 0 180)
			(size 0.8 1)
			(layers "B.Cu" "B.Paste" "B.Mask")
			(roundrect_rratio 0.2)
			(net 1 "GND")
			(pintype "passive")
		)
	)
	(footprint "antmicro-footprints:R_0402_1005Metric"
		(layer "B.Cu")
		(at 60.55 124.8 -90)
		(descr "Resistor SMD 0402")
		(tags "resistor SMD 0402")
		(property "Reference" "R105"
			(at -1.83 -1.39 90)
			(layer "B.SilkS")
			(effects
				(font
					(size 0.7 0.7)
					(thickness 0.15)
				)
				(justify left bottom mirror)
			)
		)
		(property "Value" "R_4k7_0402"
			(at 0 -1.4 90)
			(layer "B.Fab")
			(effects
				(font
					(size 0.7 0.7)
					(thickness 0.15)
				)
				(justify left bottom mirror)
			)
		)
		(property "Footprint" "antmicro-footprints:R_0402_1005Metric"
			(at 0 0 -90)
			(layer "F.Fab")
			(hide yes)
			(effects
				(font
					(size 1.27 1.27)
					(thickness 0.15)
				)
			)
		)
		(property "Datasheet" "https://www.bourns.com/docs/product-datasheets/cr.pdf"
			(at 0 0 -90)
			(layer "F.Fab")
			(hide yes)
			(effects
				(font
					(size 1.27 1.27)
					(thickness 0.15)
				)
			)
		)
		(property "Author" "Antmicro"
			(at -64.25 185.35 0)
			(layer "B.Fab")
			(hide yes)
			(effects
				(font
					(size 1 1)
					(thickness 0.15)
				)
				(justify mirror)
			)
		)
		(property "License" "Apache-2.0"
			(at -64.25 185.35 0)
			(layer "B.Fab")
			(hide yes)
			(effects
				(font
					(size 1 1)
					(thickness 0.15)
				)
				(justify mirror)
			)
		)
		(property "MPN" "CR0402-FX-4701GLF"
			(at -64.25 185.35 0)
			(layer "B.Fab")
			(hide yes)
			(effects
				(font
					(size 1 1)
					(thickness 0.15)
				)
				(justify mirror)
			)
		)
		(property "Manufacturer" "Bourns"
			(at -64.25 185.35 0)
			(layer "B.Fab")
			(hide yes)
			(effects
				(font
					(size 1 1)
					(thickness 0.15)
				)
				(justify mirror)
			)
		)
		(property "Tolerance" "1%"
			(at -64.25 185.35 0)
			(layer "B.Fab")
			(hide yes)
			(effects
				(font
					(size 1 1)
					(thickness 0.15)
				)
				(justify mirror)
			)
		)
		(property "Val" "4k7"
			(at -64.25 185.35 0)
			(layer "B.Fab")
			(hide yes)
			(effects
				(font
					(size 1 1)
					(thickness 0.15)
				)
				(justify mirror)
			)
		)
		(sheetname "USB Debug, DP")
		(sheetfile "usb.kicad_sch")
		(attr smd)
		(fp_rect
			(start -0.925 0.47)
			(end 0.925 -0.47)
			(stroke
				(width 0.05)
				(type default)
			)
			(fill none)
			(layer "B.CrtYd")
		)
		(fp_rect
			(start -0.5 0.25)
			(end 0.5 -0.25)
			(stroke
				(width 0.15)
				(type solid)
			)
			(fill none)
			(layer "B.Fab")
		)
		(fp_text user "${REFERENCE}"
			(at -0.95 -3.168 90)
			(layer "B.Fab")
			(hide yes)
			(effects
				(font
					(size 0.7 0.7)
					(thickness 0.15)
				)
				(justify left bottom mirror)
			)
		)
		(fp_text user "License: Apache-2.0"
			(at -0.95 -5.169 90)
			(layer "B.Fab")
			(hide yes)
			(effects
				(font
					(size 0.7 0.7)
					(thickness 0.15)
				)
				(justify left bottom mirror)
			)
		)
		(fp_text user "Author: Antmicro"
			(at -0.95 -4.169 90)
			(layer "B.Fab")
			(hide yes)
			(effects
				(font
					(size 0.7 0.7)
					(thickness 0.15)
				)
				(justify left bottom mirror)
			)
		)
		(pad "1" smd roundrect
			(at -0.48 0 270)
			(size 0.59 0.64)
			(layers "B.Cu" "B.Paste" "B.Mask")
			(roundrect_rratio 0.25)
			(net 196 "/USB Debug, DP/USBC3_VBUS")
			(pintype "passive")
		)
		(pad "2" smd roundrect
			(at 0.48 0 270)
			(size 0.59 0.64)
			(layers "B.Cu" "B.Paste" "B.Mask")
			(roundrect_rratio 0.25)
			(net 146 "Net-(D8-A)")
			(pintype "passive")
		)
	)
	(footprint "antmicro-footprints:R_0402_1005Metric"
		(layer "B.Cu")
		(at 52.3 90.95)
		(descr "Resistor SMD 0402")
		(tags "resistor SMD 0402")
		(property "Reference" "R146"
			(at 1.39 1.1 180)
			(layer "B.SilkS")
			(effects
				(font
					(size 0.6 0.6)
					(thickness 0.15)
				)
				(justify left bottom mirror)
			)
		)
		(property "Value" "R_24k9_0402"
			(at 0 -1.4 180)
			(layer "B.Fab")
			(effects
				(font
					(size 0.7 0.7)
					(thickness 0.15)
				)
				(justify left bottom mirror)
			)
		)
		(property "Footprint" "antmicro-footprints:R_0402_1005Metric"
			(at 0 0 0)
			(layer "F.Fab")
			(hide yes)
			(effects
				(font
					(size 1.27 1.27)
					(thickness 0.15)
				)
			)
		)
		(property "Datasheet" "https://www.bourns.com/docs/product-datasheets/cr.pdf"
			(at 0 0 0)
			(layer "F.Fab")
			(hide yes)
			(effects
				(font
					(size 1.27 1.27)
					(thickness 0.15)
				)
			)
		)
		(property "Author" "Antmicro"
			(at 0 0 0)
			(layer "B.Fab")
			(hide yes)
			(effects
				(font
					(size 1 1)
					(thickness 0.15)
				)
				(justify mirror)
			)
		)
		(property "License" "Apache-2.0"
			(at 0 0 0)
			(layer "B.Fab")
			(hide yes)
			(effects
				(font
					(size 1 1)
					(thickness 0.15)
				)
				(justify mirror)
			)
		)
		(property "MPN" "CR0402-FX-2492GLF"
			(at 0 0 0)
			(layer "B.Fab")
			(hide yes)
			(effects
				(font
					(size 1 1)
					(thickness 0.15)
				)
				(justify mirror)
			)
		)
		(property "Manufacturer" "Bourns"
			(at 0 0 0)
			(layer "B.Fab")
			(hide yes)
			(effects
				(font
					(size 1 1)
					(thickness 0.15)
				)
				(justify mirror)
			)
		)
		(property "Tolerance" "1%"
			(at 0 0 0)
			(layer "B.Fab")
			(hide yes)
			(effects
				(font
					(size 1 1)
					(thickness 0.15)
				)
				(justify mirror)
			)
		)
		(property "Val" "24k9"
			(at 0 0 0)
			(layer "B.Fab")
			(hide yes)
			(effects
				(font
					(size 1 1)
					(thickness 0.15)
				)
				(justify mirror)
			)
		)
		(sheetname "Ethernet")
		(sheetfile "ethernet.kicad_sch")
		(attr smd)
		(fp_rect
			(start -0.925 0.47)
			(end 0.925 -0.47)
			(stroke
				(width 0.05)
				(type default)
			)
			(fill none)
			(layer "B.CrtYd")
		)
		(fp_rect
			(start -0.5 0.25)
			(end 0.5 -0.25)
			(stroke
				(width 0.15)
				(type solid)
			)
			(fill none)
			(layer "B.Fab")
		)
		(fp_text user "Author: Antmicro"
			(at -0.95 -4.169 180)
			(layer "B.Fab")
			(hide yes)
			(effects
				(font
					(size 0.7 0.7)
					(thickness 0.15)
				)
				(justify left bottom mirror)
			)
		)
		(fp_text user "${REFERENCE}"
			(at -0.95 -3.168 180)
			(layer "B.Fab")
			(hide yes)
			(effects
				(font
					(size 0.7 0.7)
					(thickness 0.15)
				)
				(justify left bottom mirror)
			)
		)
		(fp_text user "License: Apache-2.0"
			(at -0.95 -5.169 180)
			(layer "B.Fab")
			(hide yes)
			(effects
				(font
					(size 0.7 0.7)
					(thickness 0.15)
				)
				(justify left bottom mirror)
			)
		)
		(pad "1" smd roundrect
			(at -0.48 0)
			(size 0.59 0.64)
			(layers "B.Cu" "B.Paste" "B.Mask")
			(roundrect_rratio 0.25)
			(net 570 "/Ethernet/DEN")
			(pintype "passive")
		)
		(pad "2" smd roundrect
			(at 0.48 0)
			(size 0.59 0.64)
			(layers "B.Cu" "B.Paste" "B.Mask")
			(roundrect_rratio 0.25)
			(net 105 "/Ethernet/VDD")
			(pintype "passive")
		)
	)
	(footprint "antmicro-footprints:R_0402_1005Metric"
		(layer "B.Cu")
		(at 75 108.3 90)
		(descr "Resistor SMD 0402")
		(tags "resistor SMD 0402")
		(property "Reference" "R98"
			(at -0.63 2.37 -90)
			(layer "B.SilkS")
			(effects
				(font
					(size 0.7 0.7)
					(thickness 0.15)
				)
				(justify left bottom mirror)
			)
		)
		(property "Value" "R_1k_0402"
			(at 0 -1.4 -90)
			(layer "B.Fab")
			(effects
				(font
					(size 0.7 0.7)
					(thickness 0.15)
				)
				(justify left bottom mirror)
			)
		)
		(property "Footprint" "antmicro-footprints:R_0402_1005Metric"
			(at 0 0 90)
			(layer "F.Fab")
			(hide yes)
			(effects
				(font
					(size 1.27 1.27)
					(thickness 0.15)
				)
			)
		)
		(property "Datasheet" "https://www.bourns.com/docs/product-datasheets/cr.pdf"
			(at 0 0 90)
			(layer "F.Fab")
			(hide yes)
			(effects
				(font
					(size 1.27 1.27)
					(thickness 0.15)
				)
			)
		)
		(property "Author" "Antmicro"
			(at 183.3 33.3 0)
			(layer "B.Fab")
			(hide yes)
			(effects
				(font
					(size 1 1)
					(thickness 0.15)
				)
				(justify mirror)
			)
		)
		(property "License" "Apache-2.0"
			(at 183.3 33.3 0)
			(layer "B.Fab")
			(hide yes)
			(effects
				(font
					(size 1 1)
					(thickness 0.15)
				)
				(justify mirror)
			)
		)
		(property "MPN" "CR0402-FX-1001GLF"
			(at 183.3 33.3 0)
			(layer "B.Fab")
			(hide yes)
			(effects
				(font
					(size 1 1)
					(thickness 0.15)
				)
				(justify mirror)
			)
		)
		(property "Manufacturer" "Bourns"
			(at 183.3 33.3 0)
			(layer "B.Fab")
			(hide yes)
			(effects
				(font
					(size 1 1)
					(thickness 0.15)
				)
				(justify mirror)
			)
		)
		(property "Tolerance" "1%"
			(at 183.3 33.3 0)
			(layer "B.Fab")
			(hide yes)
			(effects
				(font
					(size 1 1)
					(thickness 0.15)
				)
				(justify mirror)
			)
		)
		(property "Val" "1k"
			(at 183.3 33.3 0)
			(layer "B.Fab")
			(hide yes)
			(effects
				(font
					(size 1 1)
					(thickness 0.15)
				)
				(justify mirror)
			)
		)
		(sheetname "USB Debug, DP")
		(sheetfile "usb.kicad_sch")
		(attr smd)
		(fp_rect
			(start -0.925 0.47)
			(end 0.925 -0.47)
			(stroke
				(width 0.05)
				(type default)
			)
			(fill none)
			(layer "B.CrtYd")
		)
		(fp_rect
			(start -0.5 0.25)
			(end 0.5 -0.25)
			(stroke
				(width 0.15)
				(type solid)
			)
			(fill none)
			(layer "B.Fab")
		)
		(fp_text user "${REFERENCE}"
			(at -0.95 -3.168 -90)
			(layer "B.Fab")
			(hide yes)
			(effects
				(font
					(size 0.7 0.7)
					(thickness 0.15)
				)
				(justify left bottom mirror)
			)
		)
		(fp_text user "License: Apache-2.0"
			(at -0.95 -5.169 -90)
			(layer "B.Fab")
			(hide yes)
			(effects
				(font
					(size 0.7 0.7)
					(thickness 0.15)
				)
				(justify left bottom mirror)
			)
		)
		(fp_text user "Author: Antmicro"
			(at -0.95 -4.169 -90)
			(layer "B.Fab")
			(hide yes)
			(effects
				(font
					(size 0.7 0.7)
					(thickness 0.15)
				)
				(justify left bottom mirror)
			)
		)
		(pad "1" smd roundrect
			(at -0.48 0 90)
			(size 0.59 0.64)
			(layers "B.Cu" "B.Paste" "B.Mask")
			(roundrect_rratio 0.25)
			(net 310 "/USB Debug, DP/USBC0_EQ1")
			(pintype "passive")
		)
		(pad "2" smd roundrect
			(at 0.48 0 90)
			(size 0.59 0.64)
			(layers "B.Cu" "B.Paste" "B.Mask")
			(roundrect_rratio 0.25)
			(net 1 "GND")
			(pintype "passive")
		)
	)
	(footprint "antmicro-footprints:R_0402_1005Metric"
		(layer "B.Cu")
		(at 87.3 106.6 -90)
		(descr "Resistor SMD 0402")
		(tags "resistor SMD 0402")
		(property "Reference" "R217"
			(at -4.1 3.4 90)
			(layer "B.SilkS")
			(effects
				(font
					(size 0.7 0.7)
					(thickness 0.15)
				)
				(justify left bottom mirror)
			)
		)
		(property "Value" "R_0R_0402"
			(at 0 -1.4 90)
			(layer "B.Fab")
			(effects
				(font
					(size 0.7 0.7)
					(thickness 0.15)
				)
				(justify left bottom mirror)
			)
		)
		(property "Footprint" "antmicro-footprints:R_0402_1005Metric"
			(at 0 0 -90)
			(layer "F.Fab")
			(hide yes)
			(effects
				(font
					(size 1.27 1.27)
					(thickness 0.15)
				)
			)
		)
		(property "Datasheet" "https://industrial.panasonic.com/cdbs/www-data/pdf/RDA0000/AOA0000C301.pdf"
			(at 0 0 -90)
			(layer "F.Fab")
			(hide yes)
			(effects
				(font
					(size 1.27 1.27)
					(thickness 0.15)
				)
			)
		)
		(property "Author" "Antmicro"
			(at -19.3 193.9 0)
			(layer "B.Fab")
			(hide yes)
			(effects
				(font
					(size 1 1)
					(thickness 0.15)
				)
				(justify mirror)
			)
		)
		(property "Current" "1A"
			(at -19.3 193.9 0)
			(layer "B.Fab")
			(hide yes)
			(effects
				(font
					(size 1 1)
					(thickness 0.15)
				)
				(justify mirror)
			)
		)
		(property "License" "Apache-2.0"
			(at -19.3 193.9 0)
			(layer "B.Fab")
			(hide yes)
			(effects
				(font
					(size 1 1)
					(thickness 0.15)
				)
				(justify mirror)
			)
		)
		(property "MPN" "ERJ2GE0R00X"
			(at -19.3 193.9 0)
			(layer "B.Fab")
			(hide yes)
			(effects
				(font
					(size 1 1)
					(thickness 0.15)
				)
				(justify mirror)
			)
		)
		(property "Manufacturer" "Panasonic"
			(at -19.3 193.9 0)
			(layer "B.Fab")
			(hide yes)
			(effects
				(font
					(size 1 1)
					(thickness 0.15)
				)
				(justify mirror)
			)
		)
		(property "Tolerance" ""
			(at -19.3 193.9 0)
			(layer "B.Fab")
			(hide yes)
			(effects
				(font
					(size 1 1)
					(thickness 0.15)
				)
				(justify mirror)
			)
		)
		(property "Val" "0R"
			(at -19.3 193.9 0)
			(layer "B.Fab")
			(hide yes)
			(effects
				(font
					(size 1 1)
					(thickness 0.15)
				)
				(justify mirror)
			)
		)
		(sheetname "Peripherals")
		(sheetfile "peripherals.kicad_sch")
		(attr smd)
		(fp_rect
			(start -0.925 0.47)
			(end 0.925 -0.47)
			(stroke
				(width 0.05)
				(type default)
			)
			(fill none)
			(layer "B.CrtYd")
		)
		(fp_rect
			(start -0.5 0.25)
			(end 0.5 -0.25)
			(stroke
				(width 0.15)
				(type solid)
			)
			(fill none)
			(layer "B.Fab")
		)
		(fp_text user "${REFERENCE}"
			(at -0.95 -3.168 90)
			(layer "B.Fab")
			(hide yes)
			(effects
				(font
					(size 0.7 0.7)
					(thickness 0.15)
				)
				(justify left bottom mirror)
			)
		)
		(fp_text user "Author: Antmicro"
			(at -0.95 -4.169 90)
			(layer "B.Fab")
			(hide yes)
			(effects
				(font
					(size 0.7 0.7)
					(thickness 0.15)
				)
				(justify left bottom mirror)
			)
		)
		(fp_text user "License: Apache-2.0"
			(at -0.95 -5.169 90)
			(layer "B.Fab")
			(hide yes)
			(effects
				(font
					(size 0.7 0.7)
					(thickness 0.15)
				)
				(justify left bottom mirror)
			)
		)
		(pad "1" smd roundrect
			(at -0.48 0 270)
			(size 0.59 0.64)
			(layers "B.Cu" "B.Paste" "B.Mask")
			(roundrect_rratio 0.25)
			(net 87 "+3V3")
			(pintype "passive")
		)
		(pad "2" smd roundrect
			(at 0.48 0 270)
			(size 0.59 0.64)
			(layers "B.Cu" "B.Paste" "B.Mask")
			(roundrect_rratio 0.25)
			(net 351 "/Peripherals/GPIOEX_RESET")
			(pintype "passive")
		)
	)
	(footprint "antmicro-footprints:R_0402_1005Metric"
		(layer "B.Cu")
		(at 112.4 105.1 180)
		(descr "Resistor SMD 0402")
		(tags "resistor SMD 0402")
		(property "Reference" "R245"
			(at -3.78 -0.28 0)
			(layer "B.SilkS")
			(effects
				(font
					(size 0.7 0.7)
					(thickness 0.15)
				)
				(justify left bottom mirror)
			)
		)
		(property "Value" "R_0R_0402"
			(at 0 -1.4 0)
			(layer "B.Fab")
			(effects
				(font
					(size 0.7 0.7)
					(thickness 0.15)
				)
				(justify left bottom mirror)
			)
		)
		(property "Footprint" "antmicro-footprints:R_0402_1005Metric"
			(at 0 0 180)
			(layer "F.Fab")
			(hide yes)
			(effects
				(font
					(size 1.27 1.27)
					(thickness 0.15)
				)
			)
		)
		(property "Datasheet" "https://industrial.panasonic.com/cdbs/www-data/pdf/RDA0000/AOA0000C301.pdf"
			(at 0 0 180)
			(layer "F.Fab")
			(hide yes)
			(effects
				(font
					(size 1.27 1.27)
					(thickness 0.15)
				)
			)
		)
		(property "Author" "Antmicro"
			(at 224.8 210.2 0)
			(layer "B.Fab")
			(hide yes)
			(effects
				(font
					(size 1 1)
					(thickness 0.15)
				)
				(justify mirror)
			)
		)
		(property "Current" "1A"
			(at 224.8 210.2 0)
			(layer "B.Fab")
			(hide yes)
			(effects
				(font
					(size 1 1)
					(thickness 0.15)
				)
				(justify mirror)
			)
		)
		(property "License" "Apache-2.0"
			(at 224.8 210.2 0)
			(layer "B.Fab")
			(hide yes)
			(effects
				(font
					(size 1 1)
					(thickness 0.15)
				)
				(justify mirror)
			)
		)
		(property "MPN" "ERJ2GE0R00X"
			(at 224.8 210.2 0)
			(layer "B.Fab")
			(hide yes)
			(effects
				(font
					(size 1 1)
					(thickness 0.15)
				)
				(justify mirror)
			)
		)
		(property "Manufacturer" "Panasonic"
			(at 224.8 210.2 0)
			(layer "B.Fab")
			(hide yes)
			(effects
				(font
					(size 1 1)
					(thickness 0.15)
				)
				(justify mirror)
			)
		)
		(property "Tolerance" ""
			(at 224.8 210.2 0)
			(layer "B.Fab")
			(hide yes)
			(effects
				(font
					(size 1 1)
					(thickness 0.15)
				)
				(justify mirror)
			)
		)
		(property "Val" "0R"
			(at 224.8 210.2 0)
			(layer "B.Fab")
			(hide yes)
			(effects
				(font
					(size 1 1)
					(thickness 0.15)
				)
				(justify mirror)
			)
		)
		(sheetname "USB3")
		(sheetfile "usb3.kicad_sch")
		(attr smd exclude_from_pos_files exclude_from_bom dnp)
		(fp_rect
			(start -0.925 0.47)
			(end 0.925 -0.47)
			(stroke
				(width 0.05)
				(type default)
			)
			(fill none)
			(layer "B.CrtYd")
		)
		(fp_rect
			(start -0.5 0.25)
			(end 0.5 -0.25)
			(stroke
				(width 0.15)
				(type solid)
			)
			(fill none)
			(layer "B.Fab")
		)
		(fp_text user "${REFERENCE}"
			(at -0.95 -3.168 0)
			(layer "B.Fab")
			(hide yes)
			(effects
				(font
					(size 0.7 0.7)
					(thickness 0.15)
				)
				(justify left bottom mirror)
			)
		)
		(fp_text user "License: Apache-2.0"
			(at -0.95 -5.169 0)
			(layer "B.Fab")
			(hide yes)
			(effects
				(font
					(size 0.7 0.7)
					(thickness 0.15)
				)
				(justify left bottom mirror)
			)
		)
		(fp_text user "Author: Antmicro"
			(at -0.95 -4.169 0)
			(layer "B.Fab")
			(hide yes)
			(effects
				(font
					(size 0.7 0.7)
					(thickness 0.15)
				)
				(justify left bottom mirror)
			)
		)
		(pad "1" smd roundrect
			(at -0.48 0 180)
			(size 0.59 0.64)
			(layers "B.Cu" "B.Paste" "B.Mask")
			(roundrect_rratio 0.25)
			(net 714 "GPIO010")
			(pintype "passive")
		)
		(pad "2" smd roundrect
			(at 0.48 0 180)
			(size 0.59 0.64)
			(layers "B.Cu" "B.Paste" "B.Mask")
			(roundrect_rratio 0.25)
			(net 317 "/USB3/~{USBC1_INT}")
			(pintype "passive")
		)
	)
	(footprint "antmicro-footprints:FB_0805_2012Metric"
		(layer "B.Cu")
		(at 47.8 93.6375 90)
		(descr "FERRITE BEAD 0805")
		(tags "FERRITE BEAD 0805")
		(property "Reference" "FB3"
			(at 0.5575 -0.97 -90)
			(layer "B.SilkS")
			(effects
				(font
					(size 0.7 0.7)
					(thickness 0.15)
				)
				(justify left bottom mirror)
			)
		)
		(property "Value" "FB_220Z_2A_Murata-BLM21PG_0805"
			(at 0 -1.8 -90)
			(layer "B.Fab")
			(effects
				(font
					(size 0.7 0.7)
					(thickness 0.15)
				)
				(justify left bottom mirror)
			)
		)
		(property "Footprint" "antmicro-footprints:FB_0805_2012Metric"
			(at 0 0 90)
			(layer "F.Fab")
			(hide yes)
			(effects
				(font
					(size 1.27 1.27)
					(thickness 0.15)
				)
			)
		)
		(property "Datasheet" "https://www.murata.com/products/productdata/8796738977822/ENFA0005.pdf?1653276712000"
			(at 0 0 90)
			(layer "F.Fab")
			(hide yes)
			(effects
				(font
					(size 1.27 1.27)
					(thickness 0.15)
				)
			)
		)
		(property "Author" "Antmicro"
			(at 141.4375 45.8375 0)
			(layer "B.Fab")
			(hide yes)
			(effects
				(font
					(size 1 1)
					(thickness 0.15)
				)
				(justify mirror)
			)
		)
		(property "Current" ""
			(at 141.4375 45.8375 0)
			(layer "B.Fab")
			(hide yes)
			(effects
				(font
					(size 1 1)
					(thickness 0.15)
				)
				(justify mirror)
			)
		)
		(property "License" "Apache-2.0"
			(at 141.4375 45.8375 0)
			(layer "B.Fab")
			(hide yes)
			(effects
				(font
					(size 1 1)
					(thickness 0.15)
				)
				(justify mirror)
			)
		)
		(property "MPN" "BLM21PG221SN1D"
			(at 141.4375 45.8375 0)
			(layer "B.Fab")
			(hide yes)
			(effects
				(font
					(size 1 1)
					(thickness 0.15)
				)
				(justify mirror)
			)
		)
		(property "Manufacturer" "Murata"
			(at 141.4375 45.8375 0)
			(layer "B.Fab")
			(hide yes)
			(effects
				(font
					(size 1 1)
					(thickness 0.15)
				)
				(justify mirror)
			)
		)
		(property "Val" "220Z/2A"
			(at 141.4375 45.8375 0)
			(layer "B.Fab")
			(hide yes)
			(effects
				(font
					(size 1 1)
					(thickness 0.15)
				)
				(justify mirror)
			)
		)
		(sheetname "Ethernet")
		(sheetfile "ethernet.kicad_sch")
		(attr smd)
		(fp_line
			(start 0.281 -0.698)
			(end -0.319 -0.698)
			(stroke
				(width 0.15)
				(type solid)
			)
			(layer "B.SilkS")
		)
		(fp_line
			(start 0.299 0.698)
			(end -0.299 0.698)
			(stroke
				(width 0.15)
				(type solid)
			)
			(layer "B.SilkS")
		)
		(fp_rect
			(start 1.95 0.9)
			(end -1.95 -0.9)
			(stroke
				(width 0.05)
				(type default)
			)
			(fill none)
			(layer "B.CrtYd")
		)
		(fp_line
			(start 0.948 -0.681)
			(end -0.948 -0.681)
			(stroke
				(width 0.15)
				(type solid)
			)
			(layer "B.Fab")
		)
		(fp_line
			(start 0.948 -0.676)
			(end 0.948 0.676)
			(stroke
				(width 0.15)
				(type solid)
			)
			(layer "B.Fab")
		)
		(fp_line
			(start -0.948 -0.676)
			(end -0.948 0.676)
			(stroke
				(width 0.15)
				(type solid)
			)
			(layer "B.Fab")
		)
		(fp_line
			(start 0.948 0.681)
			(end -0.948 0.681)
			(stroke
				(width 0.15)
				(type solid)
			)
			(layer "B.Fab")
		)
		(fp_text user "Author: Antmicro"
			(at -1.9 -4.4 -90)
			(layer "B.Fab")
			(hide yes)
			(effects
				(font
					(size 0.7 0.7)
					(thickness 0.15)
				)
				(justify left bottom mirror)
			)
		)
		(fp_text user "${REFERENCE}"
			(at -1.9 -3.1 -90)
			(layer "B.Fab")
			(hide yes)
			(effects
				(font
					(size 0.7 0.7)
					(thickness 0.15)
				)
				(justify left bottom mirror)
			)
		)
		(fp_text user "License: Apache-2.0"
			(at -1.9 -5.75 -90)
			(layer "B.Fab")
			(hide yes)
			(effects
				(font
					(size 0.7 0.7)
					(thickness 0.15)
				)
				(justify left bottom mirror)
			)
		)
		(pad "1" smd roundrect
			(at -1.1 0 90)
			(size 1.2 1.3)
			(layers "B.Cu" "B.Paste" "B.Mask")
			(roundrect_rratio 0.25)
			(net 148 "Net-(D12-Pad1)")
			(pintype "passive")
		)
		(pad "2" smd roundrect
			(at 1.1 0 90)
			(size 1.2 1.3)
			(layers "B.Cu" "B.Paste" "B.Mask")
			(roundrect_rratio 0.25)
			(net 499 "/Ethernet/VSS")
			(pintype "passive")
		)
	)
	(footprint "antmicro-footprints:C_0402_1005Metric"
		(layer "B.Cu")
		(at 49.03 82.19)
		(descr "Capacitor SMD 0402")
		(tags "capacitor SMD 0402")
		(property "Reference" "C50"
			(at -1.105 0.51 0)
			(layer "B.SilkS")
			(effects
				(font
					(size 0.7 0.7)
					(thickness 0.15)
				)
				(justify right top mirror)
			)
		)
		(property "Value" "C_100n_0402"
			(at 0 -1.4 0)
			(layer "B.Fab")
			(effects
				(font
					(size 0.7 0.7)
					(thickness 0.15)
				)
				(justify right top mirror)
			)
		)
		(property "Footprint" "antmicro-footprints:C_0402_1005Metric"
			(at 0 0 0)
			(layer "F.Fab")
			(hide yes)
			(effects
				(font
					(size 1.27 1.27)
					(thickness 0.15)
				)
			)
		)
		(property "Datasheet" "https://www.murata.com/products/productdetail?partno=GRM155R61H104KE14%23"
			(at 0 0 0)
			(layer "F.Fab")
			(hide yes)
			(effects
				(font
					(size 1.27 1.27)
					(thickness 0.15)
				)
			)
		)
		(property "Author" "Antmicro"
			(at 134.58 27.68 90)
			(layer "B.Fab")
			(hide yes)
			(effects
				(font
					(size 1 1)
					(thickness 0.15)
				)
				(justify mirror)
			)
		)
		(property "Dielectric" "X5R"
			(at 134.58 27.68 90)
			(layer "B.Fab")
			(hide yes)
			(effects
				(font
					(size 1 1)
					(thickness 0.15)
				)
				(justify mirror)
			)
		)
		(property "License" "Apache-2.0"
			(at 134.58 27.68 90)
			(layer "B.Fab")
			(hide yes)
			(effects
				(font
					(size 1 1)
					(thickness 0.15)
				)
				(justify mirror)
			)
		)
		(property "MPN" "GRM155R61H104KE14D"
			(at 134.58 27.68 90)
			(layer "B.Fab")
			(hide yes)
			(effects
				(font
					(size 1 1)
					(thickness 0.15)
				)
				(justify mirror)
			)
		)
		(property "Manufacturer" "Murata"
			(at 134.58 27.68 90)
			(layer "B.Fab")
			(hide yes)
			(effects
				(font
					(size 1 1)
					(thickness 0.15)
				)
				(justify mirror)
			)
		)
		(property "Val" "100n"
			(at 134.58 27.68 90)
			(layer "B.Fab")
			(hide yes)
			(effects
				(font
					(size 1 1)
					(thickness 0.15)
				)
				(justify mirror)
			)
		)
		(property "Voltage" "50V"
			(at 134.58 27.68 90)
			(layer "B.Fab")
			(hide yes)
			(effects
				(font
					(size 1 1)
					(thickness 0.15)
				)
				(justify mirror)
			)
		)
		(sheetname "Supply")
		(sheetfile "supply.kicad_sch")
		(attr smd)
		(fp_rect
			(start -0.925 0.47)
			(end 0.925 -0.47)
			(stroke
				(width 0.05)
				(type default)
			)
			(fill none)
			(layer "B.CrtYd")
		)
		(fp_line
			(start -0.494 -0.248)
			(end 0.504 -0.248)
			(stroke
				(width 0.15)
				(type solid)
			)
			(layer "B.Fab")
		)
		(fp_line
			(start -0.494 0.25)
			(end -0.494 -0.248)
			(stroke
				(width 0.15)
				(type solid)
			)
			(layer "B.Fab")
		)
		(fp_line
			(start 0.504 -0.248)
			(end 0.504 0.25)
			(stroke
				(width 0.15)
				(type solid)
			)
			(layer "B.Fab")
		)
		(fp_line
			(start 0.504 0.25)
			(end -0.494 0.25)
			(stroke
				(width 0.15)
				(type solid)
			)
			(layer "B.Fab")
		)
		(fp_text user "License: Apache-2.0"
			(at -0.932 -5.17 0)
			(layer "B.Fab")
			(hide yes)
			(effects
				(font
					(size 0.7 0.7)
					(thickness 0.15)
				)
				(justify right top mirror)
			)
		)
		(fp_text user "Author: Antmicro"
			(at -0.932 -4.17 0)
			(layer "B.Fab")
			(hide yes)
			(effects
				(font
					(size 0.7 0.7)
					(thickness 0.15)
				)
				(justify right top mirror)
			)
		)
		(fp_text user "${REFERENCE}"
			(at -0.932 -3.168 0)
			(layer "B.Fab")
			(hide yes)
			(effects
				(font
					(size 0.7 0.7)
					(thickness 0.15)
				)
				(justify right top mirror)
			)
		)
		(pad "1" smd roundrect
			(at -0.48 0)
			(size 0.59 0.64)
			(layers "B.Cu" "B.Paste" "B.Mask")
			(roundrect_rratio 0.25)
			(net 135 "Net-(Q18-G)")
			(pintype "passive")
		)
		(pad "2" smd roundrect
			(at 0.48 0)
			(size 0.59 0.64)
			(layers "B.Cu" "B.Paste" "B.Mask")
			(roundrect_rratio 0.25)
			(net 115 "VCC")
			(pintype "passive")
		)
	)
	(footprint "antmicro-footprints:TP_SMD_0.75mm"
		(layer "B.Cu")
		(at 68.165 126.07)
		(property "Reference" "TP55"
			(at -0.56 0.8308 0)
			(layer "B.SilkS")
			(hide yes)
			(effects
				(font
					(size 0.7 0.7)
					(thickness 0.15)
				)
				(justify right bottom mirror)
			)
		)
		(property "Value" "TP_0.75mm_SMD"
			(at 0 -1.2 0)
			(layer "B.Fab")
			(effects
				(font
					(size 0.7 0.7)
					(thickness 0.15)
				)
				(justify right bottom mirror)
			)
		)
		(property "Footprint" "antmicro-footprints:TP_SMD_0.75mm"
			(at 0 0 0)
			(layer "F.Fab")
			(hide yes)
			(effects
				(font
					(size 1.27 1.27)
					(thickness 0.15)
				)
			)
		)
		(property "Author" "Antmicro"
			(at 0 0 0)
			(layer "B.Fab")
			(hide yes)
			(effects
				(font
					(size 1 1)
					(thickness 0.15)
				)
				(justify mirror)
			)
		)
		(property "License" "Apache-2.0"
			(at 0 0 0)
			(layer "B.Fab")
			(hide yes)
			(effects
				(font
					(size 1 1)
					(thickness 0.15)
				)
				(justify mirror)
			)
		)
		(property "MPN" ""
			(at 0 0 0)
			(layer "B.Fab")
			(hide yes)
			(effects
				(font
					(size 1 1)
					(thickness 0.15)
				)
				(justify mirror)
			)
		)
		(property "Manufacturer" ""
			(at 0 0 0)
			(layer "B.Fab")
			(hide yes)
			(effects
				(font
					(size 1 1)
					(thickness 0.15)
				)
				(justify mirror)
			)
		)
		(sheetname "Supply")
		(sheetfile "supply.kicad_sch")
		(attr exclude_from_pos_files exclude_from_bom)
		(fp_circle
			(center 0 0)
			(end 0.475 0)
			(stroke
				(width 0.05)
				(type default)
			)
			(fill none)
			(layer "B.CrtYd")
		)
		(fp_text user "Author: Antmicro"
			(at -0.4 -3.901 0)
			(layer "B.Fab")
			(hide yes)
			(effects
				(font
					(size 0.7 0.7)
					(thickness 0.15)
				)
				(justify right bottom mirror)
			)
		)
		(fp_text user "${REFERENCE}"
			(at -0.4 -2.7 0)
			(layer "B.Fab")
			(hide yes)
			(effects
				(font
					(size 0.7 0.7)
					(thickness 0.15)
				)
				(justify right bottom mirror)
			)
		)
		(fp_text user "License: Apache-2.0"
			(at -0.4 -5.101 0)
			(layer "B.Fab")
			(hide yes)
			(effects
				(font
					(size 0.7 0.7)
					(thickness 0.15)
				)
				(justify right bottom mirror)
			)
		)
		(pad "1" smd circle
			(at 0 0)
			(size 0.75 0.75)
			(layers "B.Cu" "B.Mask")
			(net 112 "+1V8")
			(pinfunction "1")
			(pintype "passive")
		)
	)
	(footprint "antmicro-footprints:R_0402_1005Metric"
		(layer "B.Cu")
		(at 111.6 88.02 90)
		(descr "Resistor SMD 0402")
		(tags "resistor SMD 0402")
		(property "Reference" "R37"
			(at 1.14 1.38 -90)
			(layer "B.SilkS")
			(effects
				(font
					(size 0.7 0.7)
					(thickness 0.15)
				)
				(justify left bottom mirror)
			)
		)
		(property "Value" "R_47k_0402"
			(at 0 -1.4 -90)
			(layer "B.Fab")
			(effects
				(font
					(size 0.7 0.7)
					(thickness 0.15)
				)
				(justify left bottom mirror)
			)
		)
		(property "Footprint" "antmicro-footprints:R_0402_1005Metric"
			(at 0 0 90)
			(layer "F.Fab")
			(hide yes)
			(effects
				(font
					(size 1.27 1.27)
					(thickness 0.15)
				)
			)
		)
		(property "Datasheet" "https://www.bourns.com/docs/product-datasheets/cr.pdf"
			(at 0 0 90)
			(layer "F.Fab")
			(hide yes)
			(effects
				(font
					(size 1.27 1.27)
					(thickness 0.15)
				)
			)
		)
		(property "Author" "Antmicro"
			(at 199.62 -23.58 0)
			(layer "B.Fab")
			(hide yes)
			(effects
				(font
					(size 1 1)
					(thickness 0.15)
				)
				(justify mirror)
			)
		)
		(property "License" "Apache-2.0"
			(at 199.62 -23.58 0)
			(layer "B.Fab")
			(hide yes)
			(effects
				(font
					(size 1 1)
					(thickness 0.15)
				)
				(justify mirror)
			)
		)
		(property "MPN" "CR0402-FX-4702GLF"
			(at 199.62 -23.58 0)
			(layer "B.Fab")
			(hide yes)
			(effects
				(font
					(size 1 1)
					(thickness 0.15)
				)
				(justify mirror)
			)
		)
		(property "Manufacturer" "Bourns"
			(at 199.62 -23.58 0)
			(layer "B.Fab")
			(hide yes)
			(effects
				(font
					(size 1 1)
					(thickness 0.15)
				)
				(justify mirror)
			)
		)
		(property "Tolerance" "1%"
			(at 199.62 -23.58 0)
			(layer "B.Fab")
			(hide yes)
			(effects
				(font
					(size 1 1)
					(thickness 0.15)
				)
				(justify mirror)
			)
		)
		(property "Val" "47k"
			(at 199.62 -23.58 0)
			(layer "B.Fab")
			(hide yes)
			(effects
				(font
					(size 1 1)
					(thickness 0.15)
				)
				(justify mirror)
			)
		)
		(sheetname "M.2")
		(sheetfile "m-2.kicad_sch")
		(attr smd exclude_from_pos_files exclude_from_bom dnp)
		(fp_rect
			(start -0.925 0.47)
			(end 0.925 -0.47)
			(stroke
				(width 0.05)
				(type default)
			)
			(fill none)
			(layer "B.CrtYd")
		)
		(fp_rect
			(start -0.5 0.25)
			(end 0.5 -0.25)
			(stroke
				(width 0.15)
				(type solid)
			)
			(fill none)
			(layer "B.Fab")
		)
		(fp_text user "License: Apache-2.0"
			(at -0.95 -5.169 -90)
			(layer "B.Fab")
			(hide yes)
			(effects
				(font
					(size 0.7 0.7)
					(thickness 0.15)
				)
				(justify left bottom mirror)
			)
		)
		(fp_text user "Author: Antmicro"
			(at -0.95 -4.169 -90)
			(layer "B.Fab")
			(hide yes)
			(effects
				(font
					(size 0.7 0.7)
					(thickness 0.15)
				)
				(justify left bottom mirror)
			)
		)
		(fp_text user "${REFERENCE}"
			(at -0.95 -3.168 -90)
			(layer "B.Fab")
			(hide yes)
			(effects
				(font
					(size 0.7 0.7)
					(thickness 0.15)
				)
				(justify left bottom mirror)
			)
		)
		(pad "1" smd roundrect
			(at -0.48 0 90)
			(size 0.59 0.64)
			(layers "B.Cu" "B.Paste" "B.Mask")
			(roundrect_rratio 0.25)
			(net 87 "+3V3")
			(pintype "passive")
		)
		(pad "2" smd roundrect
			(at 0.48 0 90)
			(size 0.59 0.64)
			(layers "B.Cu" "B.Paste" "B.Mask")
			(roundrect_rratio 0.25)
			(net 247 "/M.2/~{M2_M_PERST}")
			(pintype "passive")
		)
	)
	(footprint "antmicro-footprints:TP_SMD_0.75mm"
		(layer "B.Cu")
		(at 75.28 75.395 180)
		(property "Reference" "TP44"
			(at -0.37 0.51 0)
			(layer "B.SilkS")
			(effects
				(font
					(size 0.7 0.7)
					(thickness 0.15)
				)
				(justify left bottom mirror)
			)
		)
		(property "Value" "TP_0.75mm_SMD"
			(at 0 -1.2 0)
			(layer "B.Fab")
			(effects
				(font
					(size 0.7 0.7)
					(thickness 0.15)
				)
				(justify left bottom mirror)
			)
		)
		(property "Footprint" "antmicro-footprints:TP_SMD_0.75mm"
			(at 0 0 180)
			(layer "F.Fab")
			(hide yes)
			(effects
				(font
					(size 1.27 1.27)
					(thickness 0.15)
				)
			)
		)
		(property "Author" "Antmicro"
			(at 150.56 150.79 0)
			(layer "B.Fab")
			(hide yes)
			(effects
				(font
					(size 1 1)
					(thickness 0.15)
				)
				(justify mirror)
			)
		)
		(property "License" "Apache-2.0"
			(at 150.56 150.79 0)
			(layer "B.Fab")
			(hide yes)
			(effects
				(font
					(size 1 1)
					(thickness 0.15)
				)
				(justify mirror)
			)
		)
		(property "MPN" ""
			(at 150.56 150.79 0)
			(layer "B.Fab")
			(hide yes)
			(effects
				(font
					(size 1 1)
					(thickness 0.15)
				)
				(justify mirror)
			)
		)
		(property "Manufacturer" ""
			(at 150.56 150.79 0)
			(layer "B.Fab")
			(hide yes)
			(effects
				(font
					(size 1 1)
					(thickness 0.15)
				)
				(justify mirror)
			)
		)
		(sheetname "SoM")
		(sheetfile "som.kicad_sch")
		(attr exclude_from_pos_files exclude_from_bom)
		(fp_circle
			(center 0 0)
			(end 0.475 0)
			(stroke
				(width 0.05)
				(type default)
			)
			(fill none)
			(layer "B.CrtYd")
		)
		(fp_text user "Author: Antmicro"
			(at -0.4 -3.901 0)
			(layer "B.Fab")
			(hide yes)
			(effects
				(font
					(size 0.7 0.7)
					(thickness 0.15)
				)
				(justify left bottom mirror)
			)
		)
		(fp_text user "${REFERENCE}"
			(at -0.4 -2.7 0)
			(layer "B.Fab")
			(hide yes)
			(effects
				(font
					(size 0.7 0.7)
					(thickness 0.15)
				)
				(justify left bottom mirror)
			)
		)
		(fp_text user "License: Apache-2.0"
			(at -0.4 -5.101 0)
			(layer "B.Fab")
			(hide yes)
			(effects
				(font
					(size 0.7 0.7)
					(thickness 0.15)
				)
				(justify left bottom mirror)
			)
		)
		(pad "1" smd circle
			(at 0 0 180)
			(size 0.75 0.75)
			(layers "B.Cu" "B.Mask")
			(net 750 "Net-(J15A-CLK_32K_OUT)")
			(pinfunction "1")
			(pintype "passive")
		)
	)
	(footprint "antmicro-footprints:LED_0603_1608Metric_G"
		(layer "B.Cu")
		(at 108.4 71.8 180)
		(descr "LED SMD 0603 Green")
		(tags "LED SMD 0603 Green")
		(property "Reference" "D25"
			(at 1.1 -0.45 0)
			(layer "B.SilkS")
			(effects
				(font
					(size 0.7 0.7)
					(thickness 0.15)
				)
				(justify left bottom mirror)
			)
		)
		(property "Value" "LED_G_0603_LTST-C190GKT"
			(at -0.001 -1.599 0)
			(layer "B.Fab")
			(effects
				(font
					(size 0.7 0.7)
					(thickness 0.15)
				)
				(justify left bottom mirror)
			)
		)
		(property "Footprint" "antmicro-footprints:LED_0603_1608Metric_G"
			(at 0 0 180)
			(layer "F.Fab")
			(hide yes)
			(effects
				(font
					(size 1.27 1.27)
					(thickness 0.15)
				)
			)
		)
		(property "Datasheet" "https://media.digikey.com/pdf/Data%20Sheets/Lite-On%20PDFs/LTST-C190GKT.pdf"
			(at 0 0 180)
			(layer "F.Fab")
			(hide yes)
			(effects
				(font
					(size 1.27 1.27)
					(thickness 0.15)
				)
			)
		)
		(property "Author" "Antmicro"
			(at 216.8 143.6 0)
			(layer "B.Fab")
			(hide yes)
			(effects
				(font
					(size 1 1)
					(thickness 0.15)
				)
				(justify mirror)
			)
		)
		(property "Color" "Green"
			(at 216.8 143.6 0)
			(layer "B.Fab")
			(hide yes)
			(effects
				(font
					(size 1 1)
					(thickness 0.15)
				)
				(justify mirror)
			)
		)
		(property "License" "Apache-2.0"
			(at 216.8 143.6 0)
			(layer "B.Fab")
			(hide yes)
			(effects
				(font
					(size 1 1)
					(thickness 0.15)
				)
				(justify mirror)
			)
		)
		(property "MPN" "LTST-C190GKT"
			(at 216.8 143.6 0)
			(layer "B.Fab")
			(hide yes)
			(effects
				(font
					(size 1 1)
					(thickness 0.15)
				)
				(justify mirror)
			)
		)
		(property "Manufacturer" "Lite-On"
			(at 216.8 143.6 0)
			(layer "B.Fab")
			(hide yes)
			(effects
				(font
					(size 1 1)
					(thickness 0.15)
				)
				(justify mirror)
			)
		)
		(sheetname "CSI")
		(sheetfile "csi.kicad_sch")
		(attr smd)
		(fp_line
			(start 0.24 -0.001)
			(end 0.105328 -0.001008)
			(stroke
				(width 0.1)
				(type solid)
			)
			(layer "B.SilkS")
		)
		(fp_line
			(start 0.105328 0.198992)
			(end 0.105328 -0.201008)
			(stroke
				(width 0.1)
				(type solid)
			)
			(layer "B.SilkS")
		)
		(fp_line
			(start 0.105328 0.198992)
			(end -0.094672 -0.001008)
			(stroke
				(width 0.1)
				(type solid)
			)
			(layer "B.SilkS")
		)
		(fp_line
			(start -0.094672 0.198992)
			(end -0.094672 -0.201008)
			(stroke
				(width 0.1)
				(type solid)
			)
			(layer "B.SilkS")
		)
		(fp_line
			(start -0.094672 -0.001008)
			(end 0.105328 -0.201008)
			(stroke
				(width 0.1)
				(type solid)
			)
			(layer "B.SilkS")
		)
		(fp_line
			(start -0.22 0.35)
			(end 0.22 0.35)
			(stroke
				(width 0.15)
				(type solid)
			)
			(layer "B.SilkS")
		)
		(fp_line
			(start -0.22 -0.35)
			(end 0.22 -0.35)
			(stroke
				(width 0.15)
				(type solid)
			)
			(layer "B.SilkS")
		)
		(fp_line
			(start -0.24 -0.001008)
			(end -0.094672 -0.001008)
			(stroke
				(width 0.1)
				(type solid)
			)
			(layer "B.SilkS")
		)
		(fp_line
			(start -1.18 -0.321)
			(end -1.18 0.319)
			(stroke
				(width 0.15)
				(type solid)
			)
			(layer "B.SilkS")
		)
		(fp_rect
			(start 1.25 -0.65)
			(end -1.25 0.65)
			(stroke
				(width 0.05)
				(type solid)
			)
			(fill none)
			(layer "B.CrtYd")
		)
		(fp_line
			(start 0.201 0.202)
			(end 0.201 0)
			(stroke
				(width 0.15)
				(type solid)
			)
			(layer "B.Fab")
		)
		(fp_line
			(start 0.201 0)
			(end 0.599 0)
			(stroke
				(width 0.15)
				(type solid)
			)
			(layer "B.Fab")
		)
		(fp_line
			(start 0.201 0)
			(end 0.201 -0.2)
			(stroke
				(width 0.15)
				(type solid)
			)
			(layer "B.Fab")
		)
		(fp_line
			(start 0.201 -0.2)
			(end -0.101 0)
			(stroke
				(width 0.15)
				(type solid)
			)
			(layer "B.Fab")
		)
		(fp_line
			(start -0.101 0)
			(end 0.201 0.202)
			(stroke
				(width 0.15)
				(type solid)
			)
			(layer "B.Fab")
		)
		(fp_line
			(start -0.199 -0.1)
			(end -0.199 0.202)
			(stroke
				(width 0.15)
				(type solid)
			)
			(layer "B.Fab")
		)
		(fp_line
			(start -0.199 -0.1)
			(end -0.199 -0.2)
			(stroke
				(width 0.15)
				(type solid)
			)
			(layer "B.Fab")
		)
		(fp_line
			(start -0.597 0)
			(end -0.199 0)
			(stroke
				(width 0.15)
				(type solid)
			)
			(layer "B.Fab")
		)
		(fp_rect
			(start 0.848 -0.4)
			(end -0.85 0.402)
			(stroke
				(width 0.15)
				(type solid)
			)
			(fill none)
			(layer "B.Fab")
		)
		(fp_text user "License: Apache-2.0"
			(at -1.4224 -3.599 0)
			(layer "B.Fab")
			(hide yes)
			(effects
				(font
					(size 0.7 0.7)
					(thickness 0.15)
				)
				(justify left bottom mirror)
			)
		)
		(fp_text user "${REFERENCE}"
			(at -1.4224 -5.999 0)
			(layer "B.Fab")
			(hide yes)
			(effects
				(font
					(size 0.7 0.7)
					(thickness 0.15)
				)
				(justify left bottom mirror)
			)
		)
		(fp_text user "Author: Antmicro"
			(at -1.4224 -4.799 0)
			(layer "B.Fab")
			(hide yes)
			(effects
				(font
					(size 0.7 0.7)
					(thickness 0.15)
				)
				(justify left bottom mirror)
			)
		)
		(pad "1" smd roundrect
			(at -0.7 0)
			(size 0.8 1)
			(layers "B.Cu" "B.Paste" "B.Mask")
			(roundrect_rratio 0.2)
			(net 1 "GND")
			(pinfunction "C")
			(pintype "passive")
		)
		(pad "2" smd roundrect
			(at 0.7 0)
			(size 0.8 1)
			(layers "B.Cu" "B.Paste" "B.Mask")
			(roundrect_rratio 0.2)
			(net 162 "Net-(D25-A)")
			(pinfunction "A")
			(pintype "passive")
		)
	)
	(footprint "antmicro-footprints:R_0402_1005Metric"
		(layer "B.Cu")
		(at 137.7 116.55)
		(descr "Resistor SMD 0402")
		(tags "resistor SMD 0402")
		(property "Reference" "R7"
			(at -0.75 0.45 180)
			(layer "B.SilkS")
			(effects
				(font
					(size 0.7 0.7)
					(thickness 0.15)
				)
				(justify left bottom mirror)
			)
		)
		(property "Value" "R_4k7_0402"
			(at 0 -1.4 180)
			(layer "B.Fab")
			(effects
				(font
					(size 0.7 0.7)
					(thickness 0.15)
				)
				(justify left bottom mirror)
			)
		)
		(property "Footprint" "antmicro-footprints:R_0402_1005Metric"
			(at 0 0 0)
			(layer "F.Fab")
			(hide yes)
			(effects
				(font
					(size 1.27 1.27)
					(thickness 0.15)
				)
			)
		)
		(property "Datasheet" "https://www.bourns.com/docs/product-datasheets/cr.pdf"
			(at 0 0 0)
			(layer "F.Fab")
			(hide yes)
			(effects
				(font
					(size 1.27 1.27)
					(thickness 0.15)
				)
			)
		)
		(property "Author" "Antmicro"
			(at 0 0 0)
			(layer "B.Fab")
			(hide yes)
			(effects
				(font
					(size 1 1)
					(thickness 0.15)
				)
				(justify mirror)
			)
		)
		(property "License" "Apache-2.0"
			(at 0 0 0)
			(layer "B.Fab")
			(hide yes)
			(effects
				(font
					(size 1 1)
					(thickness 0.15)
				)
				(justify mirror)
			)
		)
		(property "MPN" "CR0402-FX-4701GLF"
			(at 0 0 0)
			(layer "B.Fab")
			(hide yes)
			(effects
				(font
					(size 1 1)
					(thickness 0.15)
				)
				(justify mirror)
			)
		)
		(property "Manufacturer" "Bourns"
			(at 0 0 0)
			(layer "B.Fab")
			(hide yes)
			(effects
				(font
					(size 1 1)
					(thickness 0.15)
				)
				(justify mirror)
			)
		)
		(property "Tolerance" "1%"
			(at 0 0 0)
			(layer "B.Fab")
			(hide yes)
			(effects
				(font
					(size 1 1)
					(thickness 0.15)
				)
				(justify mirror)
			)
		)
		(property "Val" "4k7"
			(at 0 0 0)
			(layer "B.Fab")
			(hide yes)
			(effects
				(font
					(size 1 1)
					(thickness 0.15)
				)
				(justify mirror)
			)
		)
		(sheetname "CSI")
		(sheetfile "csi.kicad_sch")
		(attr smd)
		(fp_rect
			(start -0.925 0.47)
			(end 0.925 -0.47)
			(stroke
				(width 0.05)
				(type default)
			)
			(fill none)
			(layer "B.CrtYd")
		)
		(fp_rect
			(start -0.5 0.25)
			(end 0.5 -0.25)
			(stroke
				(width 0.15)
				(type solid)
			)
			(fill none)
			(layer "B.Fab")
		)
		(fp_text user "License: Apache-2.0"
			(at -0.95 -5.169 180)
			(layer "B.Fab")
			(hide yes)
			(effects
				(font
					(size 0.7 0.7)
					(thickness 0.15)
				)
				(justify left bottom mirror)
			)
		)
		(fp_text user "Author: Antmicro"
			(at -0.95 -4.169 180)
			(layer "B.Fab")
			(hide yes)
			(effects
				(font
					(size 0.7 0.7)
					(thickness 0.15)
				)
				(justify left bottom mirror)
			)
		)
		(fp_text user "${REFERENCE}"
			(at -0.95 -3.168 180)
			(layer "B.Fab")
			(hide yes)
			(effects
				(font
					(size 0.7 0.7)
					(thickness 0.15)
				)
				(justify left bottom mirror)
			)
		)
		(pad "1" smd roundrect
			(at -0.48 0)
			(size 0.59 0.64)
			(layers "B.Cu" "B.Paste" "B.Mask")
			(roundrect_rratio 0.25)
			(net 1 "GND")
			(pintype "passive")
		)
		(pad "2" smd roundrect
			(at 0.48 0)
			(size 0.59 0.64)
			(layers "B.Cu" "B.Paste" "B.Mask")
			(roundrect_rratio 0.25)
			(net 334 "/CSI/CSIA_5V_ISET")
			(pintype "passive")
		)
	)
	(footprint "antmicro-footprints:R_0402_1005Metric"
		(layer "B.Cu")
		(at 65.925 110.275 90)
		(descr "Resistor SMD 0402")
		(tags "resistor SMD 0402")
		(property "Reference" "R44"
			(at -0.935 0.305 -90)
			(layer "B.SilkS")
			(effects
				(font
					(size 0.7 0.7)
					(thickness 0.15)
				)
				(justify left bottom mirror)
			)
		)
		(property "Value" "R_10k_0402"
			(at 0 -1.4 -90)
			(layer "B.Fab")
			(effects
				(font
					(size 0.7 0.7)
					(thickness 0.15)
				)
				(justify left bottom mirror)
			)
		)
		(property "Footprint" "antmicro-footprints:R_0402_1005Metric"
			(at 0 0 90)
			(layer "F.Fab")
			(hide yes)
			(effects
				(font
					(size 1.27 1.27)
					(thickness 0.15)
				)
			)
		)
		(property "Datasheet" "https://www.bourns.com/docs/product-datasheets/cr.pdf"
			(at 0 0 90)
			(layer "F.Fab")
			(hide yes)
			(effects
				(font
					(size 1.27 1.27)
					(thickness 0.15)
				)
			)
		)
		(property "Author" "Antmicro"
			(at 176.2 44.35 0)
			(layer "B.Fab")
			(hide yes)
			(effects
				(font
					(size 1 1)
					(thickness 0.15)
				)
				(justify mirror)
			)
		)
		(property "License" "Apache-2.0"
			(at 176.2 44.35 0)
			(layer "B.Fab")
			(hide yes)
			(effects
				(font
					(size 1 1)
					(thickness 0.15)
				)
				(justify mirror)
			)
		)
		(property "MPN" "CR0402-FX-1002GLF"
			(at 176.2 44.35 0)
			(layer "B.Fab")
			(hide yes)
			(effects
				(font
					(size 1 1)
					(thickness 0.15)
				)
				(justify mirror)
			)
		)
		(property "Manufacturer" "Bourns"
			(at 176.2 44.35 0)
			(layer "B.Fab")
			(hide yes)
			(effects
				(font
					(size 1 1)
					(thickness 0.15)
				)
				(justify mirror)
			)
		)
		(property "Tolerance" "1%"
			(at 176.2 44.35 0)
			(layer "B.Fab")
			(hide yes)
			(effects
				(font
					(size 1 1)
					(thickness 0.15)
				)
				(justify mirror)
			)
		)
		(property "Val" "10k"
			(at 176.2 44.35 0)
			(layer "B.Fab")
			(hide yes)
			(effects
				(font
					(size 1 1)
					(thickness 0.15)
				)
				(justify mirror)
			)
		)
		(sheetname "USB Debug, DP")
		(sheetfile "usb.kicad_sch")
		(attr smd)
		(fp_rect
			(start -0.925 0.47)
			(end 0.925 -0.47)
			(stroke
				(width 0.05)
				(type default)
			)
			(fill none)
			(layer "B.CrtYd")
		)
		(fp_rect
			(start -0.5 0.25)
			(end 0.5 -0.25)
			(stroke
				(width 0.15)
				(type solid)
			)
			(fill none)
			(layer "B.Fab")
		)
		(fp_text user "${REFERENCE}"
			(at -0.95 -3.168 -90)
			(layer "B.Fab")
			(hide yes)
			(effects
				(font
					(size 0.7 0.7)
					(thickness 0.15)
				)
				(justify left bottom mirror)
			)
		)
		(fp_text user "Author: Antmicro"
			(at -0.95 -4.169 -90)
			(layer "B.Fab")
			(hide yes)
			(effects
				(font
					(size 0.7 0.7)
					(thickness 0.15)
				)
				(justify left bottom mirror)
			)
		)
		(fp_text user "License: Apache-2.0"
			(at -0.95 -5.169 -90)
			(layer "B.Fab")
			(hide yes)
			(effects
				(font
					(size 0.7 0.7)
					(thickness 0.15)
				)
				(justify left bottom mirror)
			)
		)
		(pad "1" smd roundrect
			(at -0.48 0 90)
			(size 0.59 0.64)
			(layers "B.Cu" "B.Paste" "B.Mask")
			(roundrect_rratio 0.25)
			(net 134 "/USB Debug, DP/PDC_LDO_3V3")
			(pintype "passive")
		)
		(pad "2" smd roundrect
			(at 0.48 0 90)
			(size 0.59 0.64)
			(layers "B.Cu" "B.Paste" "B.Mask")
			(roundrect_rratio 0.25)
			(net 287 "/USB Debug, DP/PDC_ADCIN2")
			(pintype "passive")
		)
	)
	(footprint "antmicro-footprints:WQFN-42-1EP_3.5x9mm_P0.5mm"
		(layer "B.Cu")
		(at 91.32 91.95 180)
		(descr "WQFN, 42 Pin (http://www.ti.com/lit/ds/symlink/ts3l501e.pdf#page=23), generated with kicad-footprint-generator ipc_noLead_generator.py")
		(tags "WQFN NoLead")
		(property "Reference" "U36"
			(at 0 5.821 0)
			(layer "B.SilkS")
			(effects
				(font
					(size 0.7 0.7)
					(thickness 0.15)
				)
				(justify left bottom mirror)
			)
		)
		(property "Value" "TS3DV642RUARQ1"
			(at 0 -5.82 0)
			(layer "B.Fab")
			(effects
				(font
					(size 0.7 0.7)
					(thickness 0.15)
				)
				(justify left bottom mirror)
			)
		)
		(property "Footprint" "antmicro-footprints:WQFN-42-1EP_3.5x9mm_P0.5mm"
			(at 0 0 180)
			(layer "F.Fab")
			(hide yes)
			(effects
				(font
					(size 1.27 1.27)
					(thickness 0.15)
				)
			)
		)
		(property "Datasheet" "https://www.ti.com/lit/ds/symlink/ts3dv642-q1.pdf?ts=1676983005656&ref_url=https%253A%252F%252Fwww.ti.com%252Fproduct%252FTS3DV642-Q1"
			(at 0 0 180)
			(layer "F.Fab")
			(hide yes)
			(effects
				(font
					(size 1.27 1.27)
					(thickness 0.15)
				)
			)
		)
		(property "Description" "Special purpose interface switch"
			(at 0 0 180)
			(layer "F.Fab")
			(hide yes)
			(effects
				(font
					(size 1.27 1.27)
					(thickness 0.15)
				)
			)
		)
		(property "Author" "Antmicro"
			(at 182.64 183.9 0)
			(layer "B.Fab")
			(hide yes)
			(effects
				(font
					(size 1 1)
					(thickness 0.15)
				)
				(justify mirror)
			)
		)
		(property "License" "Apache-2.0"
			(at 182.64 183.9 0)
			(layer "B.Fab")
			(hide yes)
			(effects
				(font
					(size 1 1)
					(thickness 0.15)
				)
				(justify mirror)
			)
		)
		(property "MPN" "TS3DV642RUARQ1"
			(at 182.64 183.9 0)
			(layer "B.Fab")
			(hide yes)
			(effects
				(font
					(size 1 1)
					(thickness 0.15)
				)
				(justify mirror)
			)
		)
		(property "Manufacturer" "Texas Instruments"
			(at 182.64 183.9 0)
			(layer "B.Fab")
			(hide yes)
			(effects
				(font
					(size 1 1)
					(thickness 0.15)
				)
				(justify mirror)
			)
		)
		(sheetname "HDMI")
		(sheetfile "hdmi.kicad_sch")
		(attr smd)
		(fp_line
			(start 1.86 4.611)
			(end 1.134 4.611)
			(stroke
				(width 0.15)
				(type solid)
			)
			(layer "B.SilkS")
		)
		(fp_line
			(start 1.86 4.385)
			(end 1.86 4.611)
			(stroke
				(width 0.15)
				(type solid)
			)
			(layer "B.SilkS")
		)
		(fp_line
			(start 1.86 -4.384)
			(end 1.86 -4.61)
			(stroke
				(width 0.15)
				(type solid)
			)
			(layer "B.SilkS")
		)
		(fp_line
			(start 1.86 -4.61)
			(end 1.134 -4.61)
			(stroke
				(width 0.15)
				(type solid)
			)
			(layer "B.SilkS")
		)
		(fp_line
			(start -1.861 4.611)
			(end -1.135 4.611)
			(stroke
				(width 0.15)
				(type solid)
			)
			(layer "B.SilkS")
		)
		(fp_line
			(start -1.861 -4.384)
			(end -1.861 -4.61)
			(stroke
				(width 0.15)
				(type solid)
			)
			(layer "B.SilkS")
		)
		(fp_line
			(start -1.861 -4.61)
			(end -1.135 -4.61)
			(stroke
				(width 0.15)
				(type solid)
			)
			(layer "B.SilkS")
		)
		(fp_circle
			(center -2.68 4)
			(end -2.63 4)
			(stroke
				(width 0.15)
				(type solid)
			)
			(fill solid)
			(layer "B.SilkS")
		)
		(fp_rect
			(start -2.25 5)
			(end 2.249 -4.998)
			(stroke
				(width 0.05)
				(type solid)
			)
			(fill none)
			(layer "B.CrtYd")
		)
		(fp_line
			(start 1.749 4.5)
			(end -0.875 4.5)
			(stroke
				(width 0.15)
				(type solid)
			)
			(layer "B.Fab")
		)
		(fp_line
			(start 1.749 -4.498)
			(end 1.749 4.5)
			(stroke
				(width 0.15)
				(type solid)
			)
			(layer "B.Fab")
		)
		(fp_line
			(start -0.875 4.5)
			(end -1.75 3.625)
			(stroke
				(width 0.15)
				(type solid)
			)
			(layer "B.Fab")
		)
		(fp_line
			(start -1.75 3.625)
			(end -1.75 -4.498)
			(stroke
				(width 0.15)
				(type solid)
			)
			(layer "B.Fab")
		)
		(fp_line
			(start -1.75 -4.498)
			(end 1.749 -4.498)
			(stroke
				(width 0.15)
				(type solid)
			)
			(layer "B.Fab")
		)
		(fp_text user "License: Apache-2.0"
			(at -2.73 -9.02 0)
			(layer "B.Fab")
			(hide yes)
			(effects
				(font
					(size 0.7 0.7)
					(thickness 0.15)
				)
				(justify left bottom mirror)
			)
		)
		(fp_text user "${REFERENCE}"
			(at -2.73 -10.22 0)
			(layer "B.Fab")
			(hide yes)
			(effects
				(font
					(size 0.7 0.7)
					(thickness 0.15)
				)
				(justify left bottom mirror)
			)
		)
		(fp_text user "Author: Antmicro"
			(at -2.73 -7.82 0)
			(layer "B.Fab")
			(hide yes)
			(effects
				(font
					(size 0.7 0.7)
					(thickness 0.15)
				)
				(justify left bottom mirror)
			)
		)
		(pad "" smd roundrect
			(at -0.51 -3.24 180)
			(size 0.83 0.87)
			(layers "B.Paste")
			(roundrect_rratio 0.25)
		)
		(pad "" smd roundrect
			(at -0.51 -2.16 180)
			(size 0.83 0.87)
			(layers "B.Paste")
			(roundrect_rratio 0.25)
		)
		(pad "" smd roundrect
			(at -0.51 -1.08 180)
			(size 0.83 0.87)
			(layers "B.Paste")
			(roundrect_rratio 0.25)
		)
		(pad "" smd roundrect
			(at -0.51 0 180)
			(size 0.83 0.87)
			(layers "B.Paste")
			(roundrect_rratio 0.25)
		)
		(pad "" smd roundrect
			(at -0.51 1.081 180)
			(size 0.83 0.87)
			(layers "B.Paste")
			(roundrect_rratio 0.25)
		)
		(pad "" smd roundrect
			(at -0.51 2.161 180)
			(size 0.83 0.87)
			(layers "B.Paste")
			(roundrect_rratio 0.25)
		)
		(pad "" smd roundrect
			(at -0.51 3.242 180)
			(size 0.83 0.87)
			(layers "B.Paste")
			(roundrect_rratio 0.25)
		)
		(pad "" smd roundrect
			(at 0.508 -3.24 180)
			(size 0.83 0.87)
			(layers "B.Paste")
			(roundrect_rratio 0.25)
		)
		(pad "" smd roundrect
			(at 0.508 -2.16 180)
			(size 0.83 0.87)
			(layers "B.Paste")
			(roundrect_rratio 0.25)
		)
		(pad "" smd roundrect
			(at 0.508 -1.08 180)
			(size 0.83 0.87)
			(layers "B.Paste")
			(roundrect_rratio 0.25)
		)
		(pad "" smd roundrect
			(at 0.508 0 180)
			(size 0.83 0.87)
			(layers "B.Paste")
			(roundrect_rratio 0.25)
		)
		(pad "" smd roundrect
			(at 0.508 1.081 180)
			(size 0.83 0.87)
			(layers "B.Paste")
			(roundrect_rratio 0.25)
		)
		(pad "" smd roundrect
			(at 0.508 2.161 180)
			(size 0.83 0.87)
			(layers "B.Paste")
			(roundrect_rratio 0.25)
		)
		(pad "" smd roundrect
			(at 0.508 3.242 180)
			(size 0.83 0.87)
			(layers "B.Paste")
			(roundrect_rratio 0.25)
		)
		(pad "1" smd roundrect
			(at -1.688 4 180)
			(size 0.875 0.25)
			(layers "B.Cu" "B.Paste" "B.Mask")
			(roundrect_rratio 0.25)
			(net 87 "+3V3")
			(pinfunction "VCC")
			(pintype "power_in")
		)
		(pad "2" smd roundrect
			(at -1.688 3.5 180)
			(size 0.875 0.25)
			(layers "B.Cu" "B.Paste" "B.Mask")
			(roundrect_rratio 0.25)
			(net 678 "/HDMI/DP_MUX_EN")
			(pinfunction "EN")
			(pintype "input")
		)
		(pad "3" smd roundrect
			(at -1.688 3 180)
			(size 0.875 0.25)
			(layers "B.Cu" "B.Paste" "B.Mask")
			(roundrect_rratio 0.25)
			(net 429 "DP1_HDMI_AUX_P")
			(pinfunction "SCL/AUX+")
			(pintype "bidirectional")
		)
		(pad "4" smd roundrect
			(at -1.688 2.5 180)
			(size 0.875 0.25)
			(layers "B.Cu" "B.Paste" "B.Mask")
			(roundrect_rratio 0.25)
			(net 430 "DP1_HDMI_AUX_N")
			(pinfunction "SDA/AUX-")
			(pintype "bidirectional")
		)
		(pad "5" smd roundrect
			(at -1.688 2 180)
			(size 0.875 0.25)
			(layers "B.Cu" "B.Paste" "B.Mask")
			(roundrect_rratio 0.25)
			(net 665 "/HDMI/DP_MUX_D0+")
			(pinfunction "D0+")
			(pintype "bidirectional")
		)
		(pad "6" smd roundrect
			(at -1.688 1.5 180)
			(size 0.875 0.25)
			(layers "B.Cu" "B.Paste" "B.Mask")
			(roundrect_rratio 0.25)
			(net 556 "/HDMI/DP_MUX_D0-")
			(pinfunction "D0-")
			(pintype "bidirectional")
		)
		(pad "7" smd roundrect
			(at -1.688 1 180)
			(size 0.875 0.25)
			(layers "B.Cu" "B.Paste" "B.Mask")
			(roundrect_rratio 0.25)
			(net 666 "/HDMI/DP_MUX_D1+")
			(pinfunction "D1+")
			(pintype "bidirectional")
		)
		(pad "8" smd roundrect
			(at -1.688 0.5 180)
			(size 0.875 0.25)
			(layers "B.Cu" "B.Paste" "B.Mask")
			(roundrect_rratio 0.25)
			(net 663 "/HDMI/DP_MUX_D1-")
			(pinfunction "D1-")
			(pintype "bidirectional")
		)
		(pad "9" smd roundrect
			(at -1.688 0 180)
			(size 0.875 0.25)
			(layers "B.Cu" "B.Paste" "B.Mask")
			(roundrect_rratio 0.25)
			(net 720 "unconnected-(U36-NC-Pad9)")
			(pinfunction "NC")
			(pintype "no_connect")
		)
		(pad "10" smd roundrect
			(at -1.688 -0.5 180)
			(size 0.875 0.25)
			(layers "B.Cu" "B.Paste" "B.Mask")
			(roundrect_rratio 0.25)
			(net 667 "/HDMI/DP_MUX_D2+")
			(pinfunction "D2+")
			(pintype "bidirectional")
		)
		(pad "11" smd roundrect
			(at -1.688 -1 180)
			(size 0.875 0.25)
			(layers "B.Cu" "B.Paste" "B.Mask")
			(roundrect_rratio 0.25)
			(net 664 "/HDMI/DP_MUX_D2-")
			(pinfunction "D2-")
			(pintype "bidirectional")
		)
		(pad "12" smd roundrect
			(at -1.688 -1.5 180)
			(size 0.875 0.25)
			(layers "B.Cu" "B.Paste" "B.Mask")
			(roundrect_rratio 0.25)
			(net 700 "/HDMI/DP_MUX_D3+")
			(pinfunction "D3+")
			(pintype "bidirectional")
		)
		(pad "13" smd roundrect
			(at -1.688 -2 180)
			(size 0.875 0.25)
			(layers "B.Cu" "B.Paste" "B.Mask")
			(roundrect_rratio 0.25)
			(net 699 "/HDMI/DP_MUX_D3-")
			(pinfunction "D3-")
			(pintype "bidirectional")
		)
		(pad "14" smd roundrect
			(at -1.688 -2.5 180)
			(size 0.875 0.25)
			(layers "B.Cu" "B.Paste" "B.Mask")
			(roundrect_rratio 0.25)
			(net 622 "Net-(Q1-D)")
			(pinfunction "HPD")
			(pintype "bidirectional")
		)
		(pad "15" smd roundrect
			(at -1.688 -3 180)
			(size 0.875 0.25)
			(layers "B.Cu" "B.Paste" "B.Mask")
			(roundrect_rratio 0.25)
			(net 721 "unconnected-(U36-CEC-Pad15)")
			(pinfunction "CEC")
			(pintype "bidirectional+no_connect")
		)
		(pad "16" smd roundrect
			(at -1.688 -3.5 180)
			(size 0.875 0.25)
			(layers "B.Cu" "B.Paste" "B.Mask")
			(roundrect_rratio 0.25)
			(net 686 "Net-(U36-SEL1)")
			(pinfunction "SEL1")
			(pintype "input")
		)
		(pad "17" smd roundrect
			(at -1.688 -4 180)
			(size 0.875 0.25)
			(layers "B.Cu" "B.Paste" "B.Mask")
			(roundrect_rratio 0.25)
			(net 624 "Net-(Q3-D)")
			(pinfunction "SEL2")
			(pintype "input")
		)
		(pad "18" smd roundrect
			(at -0.75 -4.437 180)
			(size 0.25 0.875)
			(layers "B.Cu" "B.Paste" "B.Mask")
			(roundrect_rratio 0.25)
			(net 722 "unconnected-(U36-CEC_A-Pad18)")
			(pinfunction "CEC_A")
			(pintype "bidirectional+no_connect")
		)
		(pad "19" smd roundrect
			(at -0.25 -4.437 180)
			(size 0.25 0.875)
			(layers "B.Cu" "B.Paste" "B.Mask")
			(roundrect_rratio 0.25)
			(net 677 "USBC_HPD")
			(pinfunction "HPD_A")
			(pintype "bidirectional")
		)
		(pad "20" smd roundrect
			(at 0.25 -4.437 180)
			(size 0.25 0.875)
			(layers "B.Cu" "B.Paste" "B.Mask")
			(roundrect_rratio 0.25)
			(net 723 "unconnected-(U36-CEC_B-Pad20)")
			(pinfunction "CEC_B")
			(pintype "bidirectional+no_connect")
		)
		(pad "21" smd roundrect
			(at 0.75 -4.437 180)
			(size 0.25 0.875)
			(layers "B.Cu" "B.Paste" "B.Mask")
			(roundrect_rratio 0.25)
			(net 703 "/HDMI/HDMI_HPD")
			(pinfunction "HPD_B")
			(pintype "bidirectional")
		)
		(pad "22" smd roundrect
			(at 1.687 -4 180)
			(size 0.875 0.25)
			(layers "B.Cu" "B.Paste" "B.Mask")
			(roundrect_rratio 0.25)
			(net 486 "/HDMI/HDMI_D2_N")
			(pinfunction "D3-B")
			(pintype "bidirectional")
		)
		(pad "23" smd roundrect
			(at 1.687 -3.5 180)
			(size 0.875 0.25)
			(layers "B.Cu" "B.Paste" "B.Mask")
			(roundrect_rratio 0.25)
			(net 492 "/HDMI/HDMI_D2_P")
			(pinfunction "D3+B")
			(pintype "bidirectional")
		)
		(pad "24" smd roundrect
			(at 1.687 -3 180)
			(size 0.875 0.25)
			(layers "B.Cu" "B.Paste" "B.Mask")
			(roundrect_rratio 0.25)
			(net 487 "/HDMI/HDMI_D1_N")
			(pinfunction "D2-B")
			(pintype "bidirectional")
		)
		(pad "25" smd roundrect
			(at 1.687 -2.5 180)
			(size 0.875 0.25)
			(layers "B.Cu" "B.Paste" "B.Mask")
			(roundrect_rratio 0.25)
			(net 493 "/HDMI/HDMI_D1_P")
			(pinfunction "D2+B")
			(pintype "bidirectional")
		)
		(pad "26" smd roundrect
			(at 1.687 -2 180)
			(size 0.875 0.25)
			(layers "B.Cu" "B.Paste" "B.Mask")
			(roundrect_rratio 0.25)
			(net 488 "/HDMI/HDMI_D0_N")
			(pinfunction "D1-B")
			(pintype "bidirectional")
		)
		(pad "27" smd roundrect
			(at 1.687 -1.5 180)
			(size 0.875 0.25)
			(layers "B.Cu" "B.Paste" "B.Mask")
			(roundrect_rratio 0.25)
			(net 494 "/HDMI/HDMI_D0_P")
			(pinfunction "D1+B")
			(pintype "bidirectional")
		)
		(pad "28" smd roundrect
			(at 1.687 -1 180)
			(size 0.875 0.25)
			(layers "B.Cu" "B.Paste" "B.Mask")
			(roundrect_rratio 0.25)
			(net 489 "/HDMI/HDMI_CLK_N")
			(pinfunction "D0-B")
			(pintype "bidirectional")
		)
		(pad "29" smd roundrect
			(at 1.687 -0.5 180)
			(size 0.875 0.25)
			(layers "B.Cu" "B.Paste" "B.Mask")
			(roundrect_rratio 0.25)
			(net 495 "/HDMI/HDMI_CLK_P")
			(pinfunction "D0+B")
			(pintype "bidirectional")
		)
		(pad "30" smd roundrect
			(at 1.687 0 180)
			(size 0.875 0.25)
			(layers "B.Cu" "B.Paste" "B.Mask")
			(roundrect_rratio 0.25)
			(net 724 "unconnected-(U36-NC-Pad30)")
			(pinfunction "NC")
			(pintype "no_connect")
		)
		(pad "31" smd roundrect
			(at 1.687 0.5 180)
			(size 0.875 0.25)
			(layers "B.Cu" "B.Paste" "B.Mask")
			(roundrect_rratio 0.25)
			(net 26 "DP1_TXD0_N")
			(pinfunction "D3-A")
			(pintype "bidirectional")
		)
		(pad "32" smd roundrect
			(at 1.687 1 180)
			(size 0.875 0.25)
			(layers "B.Cu" "B.Paste" "B.Mask")
			(roundrect_rratio 0.25)
			(net 496 "DP1_TXD0_P")
			(pinfunction "D3+A")
			(pintype "bidirectional")
		)
		(pad "33" smd roundrect
			(at 1.687 1.5 180)
			(size 0.875 0.25)
			(layers "B.Cu" "B.Paste" "B.Mask")
			(roundrect_rratio 0.25)
			(net 490 "DP1_TXD1_N")
			(pinfunction "D2-A")
			(pintype "bidirectional")
		)
		(pad "34" smd roundrect
			(at 1.687 2 180)
			(size 0.875 0.25)
			(layers "B.Cu" "B.Paste" "B.Mask")
			(roundrect_rratio 0.25)
			(net 27 "DP1_TXD1_P")
			(pinfunction "D2+A")
			(pintype "bidirectional")
		)
		(pad "35" smd roundrect
			(at 1.687 2.5 180)
			(size 0.875 0.25)
			(layers "B.Cu" "B.Paste" "B.Mask")
			(roundrect_rratio 0.25)
			(net 491 "DP1_TXD2_N")
			(pinfunction "D1-A")
			(pintype "bidirectional")
		)
		(pad "36" smd roundrect
			(at 1.687 3 180)
			(size 0.875 0.25)
			(layers "B.Cu" "B.Paste" "B.Mask")
			(roundrect_rratio 0.25)
			(net 497 "DP1_TXD2_P")
			(pinfunction "D1+A")
			(pintype "bidirectional")
		)
		(pad "37" smd roundrect
			(at 1.687 3.5 180)
			(size 0.875 0.25)
			(layers "B.Cu" "B.Paste" "B.Mask")
			(roundrect_rratio 0.25)
			(net 28 "DP1_TXD3_N")
			(pinfunction "D0-A")
			(pintype "bidirectional")
		)
		(pad "38" smd roundrect
			(at 1.687 4 180)
			(size 0.875 0.25)
			(layers "B.Cu" "B.Paste" "B.Mask")
			(roundrect_rratio 0.25)
			(net 29 "DP1_TXD3_P")
			(pinfunction "D0+A")
			(pintype "bidirectional")
		)
		(pad "39" smd roundrect
			(at 0.75 4.438 180)
			(size 0.25 0.875)
			(layers "B.Cu" "B.Paste" "B.Mask")
			(roundrect_rratio 0.25)
			(net 680 "/HDMI/DP_MUX_AUX_A-")
			(pinfunction "SDA/AUX-_B")
			(pintype "bidirectional")
		)
		(pad "40" smd roundrect
			(at 0.25 4.438 180)
			(size 0.25 0.875)
			(layers "B.Cu" "B.Paste" "B.Mask")
			(roundrect_rratio 0.25)
			(net 679 "/HDMI/DP_MUX_AUX_A+")
			(pinfunction "SCL/AUX+_B")
			(pintype "bidirectional")
		)
		(pad "41" smd roundrect
			(at -0.25 4.438 180)
			(size 0.25 0.875)
			(layers "B.Cu" "B.Paste" "B.Mask")
			(roundrect_rratio 0.25)
			(net 668 "/HDMI/DP_MUX_AUX_B-")
			(pinfunction "SDA/AUX-_A")
			(pintype "bidirectional")
		)
		(pad "42" smd roundrect
			(at -0.75 4.438 180)
			(size 0.25 0.875)
			(layers "B.Cu" "B.Paste" "B.Mask")
			(roundrect_rratio 0.25)
			(net 669 "/HDMI/DP_MUX_AUX_B+")
			(pinfunction "SCL/AUX+_A")
			(pintype "bidirectional")
		)
		(pad "43" smd rect
			(at 0 0 180)
			(size 2.05 7.55)
			(layers "B.Cu" "B.Mask")
			(net 1 "GND")
			(pinfunction "GND")
			(pintype "power_in")
		)
	)
	(footprint "antmicro-footprints:C_0402_1005Metric"
		(layer "B.Cu")
		(at 96.49 100.525)
		(descr "Capacitor SMD 0402")
		(tags "capacitor SMD 0402")
		(property "Reference" "C89"
			(at 0.81 1.325 0)
			(layer "B.SilkS")
			(effects
				(font
					(size 0.7 0.7)
					(thickness 0.15)
				)
				(justify left bottom mirror)
			)
		)
		(property "Value" "C_100n_0402"
			(at 0 -1.4 180)
			(layer "B.Fab")
			(effects
				(font
					(size 0.7 0.7)
					(thickness 0.15)
				)
				(justify left bottom mirror)
			)
		)
		(property "Footprint" "antmicro-footprints:C_0402_1005Metric"
			(at 0 0 0)
			(layer "F.Fab")
			(hide yes)
			(effects
				(font
					(size 1.27 1.27)
					(thickness 0.15)
				)
			)
		)
		(property "Datasheet" "https://www.murata.com/products/productdetail?partno=GRM155R61H104KE14%23"
			(at 0 0 0)
			(layer "F.Fab")
			(hide yes)
			(effects
				(font
					(size 1.27 1.27)
					(thickness 0.15)
				)
			)
		)
		(property "Author" "Antmicro"
			(at 0 0 0)
			(layer "B.Fab")
			(hide yes)
			(effects
				(font
					(size 1 1)
					(thickness 0.15)
				)
				(justify mirror)
			)
		)
		(property "Dielectric" "X5R"
			(at 0 0 0)
			(layer "B.Fab")
			(hide yes)
			(effects
				(font
					(size 1 1)
					(thickness 0.15)
				)
				(justify mirror)
			)
		)
		(property "License" "Apache-2.0"
			(at 0 0 0)
			(layer "B.Fab")
			(hide yes)
			(effects
				(font
					(size 1 1)
					(thickness 0.15)
				)
				(justify mirror)
			)
		)
		(property "MPN" "GRM155R61H104KE14D"
			(at 0 0 0)
			(layer "B.Fab")
			(hide yes)
			(effects
				(font
					(size 1 1)
					(thickness 0.15)
				)
				(justify mirror)
			)
		)
		(property "Manufacturer" "Murata"
			(at 0 0 0)
			(layer "B.Fab")
			(hide yes)
			(effects
				(font
					(size 1 1)
					(thickness 0.15)
				)
				(justify mirror)
			)
		)
		(property "Val" "100n"
			(at 0 0 0)
			(layer "B.Fab")
			(hide yes)
			(effects
				(font
					(size 1 1)
					(thickness 0.15)
				)
				(justify mirror)
			)
		)
		(property "Voltage" "50V"
			(at 0 0 0)
			(layer "B.Fab")
			(hide yes)
			(effects
				(font
					(size 1 1)
					(thickness 0.15)
				)
				(justify mirror)
			)
		)
		(sheetname "CSI")
		(sheetfile "csi.kicad_sch")
		(attr smd)
		(fp_rect
			(start -0.925 0.47)
			(end 0.925 -0.47)
			(stroke
				(width 0.05)
				(type default)
			)
			(fill none)
			(layer "B.CrtYd")
		)
		(fp_line
			(start -0.494 -0.248)
			(end 0.504 -0.248)
			(stroke
				(width 0.15)
				(type solid)
			)
			(layer "B.Fab")
		)
		(fp_line
			(start -0.494 0.25)
			(end -0.494 -0.248)
			(stroke
				(width 0.15)
				(type solid)
			)
			(layer "B.Fab")
		)
		(fp_line
			(start 0.504 -0.248)
			(end 0.504 0.25)
			(stroke
				(width 0.15)
				(type solid)
			)
			(layer "B.Fab")
		)
		(fp_line
			(start 0.504 0.25)
			(end -0.494 0.25)
			(stroke
				(width 0.15)
				(type solid)
			)
			(layer "B.Fab")
		)
		(fp_text user "License: Apache-2.0"
			(at -0.932 -5.17 180)
			(layer "B.Fab")
			(hide yes)
			(effects
				(font
					(size 0.7 0.7)
					(thickness 0.15)
				)
				(justify left bottom mirror)
			)
		)
		(fp_text user "${REFERENCE}"
			(at -0.932 -3.168 180)
			(layer "B.Fab")
			(hide yes)
			(effects
				(font
					(size 0.7 0.7)
					(thickness 0.15)
				)
				(justify left bottom mirror)
			)
		)
		(fp_text user "Author: Antmicro"
			(at -0.932 -4.17 180)
			(layer "B.Fab")
			(hide yes)
			(effects
				(font
					(size 0.7 0.7)
					(thickness 0.15)
				)
				(justify left bottom mirror)
			)
		)
		(pad "1" smd roundrect
			(at -0.48 0)
			(size 0.59 0.64)
			(layers "B.Cu" "B.Paste" "B.Mask")
			(roundrect_rratio 0.25)
			(net 1 "GND")
			(pintype "passive")
		)
		(pad "2" smd roundrect
			(at 0.48 0)
			(size 0.59 0.64)
			(layers "B.Cu" "B.Paste" "B.Mask")
			(roundrect_rratio 0.25)
			(net 112 "+1V8")
			(pintype "passive")
		)
	)
	(footprint "antmicro-footprints:C_0402_1005Metric"
		(layer "B.Cu")
		(at 97.45 92.5)
		(descr "Capacitor SMD 0402")
		(tags "capacitor SMD 0402")
		(property "Reference" "C133"
			(at 3.9 0.41 180)
			(layer "B.SilkS")
			(effects
				(font
					(size 0.7 0.7)
					(thickness 0.15)
				)
				(justify left bottom mirror)
			)
		)
		(property "Value" "C_100n_0402"
			(at 0 -1.4 180)
			(layer "B.Fab")
			(effects
				(font
					(size 0.7 0.7)
					(thickness 0.15)
				)
				(justify left bottom mirror)
			)
		)
		(property "Footprint" "antmicro-footprints:C_0402_1005Metric"
			(at 0 0 0)
			(layer "F.Fab")
			(hide yes)
			(effects
				(font
					(size 1.27 1.27)
					(thickness 0.15)
				)
			)
		)
		(property "Datasheet" "https://www.murata.com/products/productdetail?partno=GRM155R61H104KE14%23"
			(at 0 0 0)
			(layer "F.Fab")
			(hide yes)
			(effects
				(font
					(size 1.27 1.27)
					(thickness 0.15)
				)
			)
		)
		(property "Author" "Antmicro"
			(at 0 0 0)
			(layer "B.Fab")
			(hide yes)
			(effects
				(font
					(size 1 1)
					(thickness 0.15)
				)
				(justify mirror)
			)
		)
		(property "Dielectric" "X5R"
			(at 0 0 0)
			(layer "B.Fab")
			(hide yes)
			(effects
				(font
					(size 1 1)
					(thickness 0.15)
				)
				(justify mirror)
			)
		)
		(property "License" "Apache-2.0"
			(at 0 0 0)
			(layer "B.Fab")
			(hide yes)
			(effects
				(font
					(size 1 1)
					(thickness 0.15)
				)
				(justify mirror)
			)
		)
		(property "MPN" "GRM155R61H104KE14D"
			(at 0 0 0)
			(layer "B.Fab")
			(hide yes)
			(effects
				(font
					(size 1 1)
					(thickness 0.15)
				)
				(justify mirror)
			)
		)
		(property "Manufacturer" "Murata"
			(at 0 0 0)
			(layer "B.Fab")
			(hide yes)
			(effects
				(font
					(size 1 1)
					(thickness 0.15)
				)
				(justify mirror)
			)
		)
		(property "Val" "100n"
			(at 0 0 0)
			(layer "B.Fab")
			(hide yes)
			(effects
				(font
					(size 1 1)
					(thickness 0.15)
				)
				(justify mirror)
			)
		)
		(property "Voltage" "50V"
			(at 0 0 0)
			(layer "B.Fab")
			(hide yes)
			(effects
				(font
					(size 1 1)
					(thickness 0.15)
				)
				(justify mirror)
			)
		)
		(sheetname "HDMI")
		(sheetfile "hdmi.kicad_sch")
		(attr smd)
		(fp_rect
			(start -0.925 0.47)
			(end 0.925 -0.47)
			(stroke
				(width 0.05)
				(type default)
			)
			(fill none)
			(layer "B.CrtYd")
		)
		(fp_line
			(start -0.494 -0.248)
			(end 0.504 -0.248)
			(stroke
				(width 0.15)
				(type solid)
			)
			(layer "B.Fab")
		)
		(fp_line
			(start -0.494 0.25)
			(end -0.494 -0.248)
			(stroke
				(width 0.15)
				(type solid)
			)
			(layer "B.Fab")
		)
		(fp_line
			(start 0.504 -0.248)
			(end 0.504 0.25)
			(stroke
				(width 0.15)
				(type solid)
			)
			(layer "B.Fab")
		)
		(fp_line
			(start 0.504 0.25)
			(end -0.494 0.25)
			(stroke
				(width 0.15)
				(type solid)
			)
			(layer "B.Fab")
		)
		(fp_text user "Author: Antmicro"
			(at -0.932 -4.17 180)
			(layer "B.Fab")
			(hide yes)
			(effects
				(font
					(size 0.7 0.7)
					(thickness 0.15)
				)
				(justify left bottom mirror)
			)
		)
		(fp_text user "${REFERENCE}"
			(at -0.932 -3.168 180)
			(layer "B.Fab")
			(hide yes)
			(effects
				(font
					(size 0.7 0.7)
					(thickness 0.15)
				)
				(justify left bottom mirror)
			)
		)
		(fp_text user "License: Apache-2.0"
			(at -0.932 -5.17 180)
			(layer "B.Fab")
			(hide yes)
			(effects
				(font
					(size 0.7 0.7)
					(thickness 0.15)
				)
				(justify left bottom mirror)
			)
		)
		(pad "1" smd roundrect
			(at -0.48 0)
			(size 0.59 0.64)
			(layers "B.Cu" "B.Paste" "B.Mask")
			(roundrect_rratio 0.25)
			(net 667 "/HDMI/DP_MUX_D2+")
			(pintype "passive")
		)
		(pad "2" smd roundrect
			(at 0.48 0)
			(size 0.59 0.64)
			(layers "B.Cu" "B.Paste" "B.Mask")
			(roundrect_rratio 0.25)
			(net 417 "DP1_TXD1_HDMI_TX1_P")
			(pintype "passive")
		)
	)
	(footprint "antmicro-footprints:TP_SMD_0.75mm"
		(layer "B.Cu")
		(at 68.165 118.57 180)
		(property "Reference" "TP29"
			(at 0 0.6 0)
			(layer "B.SilkS")
			(hide yes)
			(effects
				(font
					(size 0.7 0.7)
					(thickness 0.15)
				)
				(justify left bottom mirror)
			)
		)
		(property "Value" "TP_0.75mm_SMD"
			(at 0 -1.2 0)
			(layer "B.Fab")
			(effects
				(font
					(size 0.7 0.7)
					(thickness 0.15)
				)
				(justify left bottom mirror)
			)
		)
		(property "Footprint" "antmicro-footprints:TP_SMD_0.75mm"
			(at 0 0 180)
			(layer "F.Fab")
			(hide yes)
			(effects
				(font
					(size 1.27 1.27)
					(thickness 0.15)
				)
			)
		)
		(property "Author" "Antmicro"
			(at 136.33 237.14 0)
			(layer "B.Fab")
			(hide yes)
			(effects
				(font
					(size 1 1)
					(thickness 0.15)
				)
				(justify mirror)
			)
		)
		(property "License" "Apache-2.0"
			(at 136.33 237.14 0)
			(layer "B.Fab")
			(hide yes)
			(effects
				(font
					(size 1 1)
					(thickness 0.15)
				)
				(justify mirror)
			)
		)
		(property "MPN" ""
			(at 136.33 237.14 0)
			(layer "B.Fab")
			(hide yes)
			(effects
				(font
					(size 1 1)
					(thickness 0.15)
				)
				(justify mirror)
			)
		)
		(property "Manufacturer" ""
			(at 136.33 237.14 0)
			(layer "B.Fab")
			(hide yes)
			(effects
				(font
					(size 1 1)
					(thickness 0.15)
				)
				(justify mirror)
			)
		)
		(sheetname "USB3")
		(sheetfile "usb3.kicad_sch")
		(attr exclude_from_pos_files exclude_from_bom)
		(fp_circle
			(center 0 0)
			(end 0.475 0)
			(stroke
				(width 0.05)
				(type default)
			)
			(fill none)
			(layer "B.CrtYd")
		)
		(fp_text user "Author: Antmicro"
			(at -0.4 -3.901 0)
			(layer "B.Fab")
			(hide yes)
			(effects
				(font
					(size 0.7 0.7)
					(thickness 0.15)
				)
				(justify left bottom mirror)
			)
		)
		(fp_text user "${REFERENCE}"
			(at -0.4 -2.7 0)
			(layer "B.Fab")
			(hide yes)
			(effects
				(font
					(size 0.7 0.7)
					(thickness 0.15)
				)
				(justify left bottom mirror)
			)
		)
		(fp_text user "License: Apache-2.0"
			(at -0.4 -5.101 0)
			(layer "B.Fab")
			(hide yes)
			(effects
				(font
					(size 0.7 0.7)
					(thickness 0.15)
				)
				(justify left bottom mirror)
			)
		)
		(pad "1" smd circle
			(at 0 0 180)
			(size 0.75 0.75)
			(layers "B.Cu" "B.Mask")
			(net 270 "/USB3/USBC1_VBUS")
			(pinfunction "1")
			(pintype "passive")
		)
	)
	(footprint "antmicro-footprints:SOT-523"
		(layer "B.Cu")
		(at 48.5 119.05 -90)
		(property "Reference" "Q21"
			(at 9.14 13.56 180)
			(layer "B.SilkS")
			(effects
				(font
					(size 0.7 0.7)
					(thickness 0.15)
				)
				(justify left bottom mirror)
			)
		)
		(property "Value" "PJE138K"
			(at 0.1 -1.824 90)
			(layer "B.Fab")
			(effects
				(font
					(size 0.7 0.7)
					(thickness 0.15)
				)
				(justify left bottom mirror)
			)
		)
		(property "Footprint" "antmicro-footprints:SOT-523"
			(at 0 0 -90)
			(layer "F.Fab")
			(hide yes)
			(effects
				(font
					(size 1.27 1.27)
					(thickness 0.15)
				)
			)
		)
		(property "Datasheet" "https://www.mouser.com/datasheet/2/1057/PJE138K-1876698.pdf"
			(at 0 0 -90)
			(layer "F.Fab")
			(hide yes)
			(effects
				(font
					(size 1.27 1.27)
					(thickness 0.15)
				)
			)
		)
		(property "Author" "Antmicro"
			(at -70.55 167.55 0)
			(layer "B.Fab")
			(hide yes)
			(effects
				(font
					(size 1 1)
					(thickness 0.15)
				)
				(justify mirror)
			)
		)
		(property "License" "Apache-2.0"
			(at -70.55 167.55 0)
			(layer "B.Fab")
			(hide yes)
			(effects
				(font
					(size 1 1)
					(thickness 0.15)
				)
				(justify mirror)
			)
		)
		(property "MPN" "PJE138K_R1_00001"
			(at -70.55 167.55 0)
			(layer "B.Fab")
			(hide yes)
			(effects
				(font
					(size 1 1)
					(thickness 0.15)
				)
				(justify mirror)
			)
		)
		(property "Manufacturer" "PANJIT"
			(at -70.55 167.55 0)
			(layer "B.Fab")
			(hide yes)
			(effects
				(font
					(size 1 1)
					(thickness 0.15)
				)
				(justify mirror)
			)
		)
		(sheetname "USB Debug, DP")
		(sheetfile "usb.kicad_sch")
		(attr smd)
		(fp_line
			(start -0.277 0.75)
			(end -0.277 0.551)
			(stroke
				(width 0.15)
				(type solid)
			)
			(layer "B.SilkS")
		)
		(fp_line
			(start -0.725 0.551)
			(end -0.927 0.351)
			(stroke
				(width 0.15)
				(type solid)
			)
			(layer "B.SilkS")
		)
		(fp_line
			(start -0.277 0.551)
			(end -0.725 0.551)
			(stroke
				(width 0.15)
				(type solid)
			)
			(layer "B.SilkS")
		)
		(fp_line
			(start -0.927 0.351)
			(end -0.927 0.051)
			(stroke
				(width 0.15)
				(type solid)
			)
			(layer "B.SilkS")
		)
		(fp_circle
			(center -0.9652 -0.9652)
			(end -0.9152 -0.9652)
			(stroke
				(width 0.15)
				(type solid)
			)
			(fill solid)
			(layer "B.SilkS")
		)
		(fp_line
			(start 1.1 1.16)
			(end -1.12 1.16)
			(stroke
				(width 0.05)
				(type solid)
			)
			(layer "B.CrtYd")
		)
		(fp_line
			(start -1.12 -1.15)
			(end -1.12 1.16)
			(stroke
				(width 0.05)
				(type solid)
			)
			(layer "B.CrtYd")
		)
		(fp_line
			(start 1.1 -1.15)
			(end 1.1 1.16)
			(stroke
				(width 0.05)
				(type solid)
			)
			(layer "B.CrtYd")
		)
		(fp_line
			(start 1.1 -1.15)
			(end -1.12 -1.15)
			(stroke
				(width 0.05)
				(type solid)
			)
			(layer "B.CrtYd")
		)
		(fp_line
			(start -0.652 0.425)
			(end 0.8 0.425)
			(stroke
				(width 0.15)
				(type solid)
			)
			(layer "B.Fab")
		)
		(fp_line
			(start -0.802 0.276)
			(end -0.652 0.425)
			(stroke
				(width 0.15)
				(type solid)
			)
			(layer "B.Fab")
		)
		(fp_line
			(start -0.802 -0.424)
			(end -0.802 0.276)
			(stroke
				(width 0.15)
				(type solid)
			)
			(layer "B.Fab")
		)
		(fp_line
			(start -0.802 -0.424)
			(end 0.8 -0.424)
			(stroke
				(width 0.15)
				(type solid)
			)
			(layer "B.Fab")
		)
		(fp_line
			(start 0.8 -0.424)
			(end 0.8 0.425)
			(stroke
				(width 0.15)
				(type solid)
			)
			(layer "B.Fab")
		)
		(fp_circle
			(center -0.9652 -0.9652)
			(end -0.9144 -0.9652)
			(stroke
				(width 0.15)
				(type solid)
			)
			(fill none)
			(layer "B.Fab")
		)
		(fp_text user "License: Apache-2.0"
			(at -1.12 -5.024 90)
			(layer "B.Fab")
			(hide yes)
			(effects
				(font
					(size 0.7 0.7)
					(thickness 0.15)
				)
				(justify left bottom mirror)
			)
		)
		(fp_text user "${REFERENCE}"
			(at -1.12 -3.824 90)
			(layer "B.Fab")
			(hide yes)
			(effects
				(font
					(size 0.7 0.7)
					(thickness 0.15)
				)
				(justify left bottom mirror)
			)
		)
		(fp_text user "Author: Antmicro"
			(at -1.12 -6.224 90)
			(layer "B.Fab")
			(hide yes)
			(effects
				(font
					(size 0.7 0.7)
					(thickness 0.15)
				)
				(justify left bottom mirror)
			)
		)
		(pad "1" smd rect
			(at -0.5 -0.65 270)
			(size 0.4 0.51)
			(layers "B.Cu" "B.Paste" "B.Mask")
			(net 272 "/USB Debug, DP/FTDI_LED_RX")
			(pinfunction "G")
			(pintype "passive")
		)
		(pad "2" smd rect
			(at 0.498 -0.65 270)
			(size 0.4 0.51)
			(layers "B.Cu" "B.Paste" "B.Mask")
			(net 1 "GND")
			(pinfunction "S")
			(pintype "passive")
		)
		(pad "3" smd rect
			(at 0 0.652 270)
			(size 0.4 0.51)
			(layers "B.Cu" "B.Paste" "B.Mask")
			(net 397 "/USB Debug, DP/FTDI_CBUS_EN")
			(pinfunction "D")
			(pintype "passive")
		)
	)
	(footprint "antmicro-footprints:C_0402_1005Metric"
		(layer "B.Cu")
		(at 139.54 97.53 180)
		(descr "Capacitor SMD 0402")
		(tags "capacitor SMD 0402")
		(property "Reference" "C100"
			(at -1.24 0.53 0)
			(layer "B.SilkS")
			(effects
				(font
					(size 0.7 0.7)
					(thickness 0.15)
				)
				(justify left bottom mirror)
			)
		)
		(property "Value" "C_100n_0402"
			(at 0 -1.4 0)
			(layer "B.Fab")
			(effects
				(font
					(size 0.7 0.7)
					(thickness 0.15)
				)
				(justify left bottom mirror)
			)
		)
		(property "Footprint" "antmicro-footprints:C_0402_1005Metric"
			(at 0 0 180)
			(layer "F.Fab")
			(hide yes)
			(effects
				(font
					(size 1.27 1.27)
					(thickness 0.15)
				)
			)
		)
		(property "Datasheet" "https://www.murata.com/products/productdetail?partno=GRM155R61H104KE14%23"
			(at 0 0 180)
			(layer "F.Fab")
			(hide yes)
			(effects
				(font
					(size 1.27 1.27)
					(thickness 0.15)
				)
			)
		)
		(property "Author" "Antmicro"
			(at 279.08 195.06 0)
			(layer "B.Fab")
			(hide yes)
			(effects
				(font
					(size 1 1)
					(thickness 0.15)
				)
				(justify mirror)
			)
		)
		(property "Dielectric" "X5R"
			(at 279.08 195.06 0)
			(layer "B.Fab")
			(hide yes)
			(effects
				(font
					(size 1 1)
					(thickness 0.15)
				)
				(justify mirror)
			)
		)
		(property "License" "Apache-2.0"
			(at 279.08 195.06 0)
			(layer "B.Fab")
			(hide yes)
			(effects
				(font
					(size 1 1)
					(thickness 0.15)
				)
				(justify mirror)
			)
		)
		(property "MPN" "GRM155R61H104KE14D"
			(at 279.08 195.06 0)
			(layer "B.Fab")
			(hide yes)
			(effects
				(font
					(size 1 1)
					(thickness 0.15)
				)
				(justify mirror)
			)
		)
		(property "Manufacturer" "Murata"
			(at 279.08 195.06 0)
			(layer "B.Fab")
			(hide yes)
			(effects
				(font
					(size 1 1)
					(thickness 0.15)
				)
				(justify mirror)
			)
		)
		(property "Val" "100n"
			(at 279.08 195.06 0)
			(layer "B.Fab")
			(hide yes)
			(effects
				(font
					(size 1 1)
					(thickness 0.15)
				)
				(justify mirror)
			)
		)
		(property "Voltage" "50V"
			(at 279.08 195.06 0)
			(layer "B.Fab")
			(hide yes)
			(effects
				(font
					(size 1 1)
					(thickness 0.15)
				)
				(justify mirror)
			)
		)
		(sheetname "CSI")
		(sheetfile "csi.kicad_sch")
		(attr smd)
		(fp_rect
			(start -0.925 0.47)
			(end 0.925 -0.47)
			(stroke
				(width 0.05)
				(type default)
			)
			(fill none)
			(layer "B.CrtYd")
		)
		(fp_line
			(start 0.504 0.25)
			(end -0.494 0.25)
			(stroke
				(width 0.15)
				(type solid)
			)
			(layer "B.Fab")
		)
		(fp_line
			(start 0.504 -0.248)
			(end 0.504 0.25)
			(stroke
				(width 0.15)
				(type solid)
			)
			(layer "B.Fab")
		)
		(fp_line
			(start -0.494 0.25)
			(end -0.494 -0.248)
			(stroke
				(width 0.15)
				(type solid)
			)
			(layer "B.Fab")
		)
		(fp_line
			(start -0.494 -0.248)
			(end 0.504 -0.248)
			(stroke
				(width 0.15)
				(type solid)
			)
			(layer "B.Fab")
		)
		(fp_text user "License: Apache-2.0"
			(at -0.932 -5.17 0)
			(layer "B.Fab")
			(hide yes)
			(effects
				(font
					(size 0.7 0.7)
					(thickness 0.15)
				)
				(justify left bottom mirror)
			)
		)
		(fp_text user "Author: Antmicro"
			(at -0.932 -4.17 0)
			(layer "B.Fab")
			(hide yes)
			(effects
				(font
					(size 0.7 0.7)
					(thickness 0.15)
				)
				(justify left bottom mirror)
			)
		)
		(fp_text user "${REFERENCE}"
			(at -0.932 -3.168 0)
			(layer "B.Fab")
			(hide yes)
			(effects
				(font
					(size 0.7 0.7)
					(thickness 0.15)
				)
				(justify left bottom mirror)
			)
		)
		(pad "1" smd roundrect
			(at -0.48 0 180)
			(size 0.59 0.64)
			(layers "B.Cu" "B.Paste" "B.Mask")
			(roundrect_rratio 0.25)
			(net 1 "GND")
			(pintype "passive")
		)
		(pad "2" smd roundrect
			(at 0.48 0 180)
			(size 0.59 0.64)
			(layers "B.Cu" "B.Paste" "B.Mask")
			(roundrect_rratio 0.25)
			(net 87 "+3V3")
			(pintype "passive")
		)
	)
	(footprint "antmicro-footprints:R_Array_4x0201_Panasonic_EXB18V"
		(layer "B.Cu")
		(at 112.22 74.63 90)
		(property "Reference" "R108"
			(at -1.52 -0.67 -90)
			(layer "B.SilkS")
			(effects
				(font
					(size 0.7 0.7)
					(thickness 0.15)
				)
				(justify right bottom mirror)
			)
		)
		(property "Value" "R_4x0R_0201_array"
			(at -1.1 -1.8 -90)
			(layer "B.Fab")
			(effects
				(font
					(size 0.7 0.7)
					(thickness 0.15)
				)
				(justify left bottom mirror)
			)
		)
		(property "Footprint" "antmicro-footprints:R_Array_4x0201_Panasonic_EXB18V"
			(at 0 0 90)
			(layer "F.Fab")
			(hide yes)
			(effects
				(font
					(size 1.27 1.27)
					(thickness 0.15)
				)
			)
		)
		(property "Datasheet" "http://industrial.panasonic.com/cdbs/www-data/pdf/AOC0000/AOC0000C14.pdf"
			(at 0 0 90)
			(layer "F.Fab")
			(hide yes)
			(effects
				(font
					(size 1.27 1.27)
					(thickness 0.15)
				)
			)
		)
		(property "Author" "Antmicro"
			(at 186.85 -37.59 0)
			(layer "B.Fab")
			(hide yes)
			(effects
				(font
					(size 1 1)
					(thickness 0.15)
				)
				(justify mirror)
			)
		)
		(property "License" "Apache-2.0"
			(at 186.85 -37.59 0)
			(layer "B.Fab")
			(hide yes)
			(effects
				(font
					(size 1 1)
					(thickness 0.15)
				)
				(justify mirror)
			)
		)
		(property "MPN" "EXB-18VR000X"
			(at 186.85 -37.59 0)
			(layer "B.Fab")
			(hide yes)
			(effects
				(font
					(size 1 1)
					(thickness 0.15)
				)
				(justify mirror)
			)
		)
		(property "Manufacturer" "Panasonic"
			(at 186.85 -37.59 0)
			(layer "B.Fab")
			(hide yes)
			(effects
				(font
					(size 1 1)
					(thickness 0.15)
				)
				(justify mirror)
			)
		)
		(property "Val" "4x0R_0201"
			(at 186.85 -37.59 0)
			(layer "B.Fab")
			(hide yes)
			(effects
				(font
					(size 1 1)
					(thickness 0.15)
				)
				(justify mirror)
			)
		)
		(sheetname "CSI")
		(sheetfile "csi.kicad_sch")
		(attr smd)
		(fp_line
			(start 0.8 -0.45)
			(end 0.8 0.45)
			(stroke
				(width 0.12)
				(type solid)
			)
			(layer "B.SilkS")
		)
		(fp_line
			(start -0.8 -0.45)
			(end -0.8 0.45)
			(stroke
				(width 0.12)
				(type solid)
			)
			(layer "B.SilkS")
		)
		(fp_rect
			(start -0.898 0.66)
			(end 0.898 -0.65)
			(stroke
				(width 0.05)
				(type solid)
			)
			(fill none)
			(layer "B.CrtYd")
		)
		(fp_text user "License: Apache-2.0"
			(at -1.051 -6 -90)
			(layer "B.Fab")
			(hide yes)
			(effects
				(font
					(size 0.7 0.7)
					(thickness 0.15)
				)
				(justify left bottom mirror)
			)
		)
		(fp_text user "Author: Antmicro"
			(at -1.051 -4.599 -90)
			(layer "B.Fab")
			(hide yes)
			(effects
				(font
					(size 0.7 0.7)
					(thickness 0.15)
				)
				(justify left bottom mirror)
			)
		)
		(fp_text user "${REFERENCE}"
			(at -1.051 -3.2 -90)
			(layer "B.Fab")
			(hide yes)
			(effects
				(font
					(size 0.7 0.7)
					(thickness 0.15)
				)
				(justify left bottom mirror)
			)
		)
		(pad "1" smd roundrect
			(at -0.6 -0.298 90)
			(size 0.2 0.4)
			(layers "B.Cu" "B.Paste" "B.Mask")
			(roundrect_rratio 0.25)
			(net 14 "CSI3_D0_N")
			(pinfunction "R1.1")
			(pintype "passive")
		)
		(pad "2" smd roundrect
			(at -0.202 -0.298 90)
			(size 0.2 0.4)
			(layers "B.Cu" "B.Paste" "B.Mask")
			(roundrect_rratio 0.25)
			(net 16 "CSI3_D0_P")
			(pinfunction "R2.1")
			(pintype "passive")
		)
		(pad "3" smd roundrect
			(at 0.2 -0.298 90)
			(size 0.2 0.4)
			(layers "B.Cu" "B.Paste" "B.Mask")
			(roundrect_rratio 0.25)
			(net 22 "CSI3_D1_N")
			(pinfunction "R3.1")
			(pintype "passive")
		)
		(pad "4" smd roundrect
			(at 0.598 -0.298 90)
			(size 0.2 0.4)
			(layers "B.Cu" "B.Paste" "B.Mask")
			(roundrect_rratio 0.25)
			(net 24 "CSI3_D1_P")
			(pinfunction "R4.1")
			(pintype "passive")
		)
		(pad "5" smd roundrect
			(at 0.598 0.3 90)
			(size 0.2 0.4)
			(layers "B.Cu" "B.Paste" "B.Mask")
			(roundrect_rratio 0.25)
			(net 213 "/CSI/CSI3_0_D1_P")
			(pinfunction "R4.2")
			(pintype "passive")
		)
		(pad "6" smd roundrect
			(at 0.2 0.3 90)
			(size 0.2 0.4)
			(layers "B.Cu" "B.Paste" "B.Mask")
			(roundrect_rratio 0.25)
			(net 212 "/CSI/CSI3_0_D1_N")
			(pinfunction "R3.2")
			(pintype "passive")
		)
		(pad "7" smd roundrect
			(at -0.202 0.3 90)
			(size 0.2 0.4)
			(layers "B.Cu" "B.Paste" "B.Mask")
			(roundrect_rratio 0.25)
			(net 215 "/CSI/CSI3_0_D0_P")
			(pinfunction "R2.2")
			(pintype "passive")
		)
		(pad "8" smd roundrect
			(at -0.6 0.3 90)
			(size 0.2 0.4)
			(layers "B.Cu" "B.Paste" "B.Mask")
			(roundrect_rratio 0.25)
			(net 214 "/CSI/CSI3_0_D0_N")
			(pinfunction "R1.2")
			(pintype "passive")
		)
	)
	(footprint "antmicro-footprints:R_0402_1005Metric"
		(layer "B.Cu")
		(at 138.8 122)
		(descr "Resistor SMD 0402")
		(tags "resistor SMD 0402")
		(property "Reference" "R192"
			(at 1.11 -1.35 180)
			(layer "B.SilkS")
			(effects
				(font
					(size 0.7 0.7)
					(thickness 0.15)
				)
				(justify left bottom mirror)
			)
		)
		(property "Value" "R_100k_0402"
			(at 0 -1.4 180)
			(layer "B.Fab")
			(effects
				(font
					(size 0.7 0.7)
					(thickness 0.15)
				)
				(justify left bottom mirror)
			)
		)
		(property "Footprint" "antmicro-footprints:R_0402_1005Metric"
			(at 0 0 0)
			(layer "F.Fab")
			(hide yes)
			(effects
				(font
					(size 1.27 1.27)
					(thickness 0.15)
				)
			)
		)
		(property "Datasheet" "https://www.bourns.com/docs/product-datasheets/cr.pdf"
			(at 0 0 0)
			(layer "F.Fab")
			(hide yes)
			(effects
				(font
					(size 1.27 1.27)
					(thickness 0.15)
				)
			)
		)
		(property "Author" "Antmicro"
			(at 0 0 0)
			(layer "B.Fab")
			(hide yes)
			(effects
				(font
					(size 1 1)
					(thickness 0.15)
				)
				(justify mirror)
			)
		)
		(property "License" "Apache-2.0"
			(at 0 0 0)
			(layer "B.Fab")
			(hide yes)
			(effects
				(font
					(size 1 1)
					(thickness 0.15)
				)
				(justify mirror)
			)
		)
		(property "MPN" "CR0402-FX-1003GLF"
			(at 0 0 0)
			(layer "B.Fab")
			(hide yes)
			(effects
				(font
					(size 1 1)
					(thickness 0.15)
				)
				(justify mirror)
			)
		)
		(property "Manufacturer" "Bourns"
			(at 0 0 0)
			(layer "B.Fab")
			(hide yes)
			(effects
				(font
					(size 1 1)
					(thickness 0.15)
				)
				(justify mirror)
			)
		)
		(property "Tolerance" "1%"
			(at 0 0 0)
			(layer "B.Fab")
			(hide yes)
			(effects
				(font
					(size 1 1)
					(thickness 0.15)
				)
				(justify mirror)
			)
		)
		(property "Val" "100k"
			(at 0 0 0)
			(layer "B.Fab")
			(hide yes)
			(effects
				(font
					(size 1 1)
					(thickness 0.15)
				)
				(justify mirror)
			)
		)
		(sheetname "Peripherals")
		(sheetfile "peripherals.kicad_sch")
		(attr smd exclude_from_pos_files exclude_from_bom dnp)
		(fp_rect
			(start -0.925 0.47)
			(end 0.925 -0.47)
			(stroke
				(width 0.05)
				(type default)
			)
			(fill none)
			(layer "B.CrtYd")
		)
		(fp_rect
			(start -0.5 0.25)
			(end 0.5 -0.25)
			(stroke
				(width 0.15)
				(type solid)
			)
			(fill none)
			(layer "B.Fab")
		)
		(fp_text user "License: Apache-2.0"
			(at -0.95 -5.169 180)
			(layer "B.Fab")
			(hide yes)
			(effects
				(font
					(size 0.7 0.7)
					(thickness 0.15)
				)
				(justify left bottom mirror)
			)
		)
		(fp_text user "${REFERENCE}"
			(at -0.95 -3.168 180)
			(layer "B.Fab")
			(hide yes)
			(effects
				(font
					(size 0.7 0.7)
					(thickness 0.15)
				)
				(justify left bottom mirror)
			)
		)
		(fp_text user "Author: Antmicro"
			(at -0.95 -4.169 180)
			(layer "B.Fab")
			(hide yes)
			(effects
				(font
					(size 0.7 0.7)
					(thickness 0.15)
				)
				(justify left bottom mirror)
			)
		)
		(pad "1" smd roundrect
			(at -0.48 0)
			(size 0.59 0.64)
			(layers "B.Cu" "B.Paste" "B.Mask")
			(roundrect_rratio 0.25)
			(net 1 "GND")
			(pintype "passive")
		)
		(pad "2" smd roundrect
			(at 0.48 0)
			(size 0.59 0.64)
			(layers "B.Cu" "B.Paste" "B.Mask")
			(roundrect_rratio 0.25)
			(net 658 "/Peripherals/I2C_CONN_PEN")
			(pintype "passive")
		)
	)
	(footprint "antmicro-footprints:R_0402_1005Metric"
		(layer "B.Cu")
		(at 69.6 94.4 -90)
		(descr "Resistor SMD 0402")
		(tags "resistor SMD 0402")
		(property "Reference" "R81"
			(at -1.15 -2.32 90)
			(layer "B.SilkS")
			(effects
				(font
					(size 0.7 0.7)
					(thickness 0.15)
				)
				(justify left bottom mirror)
			)
		)
		(property "Value" "R_4k7_0402"
			(at 0 -1.4 90)
			(layer "B.Fab")
			(effects
				(font
					(size 0.7 0.7)
					(thickness 0.15)
				)
				(justify left bottom mirror)
			)
		)
		(property "Footprint" "antmicro-footprints:R_0402_1005Metric"
			(at 0 0 -90)
			(layer "F.Fab")
			(hide yes)
			(effects
				(font
					(size 1.27 1.27)
					(thickness 0.15)
				)
			)
		)
		(property "Datasheet" "https://www.bourns.com/docs/product-datasheets/cr.pdf"
			(at 0 0 -90)
			(layer "F.Fab")
			(hide yes)
			(effects
				(font
					(size 1.27 1.27)
					(thickness 0.15)
				)
			)
		)
		(property "Author" "Antmicro"
			(at -24.8 164 0)
			(layer "B.Fab")
			(hide yes)
			(effects
				(font
					(size 1 1)
					(thickness 0.15)
				)
				(justify mirror)
			)
		)
		(property "License" "Apache-2.0"
			(at -24.8 164 0)
			(layer "B.Fab")
			(hide yes)
			(effects
				(font
					(size 1 1)
					(thickness 0.15)
				)
				(justify mirror)
			)
		)
		(property "MPN" "CR0402-FX-4701GLF"
			(at -24.8 164 0)
			(layer "B.Fab")
			(hide yes)
			(effects
				(font
					(size 1 1)
					(thickness 0.15)
				)
				(justify mirror)
			)
		)
		(property "Manufacturer" "Bourns"
			(at -24.8 164 0)
			(layer "B.Fab")
			(hide yes)
			(effects
				(font
					(size 1 1)
					(thickness 0.15)
				)
				(justify mirror)
			)
		)
		(property "Tolerance" "1%"
			(at -24.8 164 0)
			(layer "B.Fab")
			(hide yes)
			(effects
				(font
					(size 1 1)
					(thickness 0.15)
				)
				(justify mirror)
			)
		)
		(property "Val" "4k7"
			(at -24.8 164 0)
			(layer "B.Fab")
			(hide yes)
			(effects
				(font
					(size 1 1)
					(thickness 0.15)
				)
				(justify mirror)
			)
		)
		(sheetname "USB Debug, DP")
		(sheetfile "usb.kicad_sch")
		(attr smd)
		(fp_rect
			(start -0.925 0.47)
			(end 0.925 -0.47)
			(stroke
				(width 0.05)
				(type default)
			)
			(fill none)
			(layer "B.CrtYd")
		)
		(fp_rect
			(start -0.5 0.25)
			(end 0.5 -0.25)
			(stroke
				(width 0.15)
				(type solid)
			)
			(fill none)
			(layer "B.Fab")
		)
		(fp_text user "License: Apache-2.0"
			(at -0.95 -5.169 90)
			(layer "B.Fab")
			(hide yes)
			(effects
				(font
					(size 0.7 0.7)
					(thickness 0.15)
				)
				(justify left bottom mirror)
			)
		)
		(fp_text user "${REFERENCE}"
			(at -0.95 -3.168 90)
			(layer "B.Fab")
			(hide yes)
			(effects
				(font
					(size 0.7 0.7)
					(thickness 0.15)
				)
				(justify left bottom mirror)
			)
		)
		(fp_text user "Author: Antmicro"
			(at -0.95 -4.169 90)
			(layer "B.Fab")
			(hide yes)
			(effects
				(font
					(size 0.7 0.7)
					(thickness 0.15)
				)
				(justify left bottom mirror)
			)
		)
		(pad "1" smd roundrect
			(at -0.48 0 270)
			(size 0.59 0.64)
			(layers "B.Cu" "B.Paste" "B.Mask")
			(roundrect_rratio 0.25)
			(net 87 "+3V3")
			(pintype "passive")
		)
		(pad "2" smd roundrect
			(at 0.48 0 270)
			(size 0.59 0.64)
			(layers "B.Cu" "B.Paste" "B.Mask")
			(roundrect_rratio 0.25)
			(net 396 "/USB Debug, DP/PDC_I2C2_SDA")
			(pintype "passive")
		)
	)
	(footprint "antmicro-footprints:R_0402_1005Metric"
		(layer "B.Cu")
		(at 64.925 110.275 90)
		(descr "Resistor SMD 0402")
		(tags "resistor SMD 0402")
		(property "Reference" "R45"
			(at -0.845 0.365 -90)
			(layer "B.SilkS")
			(effects
				(font
					(size 0.7 0.7)
					(thickness 0.15)
				)
				(justify left bottom mirror)
			)
		)
		(property "Value" "R_100k_0402"
			(at 0 -1.4 -90)
			(layer "B.Fab")
			(effects
				(font
					(size 0.7 0.7)
					(thickness 0.15)
				)
				(justify left bottom mirror)
			)
		)
		(property "Footprint" "antmicro-footprints:R_0402_1005Metric"
			(at 0 0 90)
			(layer "F.Fab")
			(hide yes)
			(effects
				(font
					(size 1.27 1.27)
					(thickness 0.15)
				)
			)
		)
		(property "Datasheet" "https://www.bourns.com/docs/product-datasheets/cr.pdf"
			(at 0 0 90)
			(layer "F.Fab")
			(hide yes)
			(effects
				(font
					(size 1.27 1.27)
					(thickness 0.15)
				)
			)
		)
		(property "Author" "Antmicro"
			(at 175.2 45.35 0)
			(layer "B.Fab")
			(hide yes)
			(effects
				(font
					(size 1 1)
					(thickness 0.15)
				)
				(justify mirror)
			)
		)
		(property "License" "Apache-2.0"
			(at 175.2 45.35 0)
			(layer "B.Fab")
			(hide yes)
			(effects
				(font
					(size 1 1)
					(thickness 0.15)
				)
				(justify mirror)
			)
		)
		(property "MPN" "CR0402-FX-1003GLF"
			(at 175.2 45.35 0)
			(layer "B.Fab")
			(hide yes)
			(effects
				(font
					(size 1 1)
					(thickness 0.15)
				)
				(justify mirror)
			)
		)
		(property "Manufacturer" "Bourns"
			(at 175.2 45.35 0)
			(layer "B.Fab")
			(hide yes)
			(effects
				(font
					(size 1 1)
					(thickness 0.15)
				)
				(justify mirror)
			)
		)
		(property "Tolerance" "1%"
			(at 175.2 45.35 0)
			(layer "B.Fab")
			(hide yes)
			(effects
				(font
					(size 1 1)
					(thickness 0.15)
				)
				(justify mirror)
			)
		)
		(property "Val" "100k"
			(at 175.2 45.35 0)
			(layer "B.Fab")
			(hide yes)
			(effects
				(font
					(size 1 1)
					(thickness 0.15)
				)
				(justify mirror)
			)
		)
		(sheetname "USB Debug, DP")
		(sheetfile "usb.kicad_sch")
		(attr smd)
		(fp_rect
			(start -0.925 0.47)
			(end 0.925 -0.47)
			(stroke
				(width 0.05)
				(type default)
			)
			(fill none)
			(layer "B.CrtYd")
		)
		(fp_rect
			(start -0.5 0.25)
			(end 0.5 -0.25)
			(stroke
				(width 0.15)
				(type solid)
			)
			(fill none)
			(layer "B.Fab")
		)
		(fp_text user "License: Apache-2.0"
			(at -0.95 -5.169 -90)
			(layer "B.Fab")
			(hide yes)
			(effects
				(font
					(size 0.7 0.7)
					(thickness 0.15)
				)
				(justify left bottom mirror)
			)
		)
		(fp_text user "${REFERENCE}"
			(at -0.95 -3.168 -90)
			(layer "B.Fab")
			(hide yes)
			(effects
				(font
					(size 0.7 0.7)
					(thickness 0.15)
				)
				(justify left bottom mirror)
			)
		)
		(fp_text user "Author: Antmicro"
			(at -0.95 -4.169 -90)
			(layer "B.Fab")
			(hide yes)
			(effects
				(font
					(size 0.7 0.7)
					(thickness 0.15)
				)
				(justify left bottom mirror)
			)
		)
		(pad "1" smd roundrect
			(at -0.48 0 90)
			(size 0.59 0.64)
			(layers "B.Cu" "B.Paste" "B.Mask")
			(roundrect_rratio 0.25)
			(net 1 "GND")
			(pintype "passive")
		)
		(pad "2" smd roundrect
			(at 0.48 0 90)
			(size 0.59 0.64)
			(layers "B.Cu" "B.Paste" "B.Mask")
			(roundrect_rratio 0.25)
			(net 287 "/USB Debug, DP/PDC_ADCIN2")
			(pintype "passive")
		)
	)
	(footprint "antmicro-footprints:C_0402_1005Metric"
		(layer "B.Cu")
		(at 106.4 87.87 90)
		(descr "Capacitor SMD 0402")
		(tags "capacitor SMD 0402")
		(property "Reference" "C7"
			(at 0.67 -0.45 -90)
			(layer "B.SilkS")
			(effects
				(font
					(size 0.7 0.7)
					(thickness 0.15)
				)
				(justify left bottom mirror)
			)
		)
		(property "Value" "C_100n_0402"
			(at 0 -1.4 -90)
			(layer "B.Fab")
			(effects
				(font
					(size 0.7 0.7)
					(thickness 0.15)
				)
				(justify left bottom mirror)
			)
		)
		(property "Footprint" "antmicro-footprints:C_0402_1005Metric"
			(at 0 0 90)
			(layer "F.Fab")
			(hide yes)
			(effects
				(font
					(size 1.27 1.27)
					(thickness 0.15)
				)
			)
		)
		(property "Datasheet" "https://www.murata.com/products/productdetail?partno=GRM155R61H104KE14%23"
			(at 0 0 90)
			(layer "F.Fab")
			(hide yes)
			(effects
				(font
					(size 1.27 1.27)
					(thickness 0.15)
				)
			)
		)
		(property "Author" "Antmicro"
			(at 194.27 -18.53 0)
			(layer "B.Fab")
			(hide yes)
			(effects
				(font
					(size 1 1)
					(thickness 0.15)
				)
				(justify mirror)
			)
		)
		(property "Dielectric" "X5R"
			(at 194.27 -18.53 0)
			(layer "B.Fab")
			(hide yes)
			(effects
				(font
					(size 1 1)
					(thickness 0.15)
				)
				(justify mirror)
			)
		)
		(property "License" "Apache-2.0"
			(at 194.27 -18.53 0)
			(layer "B.Fab")
			(hide yes)
			(effects
				(font
					(size 1 1)
					(thickness 0.15)
				)
				(justify mirror)
			)
		)
		(property "MPN" "GRM155R61H104KE14D"
			(at 194.27 -18.53 0)
			(layer "B.Fab")
			(hide yes)
			(effects
				(font
					(size 1 1)
					(thickness 0.15)
				)
				(justify mirror)
			)
		)
		(property "Manufacturer" "Murata"
			(at 194.27 -18.53 0)
			(layer "B.Fab")
			(hide yes)
			(effects
				(font
					(size 1 1)
					(thickness 0.15)
				)
				(justify mirror)
			)
		)
		(property "Val" "100n"
			(at 194.27 -18.53 0)
			(layer "B.Fab")
			(hide yes)
			(effects
				(font
					(size 1 1)
					(thickness 0.15)
				)
				(justify mirror)
			)
		)
		(property "Voltage" "50V"
			(at 194.27 -18.53 0)
			(layer "B.Fab")
			(hide yes)
			(effects
				(font
					(size 1 1)
					(thickness 0.15)
				)
				(justify mirror)
			)
		)
		(sheetname "M.2")
		(sheetfile "m-2.kicad_sch")
		(attr smd)
		(fp_rect
			(start -0.925 0.47)
			(end 0.925 -0.47)
			(stroke
				(width 0.05)
				(type default)
			)
			(fill none)
			(layer "B.CrtYd")
		)
		(fp_line
			(start 0.504 -0.248)
			(end 0.504 0.25)
			(stroke
				(width 0.15)
				(type solid)
			)
			(layer "B.Fab")
		)
		(fp_line
			(start -0.494 -0.248)
			(end 0.504 -0.248)
			(stroke
				(width 0.15)
				(type solid)
			)
			(layer "B.Fab")
		)
		(fp_line
			(start 0.504 0.25)
			(end -0.494 0.25)
			(stroke
				(width 0.15)
				(type solid)
			)
			(layer "B.Fab")
		)
		(fp_line
			(start -0.494 0.25)
			(end -0.494 -0.248)
			(stroke
				(width 0.15)
				(type solid)
			)
			(layer "B.Fab")
		)
		(fp_text user "Author: Antmicro"
			(at -0.932 -4.17 -90)
			(layer "B.Fab")
			(hide yes)
			(effects
				(font
					(size 0.7 0.7)
					(thickness 0.15)
				)
				(justify left bottom mirror)
			)
		)
		(fp_text user "License: Apache-2.0"
			(at -0.932 -5.17 -90)
			(layer "B.Fab")
			(hide yes)
			(effects
				(font
					(size 0.7 0.7)
					(thickness 0.15)
				)
				(justify left bottom mirror)
			)
		)
		(fp_text user "${REFERENCE}"
			(at -0.932 -3.168 -90)
			(layer "B.Fab")
			(hide yes)
			(effects
				(font
					(size 0.7 0.7)
					(thickness 0.15)
				)
				(justify left bottom mirror)
			)
		)
		(pad "1" smd roundrect
			(at -0.48 0 90)
			(size 0.59 0.64)
			(layers "B.Cu" "B.Paste" "B.Mask")
			(roundrect_rratio 0.25)
			(net 87 "+3V3")
			(pintype "passive")
		)
		(pad "2" smd roundrect
			(at 0.48 0 90)
			(size 0.59 0.64)
			(layers "B.Cu" "B.Paste" "B.Mask")
			(roundrect_rratio 0.25)
			(net 1 "GND")
			(pintype "passive")
		)
	)
	(footprint "antmicro-footprints:R_0402_1005Metric"
		(layer "B.Cu")
		(at 130.6 93.2 90)
		(descr "Resistor SMD 0402")
		(tags "resistor SMD 0402")
		(property "Reference" "R134"
			(at 3.78 0.44 -90)
			(layer "B.SilkS")
			(effects
				(font
					(size 0.7 0.7)
					(thickness 0.15)
				)
				(justify left bottom mirror)
			)
		)
		(property "Value" "R_0R_0402"
			(at 0 -1.4 -90)
			(layer "B.Fab")
			(effects
				(font
					(size 0.7 0.7)
					(thickness 0.15)
				)
				(justify left bottom mirror)
			)
		)
		(property "Footprint" "antmicro-footprints:R_0402_1005Metric"
			(at 0 0 90)
			(layer "F.Fab")
			(hide yes)
			(effects
				(font
					(size 1.27 1.27)
					(thickness 0.15)
				)
			)
		)
		(property "Datasheet" "https://industrial.panasonic.com/cdbs/www-data/pdf/RDA0000/AOA0000C301.pdf"
			(at 0 0 90)
			(layer "F.Fab")
			(hide yes)
			(effects
				(font
					(size 1.27 1.27)
					(thickness 0.15)
				)
			)
		)
		(property "Author" "Antmicro"
			(at 223.8 -37.4 0)
			(layer "B.Fab")
			(hide yes)
			(effects
				(font
					(size 1 1)
					(thickness 0.15)
				)
				(justify mirror)
			)
		)
		(property "Current" "1A"
			(at 223.8 -37.4 0)
			(layer "B.Fab")
			(hide yes)
			(effects
				(font
					(size 1 1)
					(thickness 0.15)
				)
				(justify mirror)
			)
		)
		(property "License" "Apache-2.0"
			(at 223.8 -37.4 0)
			(layer "B.Fab")
			(hide yes)
			(effects
				(font
					(size 1 1)
					(thickness 0.15)
				)
				(justify mirror)
			)
		)
		(property "MPN" "ERJ2GE0R00X"
			(at 223.8 -37.4 0)
			(layer "B.Fab")
			(hide yes)
			(effects
				(font
					(size 1 1)
					(thickness 0.15)
				)
				(justify mirror)
			)
		)
		(property "Manufacturer" "Panasonic"
			(at 223.8 -37.4 0)
			(layer "B.Fab")
			(hide yes)
			(effects
				(font
					(size 1 1)
					(thickness 0.15)
				)
				(justify mirror)
			)
		)
		(property "Tolerance" ""
			(at 223.8 -37.4 0)
			(layer "B.Fab")
			(hide yes)
			(effects
				(font
					(size 1 1)
					(thickness 0.15)
				)
				(justify mirror)
			)
		)
		(property "Val" "0R"
			(at 223.8 -37.4 0)
			(layer "B.Fab")
			(hide yes)
			(effects
				(font
					(size 1 1)
					(thickness 0.15)
				)
				(justify mirror)
			)
		)
		(sheetname "Peripherals")
		(sheetfile "peripherals.kicad_sch")
		(attr smd exclude_from_pos_files exclude_from_bom dnp)
		(fp_rect
			(start -0.925 0.47)
			(end 0.925 -0.47)
			(stroke
				(width 0.05)
				(type default)
			)
			(fill none)
			(layer "B.CrtYd")
		)
		(fp_rect
			(start -0.5 0.25)
			(end 0.5 -0.25)
			(stroke
				(width 0.15)
				(type solid)
			)
			(fill none)
			(layer "B.Fab")
		)
		(fp_text user "${REFERENCE}"
			(at -0.95 -3.168 -90)
			(layer "B.Fab")
			(hide yes)
			(effects
				(font
					(size 0.7 0.7)
					(thickness 0.15)
				)
				(justify left bottom mirror)
			)
		)
		(fp_text user "License: Apache-2.0"
			(at -0.95 -5.169 -90)
			(layer "B.Fab")
			(hide yes)
			(effects
				(font
					(size 0.7 0.7)
					(thickness 0.15)
				)
				(justify left bottom mirror)
			)
		)
		(fp_text user "Author: Antmicro"
			(at -0.95 -4.169 -90)
			(layer "B.Fab")
			(hide yes)
			(effects
				(font
					(size 0.7 0.7)
					(thickness 0.15)
				)
				(justify left bottom mirror)
			)
		)
		(pad "1" smd roundrect
			(at -0.48 0 90)
			(size 0.59 0.64)
			(layers "B.Cu" "B.Paste" "B.Mask")
			(roundrect_rratio 0.25)
			(net 618 "/Peripherals/USB_CONN_N")
			(pintype "passive")
		)
		(pad "2" smd roundrect
			(at 0.48 0 90)
			(size 0.59 0.64)
			(layers "B.Cu" "B.Paste" "B.Mask")
			(roundrect_rratio 0.25)
			(net 434 "USB1_D_N")
			(pintype "passive")
		)
	)
	(footprint "antmicro-footprints:TP_SMD_0.75mm"
		(layer "B.Cu")
		(at 59.69 102.41 -135)
		(property "Reference" "TP26"
			(at 1.152584 -1.421285 45)
			(layer "B.SilkS")
			(hide yes)
			(effects
				(font
					(size 0.7 0.7)
					(thickness 0.15)
				)
				(justify left bottom mirror)
			)
		)
		(property "Value" "TP_0.75mm_SMD"
			(at 0 -1.2 45)
			(layer "B.Fab")
			(effects
				(font
					(size 0.7 0.7)
					(thickness 0.15)
				)
				(justify left bottom mirror)
			)
		)
		(property "Footprint" "antmicro-footprints:TP_SMD_0.75mm"
			(at 0 0 -135)
			(layer "F.Fab")
			(hide yes)
			(effects
				(font
					(size 1.27 1.27)
					(thickness 0.15)
				)
			)
		)
		(property "Author" "Antmicro"
			(at 29.482398 217.032009 0)
			(layer "B.Fab")
			(hide yes)
			(effects
				(font
					(size 1 1)
					(thickness 0.15)
				)
				(justify mirror)
			)
		)
		(property "License" "Apache-2.0"
			(at 29.482398 217.032009 0)
			(layer "B.Fab")
			(hide yes)
			(effects
				(font
					(size 1 1)
					(thickness 0.15)
				)
				(justify mirror)
			)
		)
		(property "MPN" ""
			(at 29.482398 217.032009 0)
			(layer "B.Fab")
			(hide yes)
			(effects
				(font
					(size 1 1)
					(thickness 0.15)
				)
				(justify mirror)
			)
		)
		(property "Manufacturer" ""
			(at 29.482398 217.032009 0)
			(layer "B.Fab")
			(hide yes)
			(effects
				(font
					(size 1 1)
					(thickness 0.15)
				)
				(justify mirror)
			)
		)
		(sheetname "USB Debug, DP")
		(sheetfile "usb.kicad_sch")
		(attr exclude_from_pos_files exclude_from_bom)
		(fp_circle
			(center 0 0)
			(end 0.475 0)
			(stroke
				(width 0.05)
				(type default)
			)
			(fill none)
			(layer "B.CrtYd")
		)
		(fp_text user "${REFERENCE}"
			(at -0.4 -2.7 45)
			(layer "B.Fab")
			(hide yes)
			(effects
				(font
					(size 0.7 0.7)
					(thickness 0.15)
				)
				(justify left bottom mirror)
			)
		)
		(fp_text user "License: Apache-2.0"
			(at -0.4 -5.101 45)
			(layer "B.Fab")
			(hide yes)
			(effects
				(font
					(size 0.7 0.7)
					(thickness 0.15)
				)
				(justify left bottom mirror)
			)
		)
		(fp_text user "Author: Antmicro"
			(at -0.4 -3.901 45)
			(layer "B.Fab")
			(hide yes)
			(effects
				(font
					(size 0.7 0.7)
					(thickness 0.15)
				)
				(justify left bottom mirror)
			)
		)
		(pad "1" smd circle
			(at 0 0 225)
			(size 0.75 0.75)
			(layers "B.Cu" "B.Mask")
			(net 708 "/USB Debug, DP/~{PDC_I2C3_IRQ}")
			(pinfunction "1")
			(pintype "passive")
		)
	)
	(footprint "antmicro-footprints:TP_SMD_0.75mm"
		(layer "B.Cu")
		(at 68.165 123.07 180)
		(property "Reference" "TP54"
			(at -3.12 -0.47 0)
			(layer "B.SilkS")
			(hide yes)
			(effects
				(font
					(size 0.7 0.7)
					(thickness 0.15)
				)
				(justify left bottom mirror)
			)
		)
		(property "Value" "TP_0.75mm_SMD"
			(at 0 -1.2 0)
			(layer "B.Fab")
			(effects
				(font
					(size 0.7 0.7)
					(thickness 0.15)
				)
				(justify left bottom mirror)
			)
		)
		(property "Footprint" "antmicro-footprints:TP_SMD_0.75mm"
			(at 0 0 180)
			(layer "F.Fab")
			(hide yes)
			(effects
				(font
					(size 1.27 1.27)
					(thickness 0.15)
				)
			)
		)
		(property "Author" "Antmicro"
			(at 136.33 246.14 0)
			(layer "B.Fab")
			(hide yes)
			(effects
				(font
					(size 1 1)
					(thickness 0.15)
				)
				(justify mirror)
			)
		)
		(property "License" "Apache-2.0"
			(at 136.33 246.14 0)
			(layer "B.Fab")
			(hide yes)
			(effects
				(font
					(size 1 1)
					(thickness 0.15)
				)
				(justify mirror)
			)
		)
		(property "MPN" ""
			(at 136.33 246.14 0)
			(layer "B.Fab")
			(hide yes)
			(effects
				(font
					(size 1 1)
					(thickness 0.15)
				)
				(justify mirror)
			)
		)
		(property "Manufacturer" ""
			(at 136.33 246.14 0)
			(layer "B.Fab")
			(hide yes)
			(effects
				(font
					(size 1 1)
					(thickness 0.15)
				)
				(justify mirror)
			)
		)
		(sheetname "Supply")
		(sheetfile "supply.kicad_sch")
		(attr exclude_from_pos_files exclude_from_bom)
		(fp_circle
			(center 0 0)
			(end 0.475 0)
			(stroke
				(width 0.05)
				(type default)
			)
			(fill none)
			(layer "B.CrtYd")
		)
		(fp_text user "License: Apache-2.0"
			(at -0.4 -5.101 0)
			(layer "B.Fab")
			(hide yes)
			(effects
				(font
					(size 0.7 0.7)
					(thickness 0.15)
				)
				(justify left bottom mirror)
			)
		)
		(fp_text user "${REFERENCE}"
			(at -0.4 -2.7 0)
			(layer "B.Fab")
			(hide yes)
			(effects
				(font
					(size 0.7 0.7)
					(thickness 0.15)
				)
				(justify left bottom mirror)
			)
		)
		(fp_text user "Author: Antmicro"
			(at -0.4 -3.901 0)
			(layer "B.Fab")
			(hide yes)
			(effects
				(font
					(size 0.7 0.7)
					(thickness 0.15)
				)
				(justify left bottom mirror)
			)
		)
		(pad "1" smd circle
			(at 0 0 180)
			(size 0.75 0.75)
			(layers "B.Cu" "B.Mask")
			(net 87 "+3V3")
			(pinfunction "1")
			(pintype "passive")
		)
	)
	(footprint "antmicro-footprints:TP_SMD_0.75mm"
		(layer "B.Cu")
		(at 63.205 71.3)
		(property "Reference" "TP2"
			(at 2.5 0.385 180)
			(layer "B.SilkS")
			(effects
				(font
					(size 0.7 0.7)
					(thickness 0.15)
				)
				(justify left bottom mirror)
			)
		)
		(property "Value" "TP_0.75mm_SMD"
			(at 0 -1.2 180)
			(layer "B.Fab")
			(effects
				(font
					(size 0.7 0.7)
					(thickness 0.15)
				)
				(justify left bottom mirror)
			)
		)
		(property "Footprint" "antmicro-footprints:TP_SMD_0.75mm"
			(at 0 0 0)
			(layer "F.Fab")
			(hide yes)
			(effects
				(font
					(size 1.27 1.27)
					(thickness 0.15)
				)
			)
		)
		(property "Author" "Antmicro"
			(at 0 0 0)
			(layer "B.Fab")
			(hide yes)
			(effects
				(font
					(size 1 1)
					(thickness 0.15)
				)
				(justify mirror)
			)
		)
		(property "License" "Apache-2.0"
			(at 0 0 0)
			(layer "B.Fab")
			(hide yes)
			(effects
				(font
					(size 1 1)
					(thickness 0.15)
				)
				(justify mirror)
			)
		)
		(property "MPN" ""
			(at 0 0 0)
			(layer "B.Fab")
			(hide yes)
			(effects
				(font
					(size 1 1)
					(thickness 0.15)
				)
				(justify mirror)
			)
		)
		(property "Manufacturer" ""
			(at 0 0 0)
			(layer "B.Fab")
			(hide yes)
			(effects
				(font
					(size 1 1)
					(thickness 0.15)
				)
				(justify mirror)
			)
		)
		(sheetname "SoM")
		(sheetfile "som.kicad_sch")
		(attr exclude_from_pos_files exclude_from_bom)
		(fp_circle
			(center 0 0)
			(end 0.475 0)
			(stroke
				(width 0.05)
				(type default)
			)
			(fill none)
			(layer "B.CrtYd")
		)
		(fp_text user "License: Apache-2.0"
			(at -0.4 -5.101 180)
			(layer "B.Fab")
			(hide yes)
			(effects
				(font
					(size 0.7 0.7)
					(thickness 0.15)
				)
				(justify left bottom mirror)
			)
		)
		(fp_text user "Author: Antmicro"
			(at -0.4 -3.901 180)
			(layer "B.Fab")
			(hide yes)
			(effects
				(font
					(size 0.7 0.7)
					(thickness 0.15)
				)
				(justify left bottom mirror)
			)
		)
		(fp_text user "${REFERENCE}"
			(at -0.4 -2.7 180)
			(layer "B.Fab")
			(hide yes)
			(effects
				(font
					(size 0.7 0.7)
					(thickness 0.15)
				)
				(justify left bottom mirror)
			)
		)
		(pad "1" smd circle
			(at 0 0)
			(size 0.75 0.75)
			(layers "B.Cu" "B.Mask")
			(net 478 "/SoM/SLEEP{slash}~{WAKE}")
			(pinfunction "1")
			(pintype "passive")
		)
	)
	(footprint "antmicro-footprints:LED_0603_1608Metric_G"
		(layer "B.Cu")
		(at 79.1 105.45 90)
		(descr "LED SMD 0603 Green")
		(tags "LED SMD 0603 Green")
		(property "Reference" "D4"
			(at 1.2 -0.7 180)
			(layer "B.SilkS")
			(effects
				(font
					(size 0.7 0.7)
					(thickness 0.15)
				)
				(justify right bottom mirror)
			)
		)
		(property "Value" "LED_G_0603_LTST-C190GKT"
			(at -0.001 -1.599 90)
			(layer "B.Fab")
			(effects
				(font
					(size 0.7 0.7)
					(thickness 0.15)
				)
				(justify right bottom mirror)
			)
		)
		(property "Footprint" "antmicro-footprints:LED_0603_1608Metric_G"
			(at 0 0 90)
			(layer "F.Fab")
			(hide yes)
			(effects
				(font
					(size 1.27 1.27)
					(thickness 0.15)
				)
			)
		)
		(property "Datasheet" "https://media.digikey.com/pdf/Data%20Sheets/Lite-On%20PDFs/LTST-C190GKT.pdf"
			(at 0 0 90)
			(layer "F.Fab")
			(hide yes)
			(effects
				(font
					(size 1.27 1.27)
					(thickness 0.15)
				)
			)
		)
		(property "Author" "Antmicro"
			(at 184.55 26.35 0)
			(layer "B.Fab")
			(hide yes)
			(effects
				(font
					(size 1 1)
					(thickness 0.15)
				)
				(justify mirror)
			)
		)
		(property "Color" "Green"
			(at 184.55 26.35 0)
			(layer "B.Fab")
			(hide yes)
			(effects
				(font
					(size 1 1)
					(thickness 0.15)
				)
				(justify mirror)
			)
		)
		(property "License" "Apache-2.0"
			(at 184.55 26.35 0)
			(layer "B.Fab")
			(hide yes)
			(effects
				(font
					(size 1 1)
					(thickness 0.15)
				)
				(justify mirror)
			)
		)
		(property "MPN" "LTST-C190GKT"
			(at 184.55 26.35 0)
			(layer "B.Fab")
			(hide yes)
			(effects
				(font
					(size 1 1)
					(thickness 0.15)
				)
				(justify mirror)
			)
		)
		(property "Manufacturer" "Lite-On"
			(at 184.55 26.35 0)
			(layer "B.Fab")
			(hide yes)
			(effects
				(font
					(size 1 1)
					(thickness 0.15)
				)
				(justify mirror)
			)
		)
		(sheetname "USB Debug, DP")
		(sheetfile "usb.kicad_sch")
		(attr smd)
		(fp_line
			(start -0.22 -0.35)
			(end 0.22 -0.35)
			(stroke
				(width 0.15)
				(type solid)
			)
			(layer "B.SilkS")
		)
		(fp_line
			(start -1.18 -0.321)
			(end -1.18 0.319)
			(stroke
				(width 0.15)
				(type solid)
			)
			(layer "B.SilkS")
		)
		(fp_line
			(start -0.094672 -0.001008)
			(end 0.105328 -0.201008)
			(stroke
				(width 0.1)
				(type solid)
			)
			(layer "B.SilkS")
		)
		(fp_line
			(start -0.24 -0.001008)
			(end -0.094672 -0.001008)
			(stroke
				(width 0.1)
				(type solid)
			)
			(layer "B.SilkS")
		)
		(fp_line
			(start 0.24 -0.001)
			(end 0.105328 -0.001008)
			(stroke
				(width 0.1)
				(type solid)
			)
			(layer "B.SilkS")
		)
		(fp_line
			(start 0.105328 0.198992)
			(end 0.105328 -0.201008)
			(stroke
				(width 0.1)
				(type solid)
			)
			(layer "B.SilkS")
		)
		(fp_line
			(start 0.105328 0.198992)
			(end -0.094672 -0.001008)
			(stroke
				(width 0.1)
				(type solid)
			)
			(layer "B.SilkS")
		)
		(fp_line
			(start -0.094672 0.198992)
			(end -0.094672 -0.201008)
			(stroke
				(width 0.1)
				(type solid)
			)
			(layer "B.SilkS")
		)
		(fp_line
			(start -0.22 0.35)
			(end 0.22 0.35)
			(stroke
				(width 0.15)
				(type solid)
			)
			(layer "B.SilkS")
		)
		(fp_rect
			(start 1.25 -0.65)
			(end -1.25 0.65)
			(stroke
				(width 0.05)
				(type solid)
			)
			(fill none)
			(layer "B.CrtYd")
		)
		(fp_line
			(start 0.201 -0.2)
			(end -0.101 0)
			(stroke
				(width 0.15)
				(type solid)
			)
			(layer "B.Fab")
		)
		(fp_line
			(start -0.199 -0.1)
			(end -0.199 -0.2)
			(stroke
				(width 0.15)
				(type solid)
			)
			(layer "B.Fab")
		)
		(fp_line
			(start -0.199 -0.1)
			(end -0.199 0.202)
			(stroke
				(width 0.15)
				(type solid)
			)
			(layer "B.Fab")
		)
		(fp_line
			(start 0.201 0)
			(end 0.201 -0.2)
			(stroke
				(width 0.15)
				(type solid)
			)
			(layer "B.Fab")
		)
		(fp_line
			(start 0.201 0)
			(end 0.599 0)
			(stroke
				(width 0.15)
				(type solid)
			)
			(layer "B.Fab")
		)
		(fp_line
			(start -0.101 0)
			(end 0.201 0.202)
			(stroke
				(width 0.15)
				(type solid)
			)
			(layer "B.Fab")
		)
		(fp_line
			(start -0.597 0)
			(end -0.199 0)
			(stroke
				(width 0.15)
				(type solid)
			)
			(layer "B.Fab")
		)
		(fp_line
			(start 0.201 0.202)
			(end 0.201 0)
			(stroke
				(width 0.15)
				(type solid)
			)
			(layer "B.Fab")
		)
		(fp_rect
			(start 0.848 -0.4)
			(end -0.85 0.402)
			(stroke
				(width 0.15)
				(type solid)
			)
			(fill none)
			(layer "B.Fab")
		)
		(fp_text user "${REFERENCE}"
			(at -1.4224 -5.999 90)
			(layer "B.Fab")
			(hide yes)
			(effects
				(font
					(size 0.7 0.7)
					(thickness 0.15)
				)
				(justify right bottom mirror)
			)
		)
		(fp_text user "Author: Antmicro"
			(at -1.4224 -4.799 90)
			(layer "B.Fab")
			(hide yes)
			(effects
				(font
					(size 0.7 0.7)
					(thickness 0.15)
				)
				(justify right bottom mirror)
			)
		)
		(fp_text user "License: Apache-2.0"
			(at -1.4224 -3.599 90)
			(layer "B.Fab")
			(hide yes)
			(effects
				(font
					(size 0.7 0.7)
					(thickness 0.15)
				)
				(justify right bottom mirror)
			)
		)
		(pad "1" smd roundrect
			(at -0.7 0 270)
			(size 0.8 1)
			(layers "B.Cu" "B.Paste" "B.Mask")
			(roundrect_rratio 0.2)
			(net 1 "GND")
			(pinfunction "C")
			(pintype "passive")
		)
		(pad "2" smd roundrect
			(at 0.7 0 270)
			(size 0.8 1)
			(layers "B.Cu" "B.Paste" "B.Mask")
			(roundrect_rratio 0.2)
			(net 144 "Net-(D4-A)")
			(pinfunction "A")
			(pintype "passive")
		)
	)
	(footprint "antmicro-footprints:R_0402_1005Metric"
		(layer "B.Cu")
		(at 102.7 75.7 180)
		(descr "Resistor SMD 0402")
		(tags "resistor SMD 0402")
		(property "Reference" "R133"
			(at -3.7 -0.45 0)
			(layer "B.SilkS")
			(effects
				(font
					(size 0.7 0.7)
					(thickness 0.15)
				)
				(justify left bottom mirror)
			)
		)
		(property "Value" "R_200R_0402"
			(at 0 -1.4 0)
			(layer "B.Fab")
			(effects
				(font
					(size 0.7 0.7)
					(thickness 0.15)
				)
				(justify left bottom mirror)
			)
		)
		(property "Footprint" "antmicro-footprints:R_0402_1005Metric"
			(at 0 0 180)
			(layer "F.Fab")
			(hide yes)
			(effects
				(font
					(size 1.27 1.27)
					(thickness 0.15)
				)
			)
		)
		(property "Datasheet" "https://www.bourns.com/docs/product-datasheets/cr.pdf"
			(at 0 0 180)
			(layer "F.Fab")
			(hide yes)
			(effects
				(font
					(size 1.27 1.27)
					(thickness 0.15)
				)
			)
		)
		(property "Author" "Antmicro"
			(at 205.4 151.4 0)
			(layer "B.Fab")
			(hide yes)
			(effects
				(font
					(size 1 1)
					(thickness 0.15)
				)
				(justify mirror)
			)
		)
		(property "License" "Apache-2.0"
			(at 205.4 151.4 0)
			(layer "B.Fab")
			(hide yes)
			(effects
				(font
					(size 1 1)
					(thickness 0.15)
				)
				(justify mirror)
			)
		)
		(property "MPN" "CR0402-FX-2000GLF"
			(at 205.4 151.4 0)
			(layer "B.Fab")
			(hide yes)
			(effects
				(font
					(size 1 1)
					(thickness 0.15)
				)
				(justify mirror)
			)
		)
		(property "Manufacturer" "Bourns"
			(at 205.4 151.4 0)
			(layer "B.Fab")
			(hide yes)
			(effects
				(font
					(size 1 1)
					(thickness 0.15)
				)
				(justify mirror)
			)
		)
		(property "Tolerance" "1%"
			(at 205.4 151.4 0)
			(layer "B.Fab")
			(hide yes)
			(effects
				(font
					(size 1 1)
					(thickness 0.15)
				)
				(justify mirror)
			)
		)
		(property "Val" "200R"
			(at 205.4 151.4 0)
			(layer "B.Fab")
			(hide yes)
			(effects
				(font
					(size 1 1)
					(thickness 0.15)
				)
				(justify mirror)
			)
		)
		(sheetname "CSI")
		(sheetfile "csi.kicad_sch")
		(attr smd)
		(fp_rect
			(start -0.925 0.47)
			(end 0.925 -0.47)
			(stroke
				(width 0.05)
				(type default)
			)
			(fill none)
			(layer "B.CrtYd")
		)
		(fp_rect
			(start -0.5 0.25)
			(end 0.5 -0.25)
			(stroke
				(width 0.15)
				(type solid)
			)
			(fill none)
			(layer "B.Fab")
		)
		(fp_text user "Author: Antmicro"
			(at -0.95 -4.169 0)
			(layer "B.Fab")
			(hide yes)
			(effects
				(font
					(size 0.7 0.7)
					(thickness 0.15)
				)
				(justify left bottom mirror)
			)
		)
		(fp_text user "License: Apache-2.0"
			(at -0.95 -5.169 0)
			(layer "B.Fab")
			(hide yes)
			(effects
				(font
					(size 0.7 0.7)
					(thickness 0.15)
				)
				(justify left bottom mirror)
			)
		)
		(fp_text user "${REFERENCE}"
			(at -0.95 -3.168 0)
			(layer "B.Fab")
			(hide yes)
			(effects
				(font
					(size 0.7 0.7)
					(thickness 0.15)
				)
				(justify left bottom mirror)
			)
		)
		(pad "1" smd roundrect
			(at -0.48 0 180)
			(size 0.59 0.64)
			(layers "B.Cu" "B.Paste" "B.Mask")
			(roundrect_rratio 0.25)
			(net 161 "Net-(D24-A)")
			(pintype "passive")
		)
		(pad "2" smd roundrect
			(at 0.48 0 180)
			(size 0.59 0.64)
			(layers "B.Cu" "B.Paste" "B.Mask")
			(roundrect_rratio 0.25)
			(net 110 "/CSI/CSIB_3V3")
			(pintype "passive")
		)
	)
	(footprint "antmicro-footprints:SOT-23-5"
		(layer "B.Cu")
		(at 59.6 83.85 90)
		(property "Reference" "U42"
			(at 2.8 1.95 0)
			(layer "B.SilkS")
			(effects
				(font
					(size 0.7 0.7)
					(thickness 0.15)
				)
				(justify left top mirror)
			)
		)
		(property "Value" "TPS7A0518P_SOT23-5"
			(at 0.002 -2.799 90)
			(layer "B.Fab")
			(effects
				(font
					(size 0.7 0.7)
					(thickness 0.15)
				)
				(justify right bottom mirror)
			)
		)
		(property "Footprint" "antmicro-footprints:SOT-23-5"
			(at 0 0 90)
			(layer "F.Fab")
			(hide yes)
			(effects
				(font
					(size 1.27 1.27)
					(thickness 0.15)
				)
			)
		)
		(property "Datasheet" "https://www.ti.com/lit/ds/symlink/tps7a05.pdf?ts=1678973651768&ref_url=https%253A%252F%252Fwww.google.com%252F"
			(at 0 0 90)
			(layer "F.Fab")
			(hide yes)
			(effects
				(font
					(size 1.27 1.27)
					(thickness 0.15)
				)
			)
		)
		(property "Author" "Antmicro"
			(at 143.45 24.25 0)
			(layer "B.Fab")
			(hide yes)
			(effects
				(font
					(size 1 1)
					(thickness 0.15)
				)
				(justify mirror)
			)
		)
		(property "License" "Apache-2.0"
			(at 143.45 24.25 0)
			(layer "B.Fab")
			(hide yes)
			(effects
				(font
					(size 1 1)
					(thickness 0.15)
				)
				(justify mirror)
			)
		)
		(property "MPN" "TPS7A0518PDBVT"
			(at 143.45 24.25 0)
			(layer "B.Fab")
			(hide yes)
			(effects
				(font
					(size 1 1)
					(thickness 0.15)
				)
				(justify mirror)
			)
		)
		(property "Manufacturer" "Texas Instruments"
			(at 143.45 24.25 0)
			(layer "B.Fab")
			(hide yes)
			(effects
				(font
					(size 1 1)
					(thickness 0.15)
				)
				(justify mirror)
			)
		)
		(sheetname "Supply")
		(sheetfile "supply.kicad_sch")
		(attr smd)
		(fp_line
			(start -0.85 -1.6)
			(end -0.55 -1.6)
			(stroke
				(width 0.15)
				(type solid)
			)
			(layer "B.SilkS")
		)
		(fp_line
			(start 0.8 -1.599)
			(end 0.8 -1.3)
			(stroke
				(width 0.15)
				(type solid)
			)
			(layer "B.SilkS")
		)
		(fp_line
			(start 0.549 -1.599)
			(end 0.8 -1.599)
			(stroke
				(width 0.15)
				(type solid)
			)
			(layer "B.SilkS")
		)
		(fp_line
			(start -0.85 -1.301)
			(end -0.85 -1.6)
			(stroke
				(width 0.15)
				(type solid)
			)
			(layer "B.SilkS")
		)
		(fp_line
			(start 0.8 0.55)
			(end 0.8 -0.55)
			(stroke
				(width 0.15)
				(type solid)
			)
			(layer "B.SilkS")
		)
		(fp_line
			(start -0.8 1.3)
			(end -0.8 1.6)
			(stroke
				(width 0.15)
				(type solid)
			)
			(layer "B.SilkS")
		)
		(fp_line
			(start 0.8 1.6)
			(end 0.8 1.3)
			(stroke
				(width 0.15)
				(type solid)
			)
			(layer "B.SilkS")
		)
		(fp_line
			(start 0.5 1.6)
			(end 0.8 1.6)
			(stroke
				(width 0.15)
				(type solid)
			)
			(layer "B.SilkS")
		)
		(fp_line
			(start -0.5 1.6)
			(end -0.8 1.6)
			(stroke
				(width 0.15)
				(type solid)
			)
			(layer "B.SilkS")
		)
		(fp_circle
			(center -1.25 1.5)
			(end -1.2 1.5)
			(stroke
				(width 0.15)
				(type solid)
			)
			(fill solid)
			(layer "B.SilkS")
		)
		(fp_rect
			(start 1.9 1.76)
			(end -1.9 -1.75)
			(stroke
				(width 0.05)
				(type solid)
			)
			(fill none)
			(layer "B.CrtYd")
		)
		(fp_line
			(start -0.874 1.05)
			(end -0.398 1.526)
			(stroke
				(width 0.15)
				(type solid)
			)
			(layer "B.Fab")
		)
		(fp_rect
			(start 0.874 -1.523)
			(end -0.873 1.525)
			(stroke
				(width 0.15)
				(type solid)
			)
			(fill none)
			(layer "B.Fab")
		)
		(fp_text user "${REFERENCE}"
			(at -1.898 -4.299 90)
			(layer "B.Fab")
			(hide yes)
			(effects
				(font
					(size 0.7 0.7)
					(thickness 0.15)
				)
				(justify right bottom mirror)
			)
		)
		(fp_text user "License: Apache-2.0"
			(at -1.898 -6.7 90)
			(layer "B.Fab")
			(hide yes)
			(effects
				(font
					(size 0.7 0.7)
					(thickness 0.15)
				)
				(justify right bottom mirror)
			)
		)
		(fp_text user "Author: Antmicro"
			(at -1.898 -5.499 90)
			(layer "B.Fab")
			(hide yes)
			(effects
				(font
					(size 0.7 0.7)
					(thickness 0.15)
				)
				(justify right bottom mirror)
			)
		)
		(pad "1" smd rect
			(at -1.351 0.951 180)
			(size 0.55 1)
			(layers "B.Cu" "B.Paste" "B.Mask")
			(net 99 "+5V")
			(pinfunction "VIN")
			(pintype "power_in")
		)
		(pad "2" smd rect
			(at -1.351 0 180)
			(size 0.55 1)
			(layers "B.Cu" "B.Paste" "B.Mask")
			(net 1 "GND")
			(pinfunction "GND")
			(pintype "power_in")
		)
		(pad "3" smd rect
			(at -1.351 -0.949 180)
			(size 0.55 1)
			(layers "B.Cu" "B.Paste" "B.Mask")
			(net 690 "Net-(U42-EN)")
			(pinfunction "EN")
			(pintype "input")
		)
		(pad "4" smd rect
			(at 1.35 -0.949 180)
			(size 0.55 1)
			(layers "B.Cu" "B.Paste" "B.Mask")
			(net 729 "unconnected-(U42-NC-Pad4)")
			(pinfunction "NC")
			(pintype "no_connect")
		)
		(pad "5" smd rect
			(at 1.35 0.951 180)
			(size 0.55 1)
			(layers "B.Cu" "B.Paste" "B.Mask")
			(net 139 "/Supply/1V8_LDO")
			(pinfunction "VOUT")
			(pintype "power_out")
		)
	)
	(footprint "antmicro-footprints:C_0402_1005Metric"
		(layer "B.Cu")
		(at 47.55 121.64 180)
		(descr "Capacitor SMD 0402")
		(tags "capacitor SMD 0402")
		(property "Reference" "C34"
			(at 6.88 1.04 0)
			(layer "B.SilkS")
			(effects
				(font
					(size 0.7 0.7)
					(thickness 0.15)
				)
				(justify left bottom mirror)
			)
		)
		(property "Value" "C_10u_0402"
			(at -1.022927 -2.155213 0)
			(layer "B.Fab")
			(effects
				(font
					(size 0.7 0.7)
					(thickness 0.15)
				)
				(justify left bottom mirror)
			)
		)
		(property "Footprint" "antmicro-footprints:C_0402_1005Metric"
			(at 0 0 180)
			(layer "F.Fab")
			(hide yes)
			(effects
				(font
					(size 1.27 1.27)
					(thickness 0.15)
				)
			)
		)
		(property "Datasheet" "https://www.yageo.com/en/Chart/Download/pdf/CC0402MRX5R5BB106"
			(at 0 0 180)
			(layer "F.Fab")
			(hide yes)
			(effects
				(font
					(size 1.27 1.27)
					(thickness 0.15)
				)
			)
		)
		(property "Author" "Antmicro"
			(at 95.1 243.28 0)
			(layer "B.Fab")
			(hide yes)
			(effects
				(font
					(size 1 1)
					(thickness 0.15)
				)
				(justify mirror)
			)
		)
		(property "Dielectric" ""
			(at 95.1 243.28 0)
			(layer "B.Fab")
			(hide yes)
			(effects
				(font
					(size 1 1)
					(thickness 0.15)
				)
				(justify mirror)
			)
		)
		(property "License" "Apache-2.0"
			(at 95.1 243.28 0)
			(layer "B.Fab")
			(hide yes)
			(effects
				(font
					(size 1 1)
					(thickness 0.15)
				)
				(justify mirror)
			)
		)
		(property "MPN" "CC0402MRX5R5BB106"
			(at 95.1 243.28 0)
			(layer "B.Fab")
			(hide yes)
			(effects
				(font
					(size 1 1)
					(thickness 0.15)
				)
				(justify mirror)
			)
		)
		(property "Manufacturer" "YAGEO"
			(at 95.1 243.28 0)
			(layer "B.Fab")
			(hide yes)
			(effects
				(font
					(size 1 1)
					(thickness 0.15)
				)
				(justify mirror)
			)
		)
		(property "Val" "10u"
			(at 95.1 243.28 0)
			(layer "B.Fab")
			(hide yes)
			(effects
				(font
					(size 1 1)
					(thickness 0.15)
				)
				(justify mirror)
			)
		)
		(property "Voltage" ""
			(at 95.1 243.28 0)
			(layer "B.Fab")
			(hide yes)
			(effects
				(font
					(size 1 1)
					(thickness 0.15)
				)
				(justify mirror)
			)
		)
		(sheetname "USB Debug, DP")
		(sheetfile "usb.kicad_sch")
		(attr smd)
		(fp_rect
			(start -0.925 0.47)
			(end 0.925 -0.47)
			(stroke
				(width 0.05)
				(type default)
			)
			(fill none)
			(layer "B.CrtYd")
		)
		(fp_line
			(start 0.504 0.25)
			(end -0.494 0.25)
			(stroke
				(width 0.15)
				(type solid)
			)
			(layer "B.Fab")
		)
		(fp_line
			(start 0.504 -0.248)
			(end 0.504 0.25)
			(stroke
				(width 0.15)
				(type solid)
			)
			(layer "B.Fab")
		)
		(fp_line
			(start -0.494 0.25)
			(end -0.494 -0.248)
			(stroke
				(width 0.15)
				(type solid)
			)
			(layer "B.Fab")
		)
		(fp_line
			(start -0.494 -0.248)
			(end 0.504 -0.248)
			(stroke
				(width 0.15)
				(type solid)
			)
			(layer "B.Fab")
		)
		(fp_text user "Author: Antmicro"
			(at -0.939 -3.399 0)
			(layer "B.Fab")
			(hide yes)
			(effects
				(font
					(size 0.7 0.7)
					(thickness 0.15)
				)
				(justify left bottom mirror)
			)
		)
		(fp_text user "${REFERENCE}"
			(at -0.939 -4.599 0)
			(layer "B.Fab")
			(hide yes)
			(effects
				(font
					(size 0.7 0.7)
					(thickness 0.15)
				)
				(justify left bottom mirror)
			)
		)
		(fp_text user "License: Apache-2.0"
			(at -0.939 -5.799 0)
			(layer "B.Fab")
			(hide yes)
			(effects
				(font
					(size 0.7 0.7)
					(thickness 0.15)
				)
				(justify left bottom mirror)
			)
		)
		(pad "1" smd roundrect
			(at -0.48 0 180)
			(size 0.59 0.64)
			(layers "B.Cu" "B.Paste" "B.Mask")
			(roundrect_rratio 0.25)
			(net 1 "GND")
			(pintype "passive")
		)
		(pad "2" smd roundrect
			(at 0.48 0 180)
			(size 0.59 0.64)
			(layers "B.Cu" "B.Paste" "B.Mask")
			(roundrect_rratio 0.25)
			(net 185 "/USB Debug, DP/FTDI_3V3")
			(pintype "passive")
		)
	)
	(footprint "antmicro-footprints:C_0402_1005Metric"
		(layer "B.Cu")
		(at 126.735 84.75)
		(descr "Capacitor SMD 0402")
		(tags "capacitor SMD 0402")
		(property "Reference" "C17"
			(at 3.015 0.45 180)
			(layer "B.SilkS")
			(effects
				(font
					(size 0.7 0.7)
					(thickness 0.15)
				)
				(justify left bottom mirror)
			)
		)
		(property "Value" "C_220n_0402"
			(at 0 -1.4 180)
			(layer "B.Fab")
			(effects
				(font
					(size 0.7 0.7)
					(thickness 0.15)
				)
				(justify left bottom mirror)
			)
		)
		(property "Footprint" "antmicro-footprints:C_0402_1005Metric"
			(at 0 0 0)
			(layer "F.Fab")
			(hide yes)
			(effects
				(font
					(size 1.27 1.27)
					(thickness 0.15)
				)
			)
		)
		(property "Datasheet" "https://www.yageo.com/en/Chart/Download/pdf/CC0402KRX5R6BB224"
			(at 0 0 0)
			(layer "F.Fab")
			(hide yes)
			(effects
				(font
					(size 1.27 1.27)
					(thickness 0.15)
				)
			)
		)
		(property "Author" "Antmicro"
			(at 0 0 0)
			(layer "B.Fab")
			(hide yes)
			(effects
				(font
					(size 1 1)
					(thickness 0.15)
				)
				(justify mirror)
			)
		)
		(property "Dielectric" ""
			(at 0 0 0)
			(layer "B.Fab")
			(hide yes)
			(effects
				(font
					(size 1 1)
					(thickness 0.15)
				)
				(justify mirror)
			)
		)
		(property "License" "Apache-2.0"
			(at 0 0 0)
			(layer "B.Fab")
			(hide yes)
			(effects
				(font
					(size 1 1)
					(thickness 0.15)
				)
				(justify mirror)
			)
		)
		(property "MPN" "CC0402KRX5R6BB224"
			(at 0 0 0)
			(layer "B.Fab")
			(hide yes)
			(effects
				(font
					(size 1 1)
					(thickness 0.15)
				)
				(justify mirror)
			)
		)
		(property "Manufacturer" "YAGEO"
			(at 0 0 0)
			(layer "B.Fab")
			(hide yes)
			(effects
				(font
					(size 1 1)
					(thickness 0.15)
				)
				(justify mirror)
			)
		)
		(property "Val" "220n"
			(at 0 0 0)
			(layer "B.Fab")
			(hide yes)
			(effects
				(font
					(size 1 1)
					(thickness 0.15)
				)
				(justify mirror)
			)
		)
		(property "Voltage" ""
			(at 0 0 0)
			(layer "B.Fab")
			(hide yes)
			(effects
				(font
					(size 1 1)
					(thickness 0.15)
				)
				(justify mirror)
			)
		)
		(sheetname "M.2")
		(sheetfile "m-2.kicad_sch")
		(attr smd)
		(fp_rect
			(start -0.925 0.47)
			(end 0.925 -0.47)
			(stroke
				(width 0.05)
				(type default)
			)
			(fill none)
			(layer "B.CrtYd")
		)
		(fp_line
			(start -0.494 -0.248)
			(end 0.504 -0.248)
			(stroke
				(width 0.15)
				(type solid)
			)
			(layer "B.Fab")
		)
		(fp_line
			(start -0.494 0.25)
			(end -0.494 -0.248)
			(stroke
				(width 0.15)
				(type solid)
			)
			(layer "B.Fab")
		)
		(fp_line
			(start 0.504 -0.248)
			(end 0.504 0.25)
			(stroke
				(width 0.15)
				(type solid)
			)
			(layer "B.Fab")
		)
		(fp_line
			(start 0.504 0.25)
			(end -0.494 0.25)
			(stroke
				(width 0.15)
				(type solid)
			)
			(layer "B.Fab")
		)
		(fp_text user "${REFERENCE}"
			(at -0.932 -3.168 180)
			(layer "B.Fab")
			(hide yes)
			(effects
				(font
					(size 0.7 0.7)
					(thickness 0.15)
				)
				(justify left bottom mirror)
			)
		)
		(fp_text user "License: Apache-2.0"
			(at -0.932 -5.17 180)
			(layer "B.Fab")
			(hide yes)
			(effects
				(font
					(size 0.7 0.7)
					(thickness 0.15)
				)
				(justify left bottom mirror)
			)
		)
		(fp_text user "Author: Antmicro"
			(at -0.932 -4.17 180)
			(layer "B.Fab")
			(hide yes)
			(effects
				(font
					(size 0.7 0.7)
					(thickness 0.15)
				)
				(justify left bottom mirror)
			)
		)
		(pad "1" smd roundrect
			(at -0.48 0)
			(size 0.59 0.64)
			(layers "B.Cu" "B.Paste" "B.Mask")
			(roundrect_rratio 0.25)
			(net 89 "/M.2/C_PCIE0_TX0_N")
			(pintype "passive")
		)
		(pad "2" smd roundrect
			(at 0.48 0)
			(size 0.59 0.64)
			(layers "B.Cu" "B.Paste" "B.Mask")
			(roundrect_rratio 0.25)
			(net 441 "PCIE0_TX0_N")
			(pintype "passive")
		)
	)
	(footprint "antmicro-footprints:SOD-923"
		(layer "B.Cu")
		(at 74.5 112.45)
		(property "Reference" "D7"
			(at 1.66 1.41 0)
			(unlocked yes)
			(layer "B.SilkS")
			(effects
				(font
					(size 0.7 0.7)
					(thickness 0.15)
				)
				(justify left bottom mirror)
			)
		)
		(property "Value" "DF2S30FS_SOD"
			(at 0 -1.3 180)
			(unlocked yes)
			(layer "B.Fab")
			(effects
				(font
					(size 0.7 0.7)
					(thickness 0.15)
				)
				(justify left bottom mirror)
			)
		)
		(property "Footprint" "antmicro-footprints:SOD-923"
			(at 0 0 0)
			(layer "F.Fab")
			(hide yes)
			(effects
				(font
					(size 1.27 1.27)
					(thickness 0.15)
				)
			)
		)
		(property "Datasheet" "https://toshiba.semicon-storage.com/info/DF2S30FS_datasheet_en_20211216.pdf?did=11156&prodName=DF2S30FS"
			(at 0 0 0)
			(layer "F.Fab")
			(hide yes)
			(effects
				(font
					(size 1.27 1.27)
					(thickness 0.15)
				)
			)
		)
		(property "Author" "Antmicro"
			(at 0 0 0)
			(layer "B.Fab")
			(hide yes)
			(effects
				(font
					(size 1 1)
					(thickness 0.15)
				)
				(justify mirror)
			)
		)
		(property "License" "Apache-2.0"
			(at 0 0 0)
			(layer "B.Fab")
			(hide yes)
			(effects
				(font
					(size 1 1)
					(thickness 0.15)
				)
				(justify mirror)
			)
		)
		(property "MPN" "DF2S30FS"
			(at 0 0 0)
			(layer "B.Fab")
			(hide yes)
			(effects
				(font
					(size 1 1)
					(thickness 0.15)
				)
				(justify mirror)
			)
		)
		(property "Manufacturer" "Toshiba"
			(at 0 0 0)
			(layer "B.Fab")
			(hide yes)
			(effects
				(font
					(size 1 1)
					(thickness 0.15)
				)
				(justify mirror)
			)
		)
		(sheetname "USB Debug, DP")
		(sheetfile "usb.kicad_sch")
		(attr smd)
		(fp_line
			(start -0.5 -0.3)
			(end -0.5 -0.4)
			(stroke
				(width 0.15)
				(type solid)
			)
			(layer "B.SilkS")
		)
		(fp_line
			(start -0.5 0.4)
			(end -0.5 0.3)
			(stroke
				(width 0.15)
				(type solid)
			)
			(layer "B.SilkS")
		)
		(fp_line
			(start -0.16 -0.4)
			(end -0.16 0.4)
			(stroke
				(width 0.15)
				(type solid)
			)
			(layer "B.SilkS")
		)
		(fp_line
			(start 0.5 -0.4)
			(end -0.5 -0.4)
			(stroke
				(width 0.15)
				(type solid)
			)
			(layer "B.SilkS")
		)
		(fp_line
			(start 0.5 -0.3)
			(end 0.5 -0.4)
			(stroke
				(width 0.15)
				(type solid)
			)
			(layer "B.SilkS")
		)
		(fp_line
			(start 0.5 0.3)
			(end 0.5 0.4)
			(stroke
				(width 0.15)
				(type solid)
			)
			(layer "B.SilkS")
		)
		(fp_line
			(start 0.5 0.4)
			(end -0.5 0.4)
			(stroke
				(width 0.15)
				(type solid)
			)
			(layer "B.SilkS")
		)
		(fp_rect
			(start -0.68 0.41)
			(end 0.68 -0.41)
			(stroke
				(width 0.05)
				(type solid)
			)
			(fill none)
			(layer "B.CrtYd")
		)
		(fp_line
			(start -0.202 -0.298)
			(end -0.202 0.3)
			(stroke
				(width 0.15)
				(type solid)
			)
			(layer "B.Fab")
		)
		(fp_rect
			(start -0.402 0.3)
			(end 0.4 -0.298)
			(stroke
				(width 0.15)
				(type solid)
			)
			(fill none)
			(layer "B.Fab")
		)
		(fp_text user "License: Apache-2.0"
			(at -0.68 -4.5 180)
			(layer "B.Fab")
			(hide yes)
			(effects
				(font
					(size 0.7 0.7)
					(thickness 0.15)
				)
				(justify left bottom mirror)
			)
		)
		(fp_text user "${REFERENCE}"
			(at -0.68 -3.3 180)
			(unlocked yes)
			(layer "B.Fab")
			(hide yes)
			(effects
				(font
					(size 0.7 0.7)
					(thickness 0.15)
				)
				(justify left bottom mirror)
			)
		)
		(fp_text user "Author: Antmicro"
			(at -0.68 -5.7 180)
			(layer "B.Fab")
			(hide yes)
			(effects
				(font
					(size 0.7 0.7)
					(thickness 0.15)
				)
				(justify left bottom mirror)
			)
		)
		(pad "1" smd roundrect
			(at -0.438 0)
			(size 0.4 0.325)
			(layers "B.Cu" "B.Paste" "B.Mask")
			(roundrect_rratio 0.25)
			(net 261 "/USB Debug, DP/USBC0_VBUS")
			(pinfunction "C")
			(pintype "passive")
		)
		(pad "2" smd roundrect
			(at 0.436 0)
			(size 0.4 0.325)
			(layers "B.Cu" "B.Paste" "B.Mask")
			(roundrect_rratio 0.25)
			(net 1 "GND")
			(pinfunction "A")
			(pintype "passive")
		)
	)
	(footprint "antmicro-footprints:R_0402_1005Metric"
		(layer "B.Cu")
		(at 88 112.6 90)
		(descr "Resistor SMD 0402")
		(tags "resistor SMD 0402")
		(property "Reference" "R216"
			(at 0.965 -3.55 -90)
			(layer "B.SilkS")
			(effects
				(font
					(size 0.7 0.7)
					(thickness 0.15)
				)
				(justify left bottom mirror)
			)
		)
		(property "Value" "R_0R_0402"
			(at 0 -1.4 -90)
			(layer "B.Fab")
			(effects
				(font
					(size 0.7 0.7)
					(thickness 0.15)
				)
				(justify left bottom mirror)
			)
		)
		(property "Footprint" "antmicro-footprints:R_0402_1005Metric"
			(at 0 0 90)
			(layer "F.Fab")
			(hide yes)
			(effects
				(font
					(size 1.27 1.27)
					(thickness 0.15)
				)
			)
		)
		(property "Datasheet" "https://industrial.panasonic.com/cdbs/www-data/pdf/RDA0000/AOA0000C301.pdf"
			(at 0 0 90)
			(layer "F.Fab")
			(hide yes)
			(effects
				(font
					(size 1.27 1.27)
					(thickness 0.15)
				)
			)
		)
		(property "Author" "Antmicro"
			(at 200.6 24.6 0)
			(layer "B.Fab")
			(hide yes)
			(effects
				(font
					(size 1 1)
					(thickness 0.15)
				)
				(justify mirror)
			)
		)
		(property "Current" "1A"
			(at 200.6 24.6 0)
			(layer "B.Fab")
			(hide yes)
			(effects
				(font
					(size 1 1)
					(thickness 0.15)
				)
				(justify mirror)
			)
		)
		(property "License" "Apache-2.0"
			(at 200.6 24.6 0)
			(layer "B.Fab")
			(hide yes)
			(effects
				(font
					(size 1 1)
					(thickness 0.15)
				)
				(justify mirror)
			)
		)
		(property "MPN" "ERJ2GE0R00X"
			(at 200.6 24.6 0)
			(layer "B.Fab")
			(hide yes)
			(effects
				(font
					(size 1 1)
					(thickness 0.15)
				)
				(justify mirror)
			)
		)
		(property "Manufacturer" "Panasonic"
			(at 200.6 24.6 0)
			(layer "B.Fab")
			(hide yes)
			(effects
				(font
					(size 1 1)
					(thickness 0.15)
				)
				(justify mirror)
			)
		)
		(property "Tolerance" ""
			(at 200.6 24.6 0)
			(layer "B.Fab")
			(hide yes)
			(effects
				(font
					(size 1 1)
					(thickness 0.15)
				)
				(justify mirror)
			)
		)
		(property "Val" "0R"
			(at 200.6 24.6 0)
			(layer "B.Fab")
			(hide yes)
			(effects
				(font
					(size 1 1)
					(thickness 0.15)
				)
				(justify mirror)
			)
		)
		(sheetname "Peripherals")
		(sheetfile "peripherals.kicad_sch")
		(attr smd)
		(fp_rect
			(start -0.925 0.47)
			(end 0.925 -0.47)
			(stroke
				(width 0.05)
				(type default)
			)
			(fill none)
			(layer "B.CrtYd")
		)
		(fp_rect
			(start -0.5 0.25)
			(end 0.5 -0.25)
			(stroke
				(width 0.15)
				(type solid)
			)
			(fill none)
			(layer "B.Fab")
		)
		(fp_text user "Author: Antmicro"
			(at -0.95 -4.169 -90)
			(layer "B.Fab")
			(hide yes)
			(effects
				(font
					(size 0.7 0.7)
					(thickness 0.15)
				)
				(justify left bottom mirror)
			)
		)
		(fp_text user "License: Apache-2.0"
			(at -0.95 -5.169 -90)
			(layer "B.Fab")
			(hide yes)
			(effects
				(font
					(size 0.7 0.7)
					(thickness 0.15)
				)
				(justify left bottom mirror)
			)
		)
		(fp_text user "${REFERENCE}"
			(at -0.95 -3.168 -90)
			(layer "B.Fab")
			(hide yes)
			(effects
				(font
					(size 0.7 0.7)
					(thickness 0.15)
				)
				(justify left bottom mirror)
			)
		)
		(pad "1" smd roundrect
			(at -0.48 0 90)
			(size 0.59 0.64)
			(layers "B.Cu" "B.Paste" "B.Mask")
			(roundrect_rratio 0.25)
			(net 252 "SYS_SCL")
			(pintype "passive")
		)
		(pad "2" smd roundrect
			(at 0.48 0 90)
			(size 0.59 0.64)
			(layers "B.Cu" "B.Paste" "B.Mask")
			(roundrect_rratio 0.25)
			(net 350 "/Peripherals/GPIOEX_I2C_SCL")
			(pintype "passive")
		)
	)
	(footprint "antmicro-footprints:TSOT23-6"
		(layer "B.Cu")
		(at 93.8 81.78 -90)
		(property "Reference" "U28"
			(at -2.1 -1.05 180)
			(layer "B.SilkS")
			(effects
				(font
					(size 0.7 0.7)
					(thickness 0.15)
				)
				(justify left bottom mirror)
			)
		)
		(property "Value" "AP22615A_TSOT26"
			(at 0 -2.6 90)
			(layer "B.Fab")
			(effects
				(font
					(size 0.7 0.7)
					(thickness 0.15)
				)
				(justify left bottom mirror)
			)
		)
		(property "Footprint" "antmicro-footprints:TSOT23-6"
			(at 0 0 -90)
			(layer "F.Fab")
			(hide yes)
			(effects
				(font
					(size 1.27 1.27)
					(thickness 0.15)
				)
			)
		)
		(property "Datasheet" "https://www.mouser.com/datasheet/2/115/DIOD_S_A0008958405_1-2543193.pdf"
			(at 0 0 -90)
			(layer "F.Fab")
			(hide yes)
			(effects
				(font
					(size 1.27 1.27)
					(thickness 0.15)
				)
			)
		)
		(property "Author" "Antmicro"
			(at 12.02 175.58 0)
			(layer "B.Fab")
			(hide yes)
			(effects
				(font
					(size 1 1)
					(thickness 0.15)
				)
				(justify mirror)
			)
		)
		(property "License" "Apache-2.0"
			(at 12.02 175.58 0)
			(layer "B.Fab")
			(hide yes)
			(effects
				(font
					(size 1 1)
					(thickness 0.15)
				)
				(justify mirror)
			)
		)
		(property "MPN" "AP22615AWU-7"
			(at 12.02 175.58 0)
			(layer "B.Fab")
			(hide yes)
			(effects
				(font
					(size 1 1)
					(thickness 0.15)
				)
				(justify mirror)
			)
		)
		(property "Manufacturer" "Diodes Incorporated"
			(at 12.02 175.58 0)
			(layer "B.Fab")
			(hide yes)
			(effects
				(font
					(size 1 1)
					(thickness 0.15)
				)
				(justify mirror)
			)
		)
		(sheetname "CSI")
		(sheetfile "csi.kicad_sch")
		(attr smd)
		(fp_line
			(start -1 1.5)
			(end 1 1.497)
			(stroke
				(width 0.15)
				(type solid)
			)
			(layer "B.SilkS")
		)
		(fp_line
			(start -1 1.375)
			(end -1 1.5)
			(stroke
				(width 0.15)
				(type solid)
			)
			(layer "B.SilkS")
		)
		(fp_line
			(start 1 1.375)
			(end 1 1.497)
			(stroke
				(width 0.15)
				(type solid)
			)
			(layer "B.SilkS")
		)
		(fp_line
			(start -1 -1.4)
			(end -1 -1.55)
			(stroke
				(width 0.15)
				(type solid)
			)
			(layer "B.SilkS")
		)
		(fp_line
			(start 1 -1.4)
			(end 1 -1.55)
			(stroke
				(width 0.15)
				(type solid)
			)
			(layer "B.SilkS")
		)
		(fp_line
			(start -1 -1.55)
			(end 1 -1.55)
			(stroke
				(width 0.15)
				(type solid)
			)
			(layer "B.SilkS")
		)
		(fp_circle
			(center -1.44 1.5)
			(end -1.39 1.5)
			(stroke
				(width 0.15)
				(type solid)
			)
			(fill solid)
			(layer "B.SilkS")
		)
		(fp_rect
			(start 1.93 1.7)
			(end -1.93 -1.7)
			(stroke
				(width 0.05)
				(type solid)
			)
			(fill none)
			(layer "B.CrtYd")
		)
		(fp_line
			(start -0.876 1.096)
			(end -0.45 1.521)
			(stroke
				(width 0.15)
				(type solid)
			)
			(layer "B.Fab")
		)
		(fp_rect
			(start 0.875 -1.528)
			(end -0.875 1.525)
			(stroke
				(width 0.15)
				(type solid)
			)
			(fill none)
			(layer "B.Fab")
		)
		(fp_text user "${REFERENCE}"
			(at -1.93 -3.8 90)
			(layer "B.Fab")
			(hide yes)
			(effects
				(font
					(size 0.7 0.7)
					(thickness 0.15)
				)
				(justify left bottom mirror)
			)
		)
		(fp_text user "Author: Antmicro"
			(at -1.93 -5 90)
			(layer "B.Fab")
			(hide yes)
			(effects
				(font
					(size 0.7 0.7)
					(thickness 0.15)
				)
				(justify left bottom mirror)
			)
		)
		(fp_text user "License: Apache-2.0"
			(at -1.93 -6.199 90)
			(layer "B.Fab")
			(hide yes)
			(effects
				(font
					(size 0.7 0.7)
					(thickness 0.15)
				)
				(justify left bottom mirror)
			)
		)
		(pad "1" smd rect
			(at -1.301 0.947)
			(size 0.7 1.2)
			(layers "B.Cu" "B.Paste" "B.Mask")
			(net 110 "/CSI/CSIB_3V3")
			(pinfunction "OUT")
			(pintype "power_out")
		)
		(pad "2" smd rect
			(at -1.301 -0.004)
			(size 0.7 1.2)
			(layers "B.Cu" "B.Paste" "B.Mask")
			(net 1 "GND")
			(pinfunction "GND")
			(pintype "power_in")
		)
		(pad "3" smd rect
			(at -1.301 -0.954)
			(size 0.7 1.2)
			(layers "B.Cu" "B.Paste" "B.Mask")
			(net 393 "CSIB_FLG")
			(pinfunction "FLG")
			(pintype "output")
		)
		(pad "4" smd rect
			(at 1.299 -0.954)
			(size 0.7 1.2)
			(layers "B.Cu" "B.Paste" "B.Mask")
			(net 338 "CSIB_PEN")
			(pinfunction "EN")
			(pintype "input")
		)
		(pad "5" smd rect
			(at 1.299 -0.004)
			(size 0.7 1.2)
			(layers "B.Cu" "B.Paste" "B.Mask")
			(net 344 "/CSI/CSIB_3V3_ISET")
			(pinfunction "ISET")
			(pintype "passive")
		)
		(pad "6" smd rect
			(at 1.299 0.947)
			(size 0.7 1.2)
			(layers "B.Cu" "B.Paste" "B.Mask")
			(net 87 "+3V3")
			(pinfunction "IN")
			(pintype "power_in")
		)
	)
	(footprint "antmicro-footprints:R_0402_1005Metric"
		(layer "B.Cu")
		(at 49.98 116.95 180)
		(descr "Resistor SMD 0402")
		(tags "resistor SMD 0402")
		(property "Reference" "R267"
			(at 13.36 -9.229999 0)
			(layer "B.SilkS")
			(effects
				(font
					(size 0.7 0.7)
					(thickness 0.15)
				)
				(justify left bottom mirror)
			)
		)
		(property "Value" "R_1k_0402"
			(at -1.011843 -1.772047 0)
			(layer "B.Fab")
			(effects
				(font
					(size 0.7 0.7)
					(thickness 0.15)
				)
				(justify left bottom mirror)
			)
		)
		(property "Footprint" "antmicro-footprints:R_0402_1005Metric"
			(at 0 0 180)
			(layer "F.Fab")
			(hide yes)
			(effects
				(font
					(size 1.27 1.27)
					(thickness 0.15)
				)
			)
		)
		(property "Datasheet" "https://www.bourns.com/docs/product-datasheets/cr.pdf"
			(at 0 0 180)
			(layer "F.Fab")
			(hide yes)
			(effects
				(font
					(size 1.27 1.27)
					(thickness 0.15)
				)
			)
		)
		(property "Author" "Antmicro"
			(at 99.96 233.9 0)
			(layer "B.Fab")
			(hide yes)
			(effects
				(font
					(size 1 1)
					(thickness 0.15)
				)
				(justify mirror)
			)
		)
		(property "License" "Apache-2.0"
			(at 99.96 233.9 0)
			(layer "B.Fab")
			(hide yes)
			(effects
				(font
					(size 1 1)
					(thickness 0.15)
				)
				(justify mirror)
			)
		)
		(property "MPN" "CR0402-FX-1001GLF"
			(at 99.96 233.9 0)
			(layer "B.Fab")
			(hide yes)
			(effects
				(font
					(size 1 1)
					(thickness 0.15)
				)
				(justify mirror)
			)
		)
		(property "Manufacturer" "Bourns"
			(at 99.96 233.9 0)
			(layer "B.Fab")
			(hide yes)
			(effects
				(font
					(size 1 1)
					(thickness 0.15)
				)
				(justify mirror)
			)
		)
		(property "Tolerance" "1%"
			(at 99.96 233.9 0)
			(layer "B.Fab")
			(hide yes)
			(effects
				(font
					(size 1 1)
					(thickness 0.15)
				)
				(justify mirror)
			)
		)
		(property "Val" "1k"
			(at 99.96 233.9 0)
			(layer "B.Fab")
			(hide yes)
			(effects
				(font
					(size 1 1)
					(thickness 0.15)
				)
				(justify mirror)
			)
		)
		(sheetname "USB Debug, DP")
		(sheetfile "usb.kicad_sch")
		(attr smd)
		(fp_rect
			(start -0.925 0.47)
			(end 0.925 -0.47)
			(stroke
				(width 0.05)
				(type default)
			)
			(fill none)
			(layer "B.CrtYd")
		)
		(fp_rect
			(start -0.5 0.25)
			(end 0.5 -0.25)
			(stroke
				(width 0.15)
				(type solid)
			)
			(fill none)
			(layer "B.Fab")
		)
		(fp_text user "License: Apache-2.0"
			(at -0.95 -5.169 0)
			(layer "B.Fab")
			(hide yes)
			(effects
				(font
					(size 0.7 0.7)
					(thickness 0.15)
				)
				(justify left bottom mirror)
			)
		)
		(fp_text user "${REFERENCE}"
			(at -0.95 -3.168 0)
			(layer "B.Fab")
			(hide yes)
			(effects
				(font
					(size 0.7 0.7)
					(thickness 0.15)
				)
				(justify left bottom mirror)
			)
		)
		(fp_text user "Author: Antmicro"
			(at -0.95 -4.169 0)
			(layer "B.Fab")
			(hide yes)
			(effects
				(font
					(size 0.7 0.7)
					(thickness 0.15)
				)
				(justify left bottom mirror)
			)
		)
		(pad "1" smd roundrect
			(at -0.48 0 180)
			(size 0.59 0.64)
			(layers "B.Cu" "B.Paste" "B.Mask")
			(roundrect_rratio 0.25)
			(net 780 "/USB Debug, DP/FTDI_CBUS0{slash}SDA")
			(pintype "passive")
		)
		(pad "2" smd roundrect
			(at 0.48 0 180)
			(size 0.59 0.64)
			(layers "B.Cu" "B.Paste" "B.Mask")
			(roundrect_rratio 0.25)
			(net 185 "/USB Debug, DP/FTDI_3V3")
			(pintype "passive")
		)
	)
	(footprint "antmicro-footprints:C_0402_1005Metric"
		(layer "B.Cu")
		(at 126.75 92.75)
		(descr "Capacitor SMD 0402")
		(tags "capacitor SMD 0402")
		(property "Reference" "C16"
			(at 1.1 -0.45 180)
			(layer "B.SilkS")
			(effects
				(font
					(size 0.7 0.7)
					(thickness 0.15)
				)
				(justify left bottom mirror)
			)
		)
		(property "Value" "C_220n_0402"
			(at 0 -1.4 180)
			(layer "B.Fab")
			(effects
				(font
					(size 0.7 0.7)
					(thickness 0.15)
				)
				(justify left bottom mirror)
			)
		)
		(property "Footprint" "antmicro-footprints:C_0402_1005Metric"
			(at 0 0 0)
			(layer "F.Fab")
			(hide yes)
			(effects
				(font
					(size 1.27 1.27)
					(thickness 0.15)
				)
			)
		)
		(property "Datasheet" "https://www.yageo.com/en/Chart/Download/pdf/CC0402KRX5R6BB224"
			(at 0 0 0)
			(layer "F.Fab")
			(hide yes)
			(effects
				(font
					(size 1.27 1.27)
					(thickness 0.15)
				)
			)
		)
		(property "Author" "Antmicro"
			(at 0 0 0)
			(layer "B.Fab")
			(hide yes)
			(effects
				(font
					(size 1 1)
					(thickness 0.15)
				)
				(justify mirror)
			)
		)
		(property "Dielectric" ""
			(at 0 0 0)
			(layer "B.Fab")
			(hide yes)
			(effects
				(font
					(size 1 1)
					(thickness 0.15)
				)
				(justify mirror)
			)
		)
		(property "License" "Apache-2.0"
			(at 0 0 0)
			(layer "B.Fab")
			(hide yes)
			(effects
				(font
					(size 1 1)
					(thickness 0.15)
				)
				(justify mirror)
			)
		)
		(property "MPN" "CC0402KRX5R6BB224"
			(at 0 0 0)
			(layer "B.Fab")
			(hide yes)
			(effects
				(font
					(size 1 1)
					(thickness 0.15)
				)
				(justify mirror)
			)
		)
		(property "Manufacturer" "YAGEO"
			(at 0 0 0)
			(layer "B.Fab")
			(hide yes)
			(effects
				(font
					(size 1 1)
					(thickness 0.15)
				)
				(justify mirror)
			)
		)
		(property "Val" "220n"
			(at 0 0 0)
			(layer "B.Fab")
			(hide yes)
			(effects
				(font
					(size 1 1)
					(thickness 0.15)
				)
				(justify mirror)
			)
		)
		(property "Voltage" ""
			(at 0 0 0)
			(layer "B.Fab")
			(hide yes)
			(effects
				(font
					(size 1 1)
					(thickness 0.15)
				)
				(justify mirror)
			)
		)
		(sheetname "M.2")
		(sheetfile "m-2.kicad_sch")
		(attr smd)
		(fp_rect
			(start -0.925 0.47)
			(end 0.925 -0.47)
			(stroke
				(width 0.05)
				(type default)
			)
			(fill none)
			(layer "B.CrtYd")
		)
		(fp_line
			(start -0.494 -0.248)
			(end 0.504 -0.248)
			(stroke
				(width 0.15)
				(type solid)
			)
			(layer "B.Fab")
		)
		(fp_line
			(start -0.494 0.25)
			(end -0.494 -0.248)
			(stroke
				(width 0.15)
				(type solid)
			)
			(layer "B.Fab")
		)
		(fp_line
			(start 0.504 -0.248)
			(end 0.504 0.25)
			(stroke
				(width 0.15)
				(type solid)
			)
			(layer "B.Fab")
		)
		(fp_line
			(start 0.504 0.25)
			(end -0.494 0.25)
			(stroke
				(width 0.15)
				(type solid)
			)
			(layer "B.Fab")
		)
		(fp_text user "${REFERENCE}"
			(at -0.932 -3.168 180)
			(layer "B.Fab")
			(hide yes)
			(effects
				(font
					(size 0.7 0.7)
					(thickness 0.15)
				)
				(justify left bottom mirror)
			)
		)
		(fp_text user "License: Apache-2.0"
			(at -0.932 -5.17 180)
			(layer "B.Fab")
			(hide yes)
			(effects
				(font
					(size 0.7 0.7)
					(thickness 0.15)
				)
				(justify left bottom mirror)
			)
		)
		(fp_text user "Author: Antmicro"
			(at -0.932 -4.17 180)
			(layer "B.Fab")
			(hide yes)
			(effects
				(font
					(size 0.7 0.7)
					(thickness 0.15)
				)
				(justify left bottom mirror)
			)
		)
		(pad "1" smd roundrect
			(at -0.48 0)
			(size 0.59 0.64)
			(layers "B.Cu" "B.Paste" "B.Mask")
			(roundrect_rratio 0.25)
			(net 94 "/M.2/C_PCIE0_TX3_P")
			(pintype "passive")
		)
		(pad "2" smd roundrect
			(at 0.48 0)
			(size 0.59 0.64)
			(layers "B.Cu" "B.Paste" "B.Mask")
			(roundrect_rratio 0.25)
			(net 448 "PCIE0_TX3_P")
			(pintype "passive")
		)
	)
	(footprint "antmicro-footprints:R_0402_1005Metric"
		(layer "B.Cu")
		(at 75 110.2 -90)
		(descr "Resistor SMD 0402")
		(tags "resistor SMD 0402")
		(property "Reference" "R97"
			(at 0.76 -2.4 90)
			(layer "B.SilkS")
			(effects
				(font
					(size 0.7 0.7)
					(thickness 0.15)
				)
				(justify left bottom mirror)
			)
		)
		(property "Value" "R_1k_0402"
			(at 0 -1.4 90)
			(layer "B.Fab")
			(effects
				(font
					(size 0.7 0.7)
					(thickness 0.15)
				)
				(justify left bottom mirror)
			)
		)
		(property "Footprint" "antmicro-footprints:R_0402_1005Metric"
			(at 0 0 -90)
			(layer "F.Fab")
			(hide yes)
			(effects
				(font
					(size 1.27 1.27)
					(thickness 0.15)
				)
			)
		)
		(property "Datasheet" "https://www.bourns.com/docs/product-datasheets/cr.pdf"
			(at 0 0 -90)
			(layer "F.Fab")
			(hide yes)
			(effects
				(font
					(size 1.27 1.27)
					(thickness 0.15)
				)
			)
		)
		(property "Author" "Antmicro"
			(at -35.2 185.2 0)
			(layer "B.Fab")
			(hide yes)
			(effects
				(font
					(size 1 1)
					(thickness 0.15)
				)
				(justify mirror)
			)
		)
		(property "License" "Apache-2.0"
			(at -35.2 185.2 0)
			(layer "B.Fab")
			(hide yes)
			(effects
				(font
					(size 1 1)
					(thickness 0.15)
				)
				(justify mirror)
			)
		)
		(property "MPN" "CR0402-FX-1001GLF"
			(at -35.2 185.2 0)
			(layer "B.Fab")
			(hide yes)
			(effects
				(font
					(size 1 1)
					(thickness 0.15)
				)
				(justify mirror)
			)
		)
		(property "Manufacturer" "Bourns"
			(at -35.2 185.2 0)
			(layer "B.Fab")
			(hide yes)
			(effects
				(font
					(size 1 1)
					(thickness 0.15)
				)
				(justify mirror)
			)
		)
		(property "Tolerance" "1%"
			(at -35.2 185.2 0)
			(layer "B.Fab")
			(hide yes)
			(effects
				(font
					(size 1 1)
					(thickness 0.15)
				)
				(justify mirror)
			)
		)
		(property "Val" "1k"
			(at -35.2 185.2 0)
			(layer "B.Fab")
			(hide yes)
			(effects
				(font
					(size 1 1)
					(thickness 0.15)
				)
				(justify mirror)
			)
		)
		(sheetname "USB Debug, DP")
		(sheetfile "usb.kicad_sch")
		(attr smd exclude_from_pos_files exclude_from_bom dnp)
		(fp_rect
			(start -0.925 0.47)
			(end 0.925 -0.47)
			(stroke
				(width 0.05)
				(type default)
			)
			(fill none)
			(layer "B.CrtYd")
		)
		(fp_rect
			(start -0.5 0.25)
			(end 0.5 -0.25)
			(stroke
				(width 0.15)
				(type solid)
			)
			(fill none)
			(layer "B.Fab")
		)
		(fp_text user "Author: Antmicro"
			(at -0.95 -4.169 90)
			(layer "B.Fab")
			(hide yes)
			(effects
				(font
					(size 0.7 0.7)
					(thickness 0.15)
				)
				(justify left bottom mirror)
			)
		)
		(fp_text user "${REFERENCE}"
			(at -0.95 -3.168 90)
			(layer "B.Fab")
			(hide yes)
			(effects
				(font
					(size 0.7 0.7)
					(thickness 0.15)
				)
				(justify left bottom mirror)
			)
		)
		(fp_text user "License: Apache-2.0"
			(at -0.95 -5.169 90)
			(layer "B.Fab")
			(hide yes)
			(effects
				(font
					(size 0.7 0.7)
					(thickness 0.15)
				)
				(justify left bottom mirror)
			)
		)
		(pad "1" smd roundrect
			(at -0.48 0 270)
			(size 0.59 0.64)
			(layers "B.Cu" "B.Paste" "B.Mask")
			(roundrect_rratio 0.25)
			(net 310 "/USB Debug, DP/USBC0_EQ1")
			(pintype "passive")
		)
		(pad "2" smd roundrect
			(at 0.48 0 270)
			(size 0.59 0.64)
			(layers "B.Cu" "B.Paste" "B.Mask")
			(roundrect_rratio 0.25)
			(net 87 "+3V3")
			(pintype "passive")
		)
	)
	(footprint "antmicro-footprints:R_0402_1005Metric"
		(layer "B.Cu")
		(at 62.17 98.16 -90)
		(descr "Resistor SMD 0402")
		(tags "resistor SMD 0402")
		(property "Reference" "R244"
			(at 0.89 -0.3 90)
			(layer "B.SilkS")
			(effects
				(font
					(size 0.7 0.7)
					(thickness 0.15)
				)
				(justify left bottom mirror)
			)
		)
		(property "Value" "R_0R_0402"
			(at 0 -1.4 90)
			(layer "B.Fab")
			(effects
				(font
					(size 0.7 0.7)
					(thickness 0.15)
				)
				(justify left bottom mirror)
			)
		)
		(property "Footprint" "antmicro-footprints:R_0402_1005Metric"
			(at 0 0 -90)
			(layer "F.Fab")
			(hide yes)
			(effects
				(font
					(size 1.27 1.27)
					(thickness 0.15)
				)
			)
		)
		(property "Datasheet" "https://industrial.panasonic.com/cdbs/www-data/pdf/RDA0000/AOA0000C301.pdf"
			(at 0 0 -90)
			(layer "F.Fab")
			(hide yes)
			(effects
				(font
					(size 1.27 1.27)
					(thickness 0.15)
				)
			)
		)
		(property "Author" "Antmicro"
			(at -35.99 160.33 0)
			(layer "B.Fab")
			(hide yes)
			(effects
				(font
					(size 1 1)
					(thickness 0.15)
				)
				(justify mirror)
			)
		)
		(property "Current" "1A"
			(at -35.99 160.33 0)
			(layer "B.Fab")
			(hide yes)
			(effects
				(font
					(size 1 1)
					(thickness 0.15)
				)
				(justify mirror)
			)
		)
		(property "License" "Apache-2.0"
			(at -35.99 160.33 0)
			(layer "B.Fab")
			(hide yes)
			(effects
				(font
					(size 1 1)
					(thickness 0.15)
				)
				(justify mirror)
			)
		)
		(property "MPN" "ERJ2GE0R00X"
			(at -35.99 160.33 0)
			(layer "B.Fab")
			(hide yes)
			(effects
				(font
					(size 1 1)
					(thickness 0.15)
				)
				(justify mirror)
			)
		)
		(property "Manufacturer" "Panasonic"
			(at -35.99 160.33 0)
			(layer "B.Fab")
			(hide yes)
			(effects
				(font
					(size 1 1)
					(thickness 0.15)
				)
				(justify mirror)
			)
		)
		(property "Tolerance" ""
			(at -35.99 160.33 0)
			(layer "B.Fab")
			(hide yes)
			(effects
				(font
					(size 1 1)
					(thickness 0.15)
				)
				(justify mirror)
			)
		)
		(property "Val" "0R"
			(at -35.99 160.33 0)
			(layer "B.Fab")
			(hide yes)
			(effects
				(font
					(size 1 1)
					(thickness 0.15)
				)
				(justify mirror)
			)
		)
		(sheetname "USB Debug, DP")
		(sheetfile "usb.kicad_sch")
		(attr smd exclude_from_pos_files exclude_from_bom dnp)
		(fp_rect
			(start -0.925 0.47)
			(end 0.925 -0.47)
			(stroke
				(width 0.05)
				(type default)
			)
			(fill none)
			(layer "B.CrtYd")
		)
		(fp_rect
			(start -0.5 0.25)
			(end 0.5 -0.25)
			(stroke
				(width 0.15)
				(type solid)
			)
			(fill none)
			(layer "B.Fab")
		)
		(fp_text user "${REFERENCE}"
			(at -0.95 -3.168 90)
			(layer "B.Fab")
			(hide yes)
			(effects
				(font
					(size 0.7 0.7)
					(thickness 0.15)
				)
				(justify left bottom mirror)
			)
		)
		(fp_text user "Author: Antmicro"
			(at -0.95 -4.169 90)
			(layer "B.Fab")
			(hide yes)
			(effects
				(font
					(size 0.7 0.7)
					(thickness 0.15)
				)
				(justify left bottom mirror)
			)
		)
		(fp_text user "License: Apache-2.0"
			(at -0.95 -5.169 90)
			(layer "B.Fab")
			(hide yes)
			(effects
				(font
					(size 0.7 0.7)
					(thickness 0.15)
				)
				(justify left bottom mirror)
			)
		)
		(pad "1" smd roundrect
			(at -0.48 0 270)
			(size 0.59 0.64)
			(layers "B.Cu" "B.Paste" "B.Mask")
			(roundrect_rratio 0.25)
			(net 714 "GPIO010")
			(pintype "passive")
		)
		(pad "2" smd roundrect
			(at 0.48 0 270)
			(size 0.59 0.64)
			(layers "B.Cu" "B.Paste" "B.Mask")
			(roundrect_rratio 0.25)
			(net 713 "/USB Debug, DP/PDC_I2C1_IRQn")
			(pintype "passive")
		)
	)
	(footprint "antmicro-footprints:LED_0603_1608Metric_G"
		(layer "B.Cu")
		(at 108.4 70.3 180)
		(descr "LED SMD 0603 Green")
		(tags "LED SMD 0603 Green")
		(property "Reference" "D24"
			(at 1.1 -0.45 0)
			(layer "B.SilkS")
			(effects
				(font
					(size 0.7 0.7)
					(thickness 0.15)
				)
				(justify left bottom mirror)
			)
		)
		(property "Value" "LED_G_0603_LTST-C190GKT"
			(at -0.001 -1.599 0)
			(layer "B.Fab")
			(effects
				(font
					(size 0.7 0.7)
					(thickness 0.15)
				)
				(justify left bottom mirror)
			)
		)
		(property "Footprint" "antmicro-footprints:LED_0603_1608Metric_G"
			(at 0 0 180)
			(layer "F.Fab")
			(hide yes)
			(effects
				(font
					(size 1.27 1.27)
					(thickness 0.15)
				)
			)
		)
		(property "Datasheet" "https://media.digikey.com/pdf/Data%20Sheets/Lite-On%20PDFs/LTST-C190GKT.pdf"
			(at 0 0 180)
			(layer "F.Fab")
			(hide yes)
			(effects
				(font
					(size 1.27 1.27)
					(thickness 0.15)
				)
			)
		)
		(property "Author" "Antmicro"
			(at 216.8 140.6 0)
			(layer "B.Fab")
			(hide yes)
			(effects
				(font
					(size 1 1)
					(thickness 0.15)
				)
				(justify mirror)
			)
		)
		(property "Color" "Green"
			(at 216.8 140.6 0)
			(layer "B.Fab")
			(hide yes)
			(effects
				(font
					(size 1 1)
					(thickness 0.15)
				)
				(justify mirror)
			)
		)
		(property "License" "Apache-2.0"
			(at 216.8 140.6 0)
			(layer "B.Fab")
			(hide yes)
			(effects
				(font
					(size 1 1)
					(thickness 0.15)
				)
				(justify mirror)
			)
		)
		(property "MPN" "LTST-C190GKT"
			(at 216.8 140.6 0)
			(layer "B.Fab")
			(hide yes)
			(effects
				(font
					(size 1 1)
					(thickness 0.15)
				)
				(justify mirror)
			)
		)
		(property "Manufacturer" "Lite-On"
			(at 216.8 140.6 0)
			(layer "B.Fab")
			(hide yes)
			(effects
				(font
					(size 1 1)
					(thickness 0.15)
				)
				(justify mirror)
			)
		)
		(sheetname "CSI")
		(sheetfile "csi.kicad_sch")
		(attr smd)
		(fp_line
			(start 0.24 -0.001)
			(end 0.105328 -0.001008)
			(stroke
				(width 0.1)
				(type solid)
			)
			(layer "B.SilkS")
		)
		(fp_line
			(start 0.105328 0.198992)
			(end 0.105328 -0.201008)
			(stroke
				(width 0.1)
				(type solid)
			)
			(layer "B.SilkS")
		)
		(fp_line
			(start 0.105328 0.198992)
			(end -0.094672 -0.001008)
			(stroke
				(width 0.1)
				(type solid)
			)
			(layer "B.SilkS")
		)
		(fp_line
			(start -0.094672 0.198992)
			(end -0.094672 -0.201008)
			(stroke
				(width 0.1)
				(type solid)
			)
			(layer "B.SilkS")
		)
		(fp_line
			(start -0.094672 -0.001008)
			(end 0.105328 -0.201008)
			(stroke
				(width 0.1)
				(type solid)
			)
			(layer "B.SilkS")
		)
		(fp_line
			(start -0.22 0.35)
			(end 0.22 0.35)
			(stroke
				(width 0.15)
				(type solid)
			)
			(layer "B.SilkS")
		)
		(fp_line
			(start -0.22 -0.35)
			(end 0.22 -0.35)
			(stroke
				(width 0.15)
				(type solid)
			)
			(layer "B.SilkS")
		)
		(fp_line
			(start -0.24 -0.001008)
			(end -0.094672 -0.001008)
			(stroke
				(width 0.1)
				(type solid)
			)
			(layer "B.SilkS")
		)
		(fp_line
			(start -1.18 -0.321)
			(end -1.18 0.319)
			(stroke
				(width 0.15)
				(type solid)
			)
			(layer "B.SilkS")
		)
		(fp_rect
			(start 1.25 -0.65)
			(end -1.25 0.65)
			(stroke
				(width 0.05)
				(type solid)
			)
			(fill none)
			(layer "B.CrtYd")
		)
		(fp_line
			(start 0.201 0.202)
			(end 0.201 0)
			(stroke
				(width 0.15)
				(type solid)
			)
			(layer "B.Fab")
		)
		(fp_line
			(start 0.201 0)
			(end 0.599 0)
			(stroke
				(width 0.15)
				(type solid)
			)
			(layer "B.Fab")
		)
		(fp_line
			(start 0.201 0)
			(end 0.201 -0.2)
			(stroke
				(width 0.15)
				(type solid)
			)
			(layer "B.Fab")
		)
		(fp_line
			(start 0.201 -0.2)
			(end -0.101 0)
			(stroke
				(width 0.15)
				(type solid)
			)
			(layer "B.Fab")
		)
		(fp_line
			(start -0.101 0)
			(end 0.201 0.202)
			(stroke
				(width 0.15)
				(type solid)
			)
			(layer "B.Fab")
		)
		(fp_line
			(start -0.199 -0.1)
			(end -0.199 0.202)
			(stroke
				(width 0.15)
				(type solid)
			)
			(layer "B.Fab")
		)
		(fp_line
			(start -0.199 -0.1)
			(end -0.199 -0.2)
			(stroke
				(width 0.15)
				(type solid)
			)
			(layer "B.Fab")
		)
		(fp_line
			(start -0.597 0)
			(end -0.199 0)
			(stroke
				(width 0.15)
				(type solid)
			)
			(layer "B.Fab")
		)
		(fp_rect
			(start 0.848 -0.4)
			(end -0.85 0.402)
			(stroke
				(width 0.15)
				(type solid)
			)
			(fill none)
			(layer "B.Fab")
		)
		(fp_text user "License: Apache-2.0"
			(at -1.4224 -3.599 0)
			(layer "B.Fab")
			(hide yes)
			(effects
				(font
					(size 0.7 0.7)
					(thickness 0.15)
				)
				(justify left bottom mirror)
			)
		)
		(fp_text user "${REFERENCE}"
			(at -1.4224 -5.999 0)
			(layer "B.Fab")
			(hide yes)
			(effects
				(font
					(size 0.7 0.7)
					(thickness 0.15)
				)
				(justify left bottom mirror)
			)
		)
		(fp_text user "Author: Antmicro"
			(at -1.4224 -4.799 0)
			(layer "B.Fab")
			(hide yes)
			(effects
				(font
					(size 0.7 0.7)
					(thickness 0.15)
				)
				(justify left bottom mirror)
			)
		)
		(pad "1" smd roundrect
			(at -0.7 0)
			(size 0.8 1)
			(layers "B.Cu" "B.Paste" "B.Mask")
			(roundrect_rratio 0.2)
			(net 1 "GND")
			(pinfunction "C")
			(pintype "passive")
		)
		(pad "2" smd roundrect
			(at 0.7 0)
			(size 0.8 1)
			(layers "B.Cu" "B.Paste" "B.Mask")
			(roundrect_rratio 0.2)
			(net 161 "Net-(D24-A)")
			(pinfunction "A")
			(pintype "passive")
		)
	)
	(footprint "antmicro-footprints:XSON-8_1x1.95mm_P0.5mm"
		(layer "B.Cu")
		(at 68.1 85.8)
		(property "Reference" "U32"
			(at 1.12 2.26 180)
			(layer "B.SilkS")
			(effects
				(font
					(size 0.7 0.7)
					(thickness 0.15)
				)
				(justify left bottom mirror)
			)
		)
		(property "Value" "NTS0102_XSON"
			(at 0 -2.2 180)
			(layer "B.Fab")
			(effects
				(font
					(size 0.7 0.7)
					(thickness 0.15)
				)
				(justify left bottom mirror)
			)
		)
		(property "Footprint" "antmicro-footprints:XSON-8_1x1.95mm_P0.5mm"
			(at 0 0 0)
			(layer "F.Fab")
			(hide yes)
			(effects
				(font
					(size 1.27 1.27)
					(thickness 0.15)
				)
			)
		)
		(property "Datasheet" "http://www.farnell.com/datasheets/1760723.pdf"
			(at 0 0 0)
			(layer "F.Fab")
			(hide yes)
			(effects
				(font
					(size 1.27 1.27)
					(thickness 0.15)
				)
			)
		)
		(property "Author" "Antmicro"
			(at 0 0 0)
			(layer "B.Fab")
			(hide yes)
			(effects
				(font
					(size 1 1)
					(thickness 0.15)
				)
				(justify mirror)
			)
		)
		(property "License" "Apache-2.0"
			(at 0 0 0)
			(layer "B.Fab")
			(hide yes)
			(effects
				(font
					(size 1 1)
					(thickness 0.15)
				)
				(justify mirror)
			)
		)
		(property "MPN" "NTS0102GT"
			(at 0 0 0)
			(layer "B.Fab")
			(hide yes)
			(effects
				(font
					(size 1 1)
					(thickness 0.15)
				)
				(justify mirror)
			)
		)
		(property "Manufacturer" "NXP"
			(at 0 0 0)
			(layer "B.Fab")
			(hide yes)
			(effects
				(font
					(size 1 1)
					(thickness 0.15)
				)
				(justify mirror)
			)
		)
		(sheetname "CSI")
		(sheetfile "csi.kicad_sch")
		(attr smd)
		(fp_line
			(start -0.5 -1.1)
			(end 0.5 -1.1)
			(stroke
				(width 0.15)
				(type solid)
			)
			(layer "B.SilkS")
		)
		(fp_line
			(start 0.5 1.1)
			(end -0.5 1.1)
			(stroke
				(width 0.15)
				(type solid)
			)
			(layer "B.SilkS")
		)
		(fp_circle
			(center -0.75 1.1)
			(end -0.701 1.1)
			(stroke
				(width 0.15)
				(type solid)
			)
			(fill none)
			(layer "B.SilkS")
		)
		(fp_rect
			(start -0.8 1.2)
			(end 0.8 -1.2)
			(stroke
				(width 0.05)
				(type solid)
			)
			(fill none)
			(layer "B.CrtYd")
		)
		(fp_line
			(start -0.5305 -1)
			(end 0.5305 -1)
			(stroke
				(width 0.15)
				(type solid)
			)
			(layer "B.Fab")
		)
		(fp_line
			(start -0.5305 1.001)
			(end -0.5305 -1)
			(stroke
				(width 0.15)
				(type solid)
			)
			(layer "B.Fab")
		)
		(fp_line
			(start 0.5305 -1)
			(end 0.5305 1.001)
			(stroke
				(width 0.15)
				(type solid)
			)
			(layer "B.Fab")
		)
		(fp_line
			(start 0.5305 1.001)
			(end -0.5305 1.001)
			(stroke
				(width 0.15)
				(type solid)
			)
			(layer "B.Fab")
		)
		(fp_text user "License: Apache-2.0"
			(at -0.527 -8.306 180)
			(layer "B.Fab")
			(hide yes)
			(effects
				(font
					(size 0.7 0.7)
					(thickness 0.15)
				)
				(justify left bottom mirror)
			)
		)
		(fp_text user "${REFERENCE}"
			(at -0.527 -5.905 180)
			(layer "B.Fab")
			(hide yes)
			(effects
				(font
					(size 0.7 0.7)
					(thickness 0.15)
				)
				(justify left bottom mirror)
			)
		)
		(fp_text user "Author: Antmicro"
			(at -0.527 -7.105 180)
			(layer "B.Fab")
			(hide yes)
			(effects
				(font
					(size 0.7 0.7)
					(thickness 0.15)
				)
				(justify left bottom mirror)
			)
		)
		(pad "1" smd roundrect
			(at -0.45 0.75 180)
			(size 0.6 0.3)
			(layers "B.Cu" "B.Paste" "B.Mask")
			(roundrect_rratio 0.25)
			(net 402 "/CSI/VSYNC_CAM3_3V3")
			(pinfunction "B_{2}")
			(pintype "bidirectional")
		)
		(pad "2" smd roundrect
			(at -0.45 0.25 180)
			(size 0.6 0.25)
			(layers "B.Cu" "B.Paste" "B.Mask")
			(roundrect_rratio 0.25)
			(net 1 "GND")
			(pinfunction "GND")
			(pintype "power_in")
		)
		(pad "3" smd roundrect
			(at -0.45 -0.25 180)
			(size 0.6 0.25)
			(layers "B.Cu" "B.Paste" "B.Mask")
			(roundrect_rratio 0.25)
			(net 112 "+1V8")
			(pinfunction "VCC_{A}")
			(pintype "power_in")
		)
		(pad "4" smd roundrect
			(at -0.45 -0.75 180)
			(size 0.6 0.3)
			(layers "B.Cu" "B.Paste" "B.Mask")
			(roundrect_rratio 0.25)
			(net 243 "VSYNC_CAM3")
			(pinfunction "A_{2}")
			(pintype "bidirectional")
		)
		(pad "5" smd roundrect
			(at 0.45 -0.75 180)
			(size 0.6 0.3)
			(layers "B.Cu" "B.Paste" "B.Mask")
			(roundrect_rratio 0.25)
			(net 242 "VSYNC_CAM2")
			(pinfunction "A_{1}")
			(pintype "bidirectional")
		)
		(pad "6" smd roundrect
			(at 0.45 -0.25 180)
			(size 0.6 0.25)
			(layers "B.Cu" "B.Paste" "B.Mask")
			(roundrect_rratio 0.25)
			(net 112 "+1V8")
			(pinfunction "OE")
			(pintype "input")
		)
		(pad "7" smd roundrect
			(at 0.45 0.25 180)
			(size 0.6 0.25)
			(layers "B.Cu" "B.Paste" "B.Mask")
			(roundrect_rratio 0.25)
			(net 87 "+3V3")
			(pinfunction "VCC_{B}")
			(pintype "power_in")
		)
		(pad "8" smd roundrect
			(at 0.45 0.75 180)
			(size 0.6 0.3)
			(layers "B.Cu" "B.Paste" "B.Mask")
			(roundrect_rratio 0.25)
			(net 406 "/CSI/VSYNC_CAM2_3V3")
			(pinfunction "B_{1}")
			(pintype "bidirectional")
		)
	)
	(footprint "antmicro-footprints:R_0603_1608Metric"
		(layer "B.Cu")
		(at 62.8 82.7)
		(descr "Resistor SMD 0603")
		(tags "resistor SMD 0603")
		(property "Reference" "R276"
			(at 1.45 -0.6 180)
			(layer "B.SilkS")
			(effects
				(font
					(size 0.7 0.7)
					(thickness 0.15)
				)
				(justify left bottom mirror)
			)
		)
		(property "Value" "R_0R_0603"
			(at 0 -1.6 180)
			(layer "B.Fab")
			(effects
				(font
					(size 0.7 0.7)
					(thickness 0.15)
				)
				(justify left bottom mirror)
			)
		)
		(property "Footprint" "antmicro-footprints:R_0603_1608Metric"
			(at 0 0 0)
			(layer "F.Fab")
			(hide yes)
			(effects
				(font
					(size 1.27 1.27)
					(thickness 0.15)
				)
			)
		)
		(property "Datasheet" "https://www.bourns.com/docs/product-datasheets/cr.pdf?sfvrsn=574d41f6_14"
			(at 0 0 0)
			(layer "F.Fab")
			(hide yes)
			(effects
				(font
					(size 1.27 1.27)
					(thickness 0.15)
				)
			)
		)
		(property "Author" "Antmicro"
			(at 0 0 0)
			(layer "B.Fab")
			(hide yes)
			(effects
				(font
					(size 1 1)
					(thickness 0.15)
				)
				(justify mirror)
			)
		)
		(property "Current" "1A"
			(at 0 0 0)
			(layer "B.Fab")
			(hide yes)
			(effects
				(font
					(size 1 1)
					(thickness 0.15)
				)
				(justify mirror)
			)
		)
		(property "License" "Apache-2.0"
			(at 0 0 0)
			(layer "B.Fab")
			(hide yes)
			(effects
				(font
					(size 1 1)
					(thickness 0.15)
				)
				(justify mirror)
			)
		)
		(property "MPN" "CR0603-J/-000ELF"
			(at 0 0 0)
			(layer "B.Fab")
			(hide yes)
			(effects
				(font
					(size 1 1)
					(thickness 0.15)
				)
				(justify mirror)
			)
		)
		(property "Manufacturer" "Bourns"
			(at 0 0 0)
			(layer "B.Fab")
			(hide yes)
			(effects
				(font
					(size 1 1)
					(thickness 0.15)
				)
				(justify mirror)
			)
		)
		(property "Tolerance" ""
			(at 0 0 0)
			(layer "B.Fab")
			(hide yes)
			(effects
				(font
					(size 1 1)
					(thickness 0.15)
				)
				(justify mirror)
			)
		)
		(property "Val" "0R"
			(at 0 0 0)
			(layer "B.Fab")
			(hide yes)
			(effects
				(font
					(size 1 1)
					(thickness 0.15)
				)
				(justify mirror)
			)
		)
		(sheetname "Supply")
		(sheetfile "supply.kicad_sch")
		(attr smd)
		(fp_line
			(start 0.15 -0.4)
			(end -0.15 -0.4)
			(stroke
				(width 0.15)
				(type solid)
			)
			(layer "B.SilkS")
		)
		(fp_line
			(start 0.15 0.4)
			(end -0.15 0.4)
			(stroke
				(width 0.15)
				(type solid)
			)
			(layer "B.SilkS")
		)
		(fp_rect
			(start -1.25 0.65)
			(end 1.25 -0.65)
			(stroke
				(width 0.05)
				(type solid)
			)
			(fill none)
			(layer "B.CrtYd")
		)
		(fp_rect
			(start -0.8 0.4)
			(end 0.8 -0.4)
			(stroke
				(width 0.15)
				(type solid)
			)
			(fill none)
			(layer "B.Fab")
		)
		(fp_text user "Author: Antmicro"
			(at -1.25 -4.9 180)
			(layer "B.Fab")
			(hide yes)
			(effects
				(font
					(size 0.7 0.7)
					(thickness 0.15)
				)
				(justify left bottom mirror)
			)
		)
		(fp_text user "License: Apache-2.0"
			(at -1.25 -5.9 180)
			(layer "B.Fab")
			(hide yes)
			(effects
				(font
					(size 0.7 0.7)
					(thickness 0.15)
				)
				(justify left bottom mirror)
			)
		)
		(fp_text user "${REFERENCE}"
			(at -1.25 -3.898 180)
			(layer "B.Fab")
			(hide yes)
			(effects
				(font
					(size 0.7 0.7)
					(thickness 0.15)
				)
				(justify left bottom mirror)
			)
		)
		(pad "1" smd roundrect
			(at -0.7 0)
			(size 0.8 1)
			(layers "B.Cu" "B.Paste" "B.Mask")
			(roundrect_rratio 0.2)
			(net 139 "/Supply/1V8_LDO")
			(pintype "passive")
		)
		(pad "2" smd roundrect
			(at 0.7 0)
			(size 0.8 1)
			(layers "B.Cu" "B.Paste" "B.Mask")
			(roundrect_rratio 0.2)
			(net 112 "+1V8")
			(pintype "passive")
		)
	)
	(footprint "antmicro-footprints:XSON-8_1x1.95mm_P0.5mm"
		(layer "B.Cu")
		(at 49.78 111.3245 -90)
		(property "Reference" "U47"
			(at -1.2745 1.23 0)
			(layer "B.SilkS")
			(effects
				(font
					(size 0.7 0.7)
					(thickness 0.15)
				)
				(justify right bottom mirror)
			)
		)
		(property "Value" "NTS0102_XSON"
			(at 0 -2.2 90)
			(layer "B.Fab")
			(effects
				(font
					(size 0.7 0.7)
					(thickness 0.15)
				)
				(justify left bottom mirror)
			)
		)
		(property "Footprint" "antmicro-footprints:XSON-8_1x1.95mm_P0.5mm"
			(at 0 0 -90)
			(layer "F.Fab")
			(hide yes)
			(effects
				(font
					(size 1.27 1.27)
					(thickness 0.15)
				)
			)
		)
		(property "Datasheet" "http://www.farnell.com/datasheets/1760723.pdf"
			(at 0 0 -90)
			(layer "F.Fab")
			(hide yes)
			(effects
				(font
					(size 1.27 1.27)
					(thickness 0.15)
				)
			)
		)
		(property "Author" "Antmicro"
			(at -61.5445 161.1045 0)
			(layer "B.Fab")
			(hide yes)
			(effects
				(font
					(size 1 1)
					(thickness 0.15)
				)
				(justify mirror)
			)
		)
		(property "License" "Apache-2.0"
			(at -61.5445 161.1045 0)
			(layer "B.Fab")
			(hide yes)
			(effects
				(font
					(size 1 1)
					(thickness 0.15)
				)
				(justify mirror)
			)
		)
		(property "MPN" "NTS0102GT"
			(at -61.5445 161.1045 0)
			(layer "B.Fab")
			(hide yes)
			(effects
				(font
					(size 1 1)
					(thickness 0.15)
				)
				(justify mirror)
			)
		)
		(property "Manufacturer" "NXP"
			(at -61.5445 161.1045 0)
			(layer "B.Fab")
			(hide yes)
			(effects
				(font
					(size 1 1)
					(thickness 0.15)
				)
				(justify mirror)
			)
		)
		(sheetname "USB Debug, DP")
		(sheetfile "usb.kicad_sch")
		(attr smd)
		(fp_line
			(start 0.5 1.1)
			(end -0.5 1.1)
			(stroke
				(width 0.15)
				(type solid)
			)
			(layer "B.SilkS")
		)
		(fp_line
			(start -0.5 -1.1)
			(end 0.5 -1.1)
			(stroke
				(width 0.15)
				(type solid)
			)
			(layer "B.SilkS")
		)
		(fp_circle
			(center -0.75 1.1)
			(end -0.701 1.1)
			(stroke
				(width 0.15)
				(type solid)
			)
			(fill none)
			(layer "B.SilkS")
		)
		(fp_rect
			(start -0.8 1.2)
			(end 0.8 -1.2)
			(stroke
				(width 0.05)
				(type solid)
			)
			(fill none)
			(layer "B.CrtYd")
		)
		(fp_line
			(start -0.5305 1.001)
			(end -0.5305 -1)
			(stroke
				(width 0.15)
				(type solid)
			)
			(layer "B.Fab")
		)
		(fp_line
			(start 0.5305 1.001)
			(end -0.5305 1.001)
			(stroke
				(width 0.15)
				(type solid)
			)
			(layer "B.Fab")
		)
		(fp_line
			(start -0.5305 -1)
			(end 0.5305 -1)
			(stroke
				(width 0.15)
				(type solid)
			)
			(layer "B.Fab")
		)
		(fp_line
			(start 0.5305 -1)
			(end 0.5305 1.001)
			(stroke
				(width 0.15)
				(type solid)
			)
			(layer "B.Fab")
		)
		(fp_text user "${REFERENCE}"
			(at -0.527 -5.905 90)
			(layer "B.Fab")
			(hide yes)
			(effects
				(font
					(size 0.7 0.7)
					(thickness 0.15)
				)
				(justify left bottom mirror)
			)
		)
		(fp_text user "Author: Antmicro"
			(at -0.527 -7.105 90)
			(layer "B.Fab")
			(hide yes)
			(effects
				(font
					(size 0.7 0.7)
					(thickness 0.15)
				)
				(justify left bottom mirror)
			)
		)
		(fp_text user "License: Apache-2.0"
			(at -0.527 -8.306 90)
			(layer "B.Fab")
			(hide yes)
			(effects
				(font
					(size 0.7 0.7)
					(thickness 0.15)
				)
				(justify left bottom mirror)
			)
		)
		(pad "1" smd roundrect
			(at -0.45 0.75 90)
			(size 0.6 0.3)
			(layers "B.Cu" "B.Paste" "B.Mask")
			(roundrect_rratio 0.25)
			(net 302 "/USB Debug, DP/PDC_I2C1_SCL")
			(pinfunction "B_{2}")
			(pintype "bidirectional")
		)
		(pad "2" smd roundrect
			(at -0.45 0.25 90)
			(size 0.6 0.25)
			(layers "B.Cu" "B.Paste" "B.Mask")
			(roundrect_rratio 0.25)
			(net 1 "GND")
			(pinfunction "GND")
			(pintype "power_in")
		)
		(pad "3" smd roundrect
			(at -0.45 -0.25 90)
			(size 0.6 0.25)
			(layers "B.Cu" "B.Paste" "B.Mask")
			(roundrect_rratio 0.25)
			(net 185 "/USB Debug, DP/FTDI_3V3")
			(pinfunction "VCC_{A}")
			(pintype "power_in")
		)
		(pad "4" smd roundrect
			(at -0.45 -0.75 90)
			(size 0.6 0.3)
			(layers "B.Cu" "B.Paste" "B.Mask")
			(roundrect_rratio 0.25)
			(net 398 "/USB Debug, DP/FTDI_CBUS3{slash}SCL")
			(pinfunction "A_{2}")
			(pintype "bidirectional")
		)
		(pad "5" smd roundrect
			(at 0.45 -0.75 90)
			(size 0.6 0.3)
			(layers "B.Cu" "B.Paste" "B.Mask")
			(roundrect_rratio 0.25)
			(net 780 "/USB Debug, DP/FTDI_CBUS0{slash}SDA")
			(pinfunction "A_{1}")
			(pintype "bidirectional")
		)
		(pad "6" smd roundrect
			(at 0.45 -0.25 90)
			(size 0.6 0.25)
			(layers "B.Cu" "B.Paste" "B.Mask")
			(roundrect_rratio 0.25)
			(net 397 "/USB Debug, DP/FTDI_CBUS_EN")
			(pinfunction "OE")
			(pintype "input")
		)
		(pad "7" smd roundrect
			(at 0.45 0.25 90)
			(size 0.6 0.25)
			(layers "B.Cu" "B.Paste" "B.Mask")
			(roundrect_rratio 0.25)
			(net 185 "/USB Debug, DP/FTDI_3V3")
			(pinfunction "VCC_{B}")
			(pintype "power_in")
		)
		(pad "8" smd roundrect
			(at 0.45 0.75 90)
			(size 0.6 0.3)
			(layers "B.Cu" "B.Paste" "B.Mask")
			(roundrect_rratio 0.25)
			(net 303 "/USB Debug, DP/PDC_I2C1_SDA")
			(pinfunction "B_{1}")
			(pintype "bidirectional")
		)
	)
	(footprint "antmicro-footprints:R_0402_1005Metric"
		(layer "B.Cu")
		(at 92.9 98.5 -90)
		(descr "Resistor SMD 0402")
		(tags "resistor SMD 0402")
		(property "Reference" "R211"
			(at -1.57 0.35 90)
			(layer "B.SilkS")
			(effects
				(font
					(size 0.7 0.7)
					(thickness 0.15)
				)
				(justify left bottom mirror)
			)
		)
		(property "Value" "R_10k_0402"
			(at 0 -1.4 90)
			(layer "B.Fab")
			(effects
				(font
					(size 0.7 0.7)
					(thickness 0.15)
				)
				(justify left bottom mirror)
			)
		)
		(property "Footprint" "antmicro-footprints:R_0402_1005Metric"
			(at 0 0 -90)
			(layer "F.Fab")
			(hide yes)
			(effects
				(font
					(size 1.27 1.27)
					(thickness 0.15)
				)
			)
		)
		(property "Datasheet" "https://www.bourns.com/docs/product-datasheets/cr.pdf"
			(at 0 0 -90)
			(layer "F.Fab")
			(hide yes)
			(effects
				(font
					(size 1.27 1.27)
					(thickness 0.15)
				)
			)
		)
		(property "Author" "Antmicro"
			(at -5.6 191.4 0)
			(layer "B.Fab")
			(hide yes)
			(effects
				(font
					(size 1 1)
					(thickness 0.15)
				)
				(justify mirror)
			)
		)
		(property "License" "Apache-2.0"
			(at -5.6 191.4 0)
			(layer "B.Fab")
			(hide yes)
			(effects
				(font
					(size 1 1)
					(thickness 0.15)
				)
				(justify mirror)
			)
		)
		(property "MPN" "CR0402-FX-1002GLF"
			(at -5.6 191.4 0)
			(layer "B.Fab")
			(hide yes)
			(effects
				(font
					(size 1 1)
					(thickness 0.15)
				)
				(justify mirror)
			)
		)
		(property "Manufacturer" "Bourns"
			(at -5.6 191.4 0)
			(layer "B.Fab")
			(hide yes)
			(effects
				(font
					(size 1 1)
					(thickness 0.15)
				)
				(justify mirror)
			)
		)
		(property "Tolerance" "1%"
			(at -5.6 191.4 0)
			(layer "B.Fab")
			(hide yes)
			(effects
				(font
					(size 1 1)
					(thickness 0.15)
				)
				(justify mirror)
			)
		)
		(property "Val" "10k"
			(at -5.6 191.4 0)
			(layer "B.Fab")
			(hide yes)
			(effects
				(font
					(size 1 1)
					(thickness 0.15)
				)
				(justify mirror)
			)
		)
		(sheetname "HDMI")
		(sheetfile "hdmi.kicad_sch")
		(attr smd)
		(fp_rect
			(start -0.925 0.47)
			(end 0.925 -0.47)
			(stroke
				(width 0.05)
				(type default)
			)
			(fill none)
			(layer "B.CrtYd")
		)
		(fp_rect
			(start -0.5 0.25)
			(end 0.5 -0.25)
			(stroke
				(width 0.15)
				(type solid)
			)
			(fill none)
			(layer "B.Fab")
		)
		(fp_text user "License: Apache-2.0"
			(at -0.95 -5.169 90)
			(layer "B.Fab")
			(hide yes)
			(effects
				(font
					(size 0.7 0.7)
					(thickness 0.15)
				)
				(justify left bottom mirror)
			)
		)
		(fp_text user "${REFERENCE}"
			(at -0.95 -3.168 90)
			(layer "B.Fab")
			(hide yes)
			(effects
				(font
					(size 0.7 0.7)
					(thickness 0.15)
				)
				(justify left bottom mirror)
			)
		)
		(fp_text user "Author: Antmicro"
			(at -0.95 -4.169 90)
			(layer "B.Fab")
			(hide yes)
			(effects
				(font
					(size 0.7 0.7)
					(thickness 0.15)
				)
				(justify left bottom mirror)
			)
		)
		(pad "1" smd roundrect
			(at -0.48 0 270)
			(size 0.59 0.64)
			(layers "B.Cu" "B.Paste" "B.Mask")
			(roundrect_rratio 0.25)
			(net 686 "Net-(U36-SEL1)")
			(pintype "passive")
		)
		(pad "2" smd roundrect
			(at 0.48 0 270)
			(size 0.59 0.64)
			(layers "B.Cu" "B.Paste" "B.Mask")
			(roundrect_rratio 0.25)
			(net 87 "+3V3")
			(pintype "passive")
		)
	)
	(footprint "antmicro-footprints:D_SOD-123F"
		(layer "B.Cu")
		(at 51.2 93.3 180)
		(property "Reference" "D14"
			(at 4.65 1.04 0)
			(layer "B.SilkS")
			(effects
				(font
					(size 0.7 0.7)
					(thickness 0.15)
				)
				(justify left bottom mirror)
			)
		)
		(property "Value" "PTVS58VS1UR,115"
			(at 0 -2.1 0)
			(layer "B.Fab")
			(effects
				(font
					(size 0.7 0.7)
					(thickness 0.15)
				)
				(justify left bottom mirror)
			)
		)
		(property "Footprint" "antmicro-footprints:D_SOD-123F"
			(at 0 0 180)
			(layer "F.Fab")
			(hide yes)
			(effects
				(font
					(size 1.27 1.27)
					(thickness 0.15)
				)
			)
		)
		(property "Datasheet" "https://assets.nexperia.com/documents/data-sheet/PTVSXS1UR_SER.pdf"
			(at 0 0 180)
			(layer "F.Fab")
			(hide yes)
			(effects
				(font
					(size 1.27 1.27)
					(thickness 0.15)
				)
			)
		)
		(property "Author" "Antmicro"
			(at 102.4 186.6 0)
			(layer "B.Fab")
			(hide yes)
			(effects
				(font
					(size 1 1)
					(thickness 0.15)
				)
				(justify mirror)
			)
		)
		(property "License" "Apache-2.0"
			(at 102.4 186.6 0)
			(layer "B.Fab")
			(hide yes)
			(effects
				(font
					(size 1 1)
					(thickness 0.15)
				)
				(justify mirror)
			)
		)
		(property "MPN" "PTVS58VS1UR,115"
			(at 102.4 186.6 0)
			(layer "B.Fab")
			(hide yes)
			(effects
				(font
					(size 1 1)
					(thickness 0.15)
				)
				(justify mirror)
			)
		)
		(property "Manufacturer" "Nexperia"
			(at 102.4 186.6 0)
			(layer "B.Fab")
			(hide yes)
			(effects
				(font
					(size 1 1)
					(thickness 0.15)
				)
				(justify mirror)
			)
		)
		(sheetname "Ethernet")
		(sheetfile "ethernet.kicad_sch")
		(attr smd)
		(fp_line
			(start -0.65 -0.6)
			(end -0.65 0.6)
			(stroke
				(width 0.15)
				(type solid)
			)
			(layer "B.SilkS")
		)
		(fp_line
			(start 2.2 -1.1)
			(end 2.2 1.1)
			(stroke
				(width 0.05)
				(type solid)
			)
			(layer "B.CrtYd")
		)
		(fp_line
			(start -2.21 1.1)
			(end 2.2 1.1)
			(stroke
				(width 0.05)
				(type solid)
			)
			(layer "B.CrtYd")
		)
		(fp_line
			(start -2.21 1.1)
			(end -2.21 -1.1)
			(stroke
				(width 0.05)
				(type solid)
			)
			(layer "B.CrtYd")
		)
		(fp_line
			(start -2.21 -1.1)
			(end 2.2 -1.1)
			(stroke
				(width 0.05)
				(type solid)
			)
			(layer "B.CrtYd")
		)
		(fp_line
			(start -0.8 -0.8)
			(end -0.8 0.8)
			(stroke
				(width 0.1)
				(type solid)
			)
			(layer "B.Fab")
		)
		(fp_rect
			(start -1.75 0.802)
			(end 1.749 -0.8)
			(stroke
				(width 0.1)
				(type solid)
			)
			(fill none)
			(layer "B.Fab")
		)
		(fp_text user "Author: Antmicro"
			(at -2.202 -4.998 0)
			(layer "B.Fab")
			(hide yes)
			(effects
				(font
					(size 0.7 0.7)
					(thickness 0.15)
				)
				(justify left bottom mirror)
			)
		)
		(fp_text user "License: Apache-2.0"
			(at -2.202 -6.2 0)
			(layer "B.Fab")
			(hide yes)
			(effects
				(font
					(size 0.7 0.7)
					(thickness 0.15)
				)
				(justify left bottom mirror)
			)
		)
		(fp_text user "${REFERENCE}"
			(at -2.202 -3.798 0)
			(layer "B.Fab")
			(hide yes)
			(effects
				(font
					(size 0.7 0.7)
					(thickness 0.15)
				)
				(justify left bottom mirror)
			)
		)
		(pad "1" smd roundrect
			(at -1.401 0 180)
			(size 1.2 1.2)
			(layers "B.Cu" "B.Paste" "B.Mask")
			(roundrect_rratio 0.25)
			(net 105 "/Ethernet/VDD")
			(pinfunction "C")
			(pintype "passive")
		)
		(pad "2" smd roundrect
			(at 1.398 0 180)
			(size 1.2 1.2)
			(layers "B.Cu" "B.Paste" "B.Mask")
			(roundrect_rratio 0.25)
			(net 499 "/Ethernet/VSS")
			(pinfunction "A")
			(pintype "passive")
		)
	)
	(footprint "antmicro-footprints:TP_SMD_0.75mm"
		(layer "B.Cu")
		(at 68.165 124.57)
		(property "Reference" "TP52"
			(at 4.9 0.15 180)
			(layer "B.SilkS")
			(hide yes)
			(effects
				(font
					(size 0.7 0.7)
					(thickness 0.15)
				)
				(justify left bottom mirror)
			)
		)
		(property "Value" "TP_0.75mm_SMD"
			(at 0 -1.2 180)
			(layer "B.Fab")
			(effects
				(font
					(size 0.7 0.7)
					(thickness 0.15)
				)
				(justify left bottom mirror)
			)
		)
		(property "Footprint" "antmicro-footprints:TP_SMD_0.75mm"
			(at 0 0 0)
			(layer "F.Fab")
			(hide yes)
			(effects
				(font
					(size 1.27 1.27)
					(thickness 0.15)
				)
			)
		)
		(property "Author" "Antmicro"
			(at 0 0 0)
			(layer "B.Fab")
			(hide yes)
			(effects
				(font
					(size 1 1)
					(thickness 0.15)
				)
				(justify mirror)
			)
		)
		(property "License" "Apache-2.0"
			(at 0 0 0)
			(layer "B.Fab")
			(hide yes)
			(effects
				(font
					(size 1 1)
					(thickness 0.15)
				)
				(justify mirror)
			)
		)
		(property "MPN" ""
			(at 0 0 0)
			(layer "B.Fab")
			(hide yes)
			(effects
				(font
					(size 1 1)
					(thickness 0.15)
				)
				(justify mirror)
			)
		)
		(property "Manufacturer" ""
			(at 0 0 0)
			(layer "B.Fab")
			(hide yes)
			(effects
				(font
					(size 1 1)
					(thickness 0.15)
				)
				(justify mirror)
			)
		)
		(sheetname "Supply")
		(sheetfile "supply.kicad_sch")
		(attr exclude_from_pos_files exclude_from_bom)
		(fp_circle
			(center 0 0)
			(end 0.475 0)
			(stroke
				(width 0.05)
				(type default)
			)
			(fill none)
			(layer "B.CrtYd")
		)
		(fp_text user "${REFERENCE}"
			(at -0.4 -2.7 180)
			(layer "B.Fab")
			(hide yes)
			(effects
				(font
					(size 0.7 0.7)
					(thickness 0.15)
				)
				(justify left bottom mirror)
			)
		)
		(fp_text user "Author: Antmicro"
			(at -0.4 -3.901 180)
			(layer "B.Fab")
			(hide yes)
			(effects
				(font
					(size 0.7 0.7)
					(thickness 0.15)
				)
				(justify left bottom mirror)
			)
		)
		(fp_text user "License: Apache-2.0"
			(at -0.4 -5.101 180)
			(layer "B.Fab")
			(hide yes)
			(effects
				(font
					(size 0.7 0.7)
					(thickness 0.15)
				)
				(justify left bottom mirror)
			)
		)
		(pad "1" smd circle
			(at 0 0)
			(size 0.75 0.75)
			(layers "B.Cu" "B.Mask")
			(net 117 "3V3_STDB")
			(pinfunction "1")
			(pintype "passive")
		)
	)
	(footprint "antmicro-footprints:C_0805_2012Metric"
		(layer "B.Cu")
		(at 51.3 95.45)
		(descr "Capacitor SMD 0805")
		(tags "capacitor SMD 0805")
		(property "Reference" "C76"
			(at -1 1.87 0)
			(layer "B.SilkS")
			(effects
				(font
					(size 0.7 0.7)
					(thickness 0.15)
				)
				(justify right bottom mirror)
			)
		)
		(property "Value" "C_100n_100V_0805"
			(at -2.055717 -1.963152 0)
			(layer "B.Fab")
			(effects
				(font
					(size 0.7 0.7)
					(thickness 0.15)
				)
				(justify right bottom mirror)
			)
		)
		(property "Footprint" "antmicro-footprints:C_0805_2012Metric"
			(at 0 0 0)
			(layer "F.Fab")
			(hide yes)
			(effects
				(font
					(size 1.27 1.27)
					(thickness 0.15)
				)
			)
		)
		(property "Datasheet" "https://product.samsungsem.com/mlcc/CL21B104KCFNNN.do"
			(at 0 0 0)
			(layer "F.Fab")
			(hide yes)
			(effects
				(font
					(size 1.27 1.27)
					(thickness 0.15)
				)
			)
		)
		(property "Author" "Antmicro"
			(at 0 0 0)
			(layer "B.Fab")
			(hide yes)
			(effects
				(font
					(size 1 1)
					(thickness 0.15)
				)
				(justify mirror)
			)
		)
		(property "Dielectric" "X7R"
			(at 0 0 0)
			(layer "B.Fab")
			(hide yes)
			(effects
				(font
					(size 1 1)
					(thickness 0.15)
				)
				(justify mirror)
			)
		)
		(property "License" "Apache-2.0"
			(at 0 0 0)
			(layer "B.Fab")
			(hide yes)
			(effects
				(font
					(size 1 1)
					(thickness 0.15)
				)
				(justify mirror)
			)
		)
		(property "MPN" "CL21B104KCFNNNE"
			(at 0 0 0)
			(layer "B.Fab")
			(hide yes)
			(effects
				(font
					(size 1 1)
					(thickness 0.15)
				)
				(justify mirror)
			)
		)
		(property "Manufacturer" "Samsung Electro-Mechanics"
			(at 0 0 0)
			(layer "B.Fab")
			(hide yes)
			(effects
				(font
					(size 1 1)
					(thickness 0.15)
				)
				(justify mirror)
			)
		)
		(property "Public" "False"
			(at 0 0 0)
			(layer "B.Fab")
			(hide yes)
			(effects
				(font
					(size 1 1)
					(thickness 0.15)
				)
				(justify mirror)
			)
		)
		(property "Val" "100n"
			(at 0 0 0)
			(layer "B.Fab")
			(hide yes)
			(effects
				(font
					(size 1 1)
					(thickness 0.15)
				)
				(justify mirror)
			)
		)
		(property "Voltage" "100V"
			(at 0 0 0)
			(layer "B.Fab")
			(hide yes)
			(effects
				(font
					(size 1 1)
					(thickness 0.15)
				)
				(justify mirror)
			)
		)
		(sheetname "Ethernet")
		(sheetfile "ethernet.kicad_sch")
		(attr smd)
		(fp_line
			(start 0.3 -0.7)
			(end -0.3 -0.7)
			(stroke
				(width 0.15)
				(type solid)
			)
			(layer "B.SilkS")
		)
		(fp_line
			(start 0.3 0.7)
			(end -0.3 0.7)
			(stroke
				(width 0.15)
				(type solid)
			)
			(layer "B.SilkS")
		)
		(fp_rect
			(start 1.95 0.9)
			(end -1.95 -0.9)
			(stroke
				(width 0.05)
				(type default)
			)
			(fill none)
			(layer "B.CrtYd")
		)
		(fp_rect
			(start -0.95 0.675)
			(end 0.95 -0.675)
			(stroke
				(width 0.15)
				(type solid)
			)
			(fill none)
			(layer "B.Fab")
		)
		(fp_text user "License: Apache-2.0"
			(at -1.9 -4.947 0)
			(layer "B.Fab")
			(hide yes)
			(effects
				(font
					(size 0.7 0.7)
					(thickness 0.15)
				)
				(justify right bottom mirror)
			)
		)
		(fp_text user "Author: Antmicro"
			(at -1.9 -5.947 0)
			(layer "B.Fab")
			(hide yes)
			(effects
				(font
					(size 0.7 0.7)
					(thickness 0.15)
				)
				(justify right bottom mirror)
			)
		)
		(fp_text user "${REFERENCE}"
			(at -1.9 -3.947 0)
			(layer "B.Fab")
			(hide yes)
			(effects
				(font
					(size 0.7 0.7)
					(thickness 0.15)
				)
				(justify right bottom mirror)
			)
		)
		(pad "1" smd roundrect
			(at -1.1 0)
			(size 1.2 1.3)
			(layers "B.Cu" "B.Paste" "B.Mask")
			(roundrect_rratio 0.25)
			(net 499 "/Ethernet/VSS")
			(pintype "passive")
		)
		(pad "2" smd roundrect
			(at 1.1 0)
			(size 1.2 1.3)
			(layers "B.Cu" "B.Paste" "B.Mask")
			(roundrect_rratio 0.25)
			(net 105 "/Ethernet/VDD")
			(pintype "passive")
		)
	)
	(footprint "antmicro-footprints:R_Array_4x0201_Panasonic_EXB18V"
		(layer "B.Cu")
		(at 90.135 106.25)
		(property "Reference" "R25"
			(at -1.085 1.45 180)
			(layer "B.SilkS")
			(effects
				(font
					(size 0.7 0.7)
					(thickness 0.15)
				)
				(justify right bottom mirror)
			)
		)
		(property "Value" "R_4x0R_0201_array"
			(at -1.1 -1.8 180)
			(layer "B.Fab")
			(effects
				(font
					(size 0.7 0.7)
					(thickness 0.15)
				)
				(justify left bottom mirror)
			)
		)
		(property "Footprint" "antmicro-footprints:R_Array_4x0201_Panasonic_EXB18V"
			(at 0 0 0)
			(layer "F.Fab")
			(hide yes)
			(effects
				(font
					(size 1.27 1.27)
					(thickness 0.15)
				)
			)
		)
		(property "Datasheet" "http://industrial.panasonic.com/cdbs/www-data/pdf/AOC0000/AOC0000C14.pdf"
			(at 0 0 0)
			(layer "F.Fab")
			(hide yes)
			(effects
				(font
					(size 1.27 1.27)
					(thickness 0.15)
				)
			)
		)
		(property "Author" "Antmicro"
			(at 0 0 0)
			(layer "B.Fab")
			(hide yes)
			(effects
				(font
					(size 1 1)
					(thickness 0.15)
				)
				(justify mirror)
			)
		)
		(property "License" "Apache-2.0"
			(at 0 0 0)
			(layer "B.Fab")
			(hide yes)
			(effects
				(font
					(size 1 1)
					(thickness 0.15)
				)
				(justify mirror)
			)
		)
		(property "MPN" "EXB-18VR000X"
			(at 0 0 0)
			(layer "B.Fab")
			(hide yes)
			(effects
				(font
					(size 1 1)
					(thickness 0.15)
				)
				(justify mirror)
			)
		)
		(property "Manufacturer" "Panasonic"
			(at 0 0 0)
			(layer "B.Fab")
			(hide yes)
			(effects
				(font
					(size 1 1)
					(thickness 0.15)
				)
				(justify mirror)
			)
		)
		(property "Val" "4x0R_0201"
			(at 0 0 0)
			(layer "B.Fab")
			(hide yes)
			(effects
				(font
					(size 1 1)
					(thickness 0.15)
				)
				(justify mirror)
			)
		)
		(sheetname "Peripherals")
		(sheetfile "peripherals.kicad_sch")
		(attr smd)
		(fp_line
			(start -0.8 -0.45)
			(end -0.8 0.45)
			(stroke
				(width 0.12)
				(type solid)
			)
			(layer "B.SilkS")
		)
		(fp_line
			(start 0.8 -0.45)
			(end 0.8 0.45)
			(stroke
				(width 0.12)
				(type solid)
			)
			(layer "B.SilkS")
		)
		(fp_rect
			(start -0.898 0.66)
			(end 0.898 -0.65)
			(stroke
				(width 0.05)
				(type solid)
			)
			(fill none)
			(layer "B.CrtYd")
		)
		(fp_text user "License: Apache-2.0"
			(at -1.051 -6 180)
			(layer "B.Fab")
			(hide yes)
			(effects
				(font
					(size 0.7 0.7)
					(thickness 0.15)
				)
				(justify left bottom mirror)
			)
		)
		(fp_text user "Author: Antmicro"
			(at -1.051 -4.599 180)
			(layer "B.Fab")
			(hide yes)
			(effects
				(font
					(size 0.7 0.7)
					(thickness 0.15)
				)
				(justify left bottom mirror)
			)
		)
		(fp_text user "${REFERENCE}"
			(at -1.051 -3.2 180)
			(layer "B.Fab")
			(hide yes)
			(effects
				(font
					(size 0.7 0.7)
					(thickness 0.15)
				)
				(justify left bottom mirror)
			)
		)
		(pad "1" smd roundrect
			(at -0.6 -0.298)
			(size 0.2 0.4)
			(layers "B.Cu" "B.Paste" "B.Mask")
			(roundrect_rratio 0.25)
			(net 322 "CSIA_PEN")
			(pinfunction "R1.1")
			(pintype "passive")
		)
		(pad "2" smd roundrect
			(at -0.202 -0.298)
			(size 0.2 0.4)
			(layers "B.Cu" "B.Paste" "B.Mask")
			(roundrect_rratio 0.25)
			(net 338 "CSIB_PEN")
			(pinfunction "R2.1")
			(pintype "passive")
		)
		(pad "3" smd roundrect
			(at 0.2 -0.298)
			(size 0.2 0.4)
			(layers "B.Cu" "B.Paste" "B.Mask")
			(roundrect_rratio 0.25)
			(net 562 "USBC1_PEN")
			(pinfunction "R3.1")
			(pintype "passive")
		)
		(pad "4" smd roundrect
			(at 0.598 -0.298)
			(size 0.2 0.4)
			(layers "B.Cu" "B.Paste" "B.Mask")
			(roundrect_rratio 0.25)
			(net 514 "DISABLE_POE_DCDC")
			(pinfunction "R4.1")
			(pintype "passive")
		)
		(pad "5" smd roundrect
			(at 0.598 0.3)
			(size 0.2 0.4)
			(layers "B.Cu" "B.Paste" "B.Mask")
			(roundrect_rratio 0.25)
			(net 356 "/Peripherals/GPIOEX_P0_3")
			(pinfunction "R4.2")
			(pintype "passive")
		)
		(pad "6" smd roundrect
			(at 0.2 0.3)
			(size 0.2 0.4)
			(layers "B.Cu" "B.Paste" "B.Mask")
			(roundrect_rratio 0.25)
			(net 355 "/Peripherals/GPIOEX_P0_2")
			(pinfunction "R3.2")
			(pintype "passive")
		)
		(pad "7" smd roundrect
			(at -0.202 0.3)
			(size 0.2 0.4)
			(layers "B.Cu" "B.Paste" "B.Mask")
			(roundrect_rratio 0.25)
			(net 354 "/Peripherals/GPIOEX_P0_1")
			(pinfunction "R2.2")
			(pintype "passive")
		)
		(pad "8" smd roundrect
			(at -0.6 0.3)
			(size 0.2 0.4)
			(layers "B.Cu" "B.Paste" "B.Mask")
			(roundrect_rratio 0.25)
			(net 353 "/Peripherals/GPIOEX_P0_0")
			(pinfunction "R1.2")
			(pintype "passive")
		)
	)
	(footprint "antmicro-footprints:SOD-923"
		(layer "B.Cu")
		(at 56.5 119.67)
		(property "Reference" "D6"
			(at 0.8 -0.52 0)
			(unlocked yes)
			(layer "B.SilkS")
			(effects
				(font
					(size 0.7 0.7)
					(thickness 0.15)
				)
				(justify left bottom mirror)
			)
		)
		(property "Value" "DF2S30FS_SOD"
			(at 0 -1.3 180)
			(unlocked yes)
			(layer "B.Fab")
			(effects
				(font
					(size 0.7 0.7)
					(thickness 0.15)
				)
				(justify left bottom mirror)
			)
		)
		(property "Footprint" "antmicro-footprints:SOD-923"
			(at 0 0 0)
			(layer "F.Fab")
			(hide yes)
			(effects
				(font
					(size 1.27 1.27)
					(thickness 0.15)
				)
			)
		)
		(property "Datasheet" "https://toshiba.semicon-storage.com/info/DF2S30FS_datasheet_en_20211216.pdf?did=11156&prodName=DF2S30FS"
			(at 0 0 0)
			(layer "F.Fab")
			(hide yes)
			(effects
				(font
					(size 1.27 1.27)
					(thickness 0.15)
				)
			)
		)
		(property "Author" "Antmicro"
			(at 0 0 0)
			(layer "B.Fab")
			(hide yes)
			(effects
				(font
					(size 1 1)
					(thickness 0.15)
				)
				(justify mirror)
			)
		)
		(property "License" "Apache-2.0"
			(at 0 0 0)
			(layer "B.Fab")
			(hide yes)
			(effects
				(font
					(size 1 1)
					(thickness 0.15)
				)
				(justify mirror)
			)
		)
		(property "MPN" "DF2S30FS"
			(at 0 0 0)
			(layer "B.Fab")
			(hide yes)
			(effects
				(font
					(size 1 1)
					(thickness 0.15)
				)
				(justify mirror)
			)
		)
		(property "Manufacturer" "Toshiba"
			(at 0 0 0)
			(layer "B.Fab")
			(hide yes)
			(effects
				(font
					(size 1 1)
					(thickness 0.15)
				)
				(justify mirror)
			)
		)
		(sheetname "USB Debug, DP")
		(sheetfile "usb.kicad_sch")
		(attr smd)
		(fp_line
			(start -0.5 -0.3)
			(end -0.5 -0.4)
			(stroke
				(width 0.15)
				(type solid)
			)
			(layer "B.SilkS")
		)
		(fp_line
			(start -0.5 0.4)
			(end -0.5 0.3)
			(stroke
				(width 0.15)
				(type solid)
			)
			(layer "B.SilkS")
		)
		(fp_line
			(start -0.16 -0.4)
			(end -0.16 0.4)
			(stroke
				(width 0.15)
				(type solid)
			)
			(layer "B.SilkS")
		)
		(fp_line
			(start 0.5 -0.4)
			(end -0.5 -0.4)
			(stroke
				(width 0.15)
				(type solid)
			)
			(layer "B.SilkS")
		)
		(fp_line
			(start 0.5 -0.3)
			(end 0.5 -0.4)
			(stroke
				(width 0.15)
				(type solid)
			)
			(layer "B.SilkS")
		)
		(fp_line
			(start 0.5 0.3)
			(end 0.5 0.4)
			(stroke
				(width 0.15)
				(type solid)
			)
			(layer "B.SilkS")
		)
		(fp_line
			(start 0.5 0.4)
			(end -0.5 0.4)
			(stroke
				(width 0.15)
				(type solid)
			)
			(layer "B.SilkS")
		)
		(fp_rect
			(start -0.68 0.41)
			(end 0.68 -0.41)
			(stroke
				(width 0.05)
				(type solid)
			)
			(fill none)
			(layer "B.CrtYd")
		)
		(fp_line
			(start -0.202 -0.298)
			(end -0.202 0.3)
			(stroke
				(width 0.15)
				(type solid)
			)
			(layer "B.Fab")
		)
		(fp_rect
			(start -0.402 0.3)
			(end 0.4 -0.298)
			(stroke
				(width 0.15)
				(type solid)
			)
			(fill none)
			(layer "B.Fab")
		)
		(fp_text user "License: Apache-2.0"
			(at -0.68 -4.5 180)
			(layer "B.Fab")
			(hide yes)
			(effects
				(font
					(size 0.7 0.7)
					(thickness 0.15)
				)
				(justify left bottom mirror)
			)
		)
		(fp_text user "Author: Antmicro"
			(at -0.68 -5.7 180)
			(layer "B.Fab")
			(hide yes)
			(effects
				(font
					(size 0.7 0.7)
					(thickness 0.15)
				)
				(justify left bottom mirror)
			)
		)
		(fp_text user "${REFERENCE}"
			(at -0.68 -3.3 180)
			(unlocked yes)
			(layer "B.Fab")
			(hide yes)
			(effects
				(font
					(size 0.7 0.7)
					(thickness 0.15)
				)
				(justify left bottom mirror)
			)
		)
		(pad "1" smd roundrect
			(at -0.438 0)
			(size 0.4 0.325)
			(layers "B.Cu" "B.Paste" "B.Mask")
			(roundrect_rratio 0.25)
			(net 196 "/USB Debug, DP/USBC3_VBUS")
			(pinfunction "C")
			(pintype "passive")
		)
		(pad "2" smd roundrect
			(at 0.436 0)
			(size 0.4 0.325)
			(layers "B.Cu" "B.Paste" "B.Mask")
			(roundrect_rratio 0.25)
			(net 1 "GND")
			(pinfunction "A")
			(pintype "passive")
		)
	)
	(footprint "antmicro-footprints:R_0402_1005Metric"
		(layer "B.Cu")
		(at 74.12 77.03 -90)
		(descr "Resistor SMD 0402")
		(tags "resistor SMD 0402")
		(property "Reference" "R183"
			(at -1.155 -1.45 90)
			(layer "B.SilkS")
			(effects
				(font
					(size 0.7 0.7)
					(thickness 0.15)
				)
				(justify left bottom mirror)
			)
		)
		(property "Value" "R_0R_0402"
			(at 0 -1.4 90)
			(layer "B.Fab")
			(effects
				(font
					(size 0.7 0.7)
					(thickness 0.15)
				)
				(justify left bottom mirror)
			)
		)
		(property "Footprint" "antmicro-footprints:R_0402_1005Metric"
			(at 0 0 -90)
			(layer "F.Fab")
			(hide yes)
			(effects
				(font
					(size 1.27 1.27)
					(thickness 0.15)
				)
			)
		)
		(property "Datasheet" "https://industrial.panasonic.com/cdbs/www-data/pdf/RDA0000/AOA0000C301.pdf"
			(at 0 0 -90)
			(layer "F.Fab")
			(hide yes)
			(effects
				(font
					(size 1.27 1.27)
					(thickness 0.15)
				)
			)
		)
		(property "Author" "Antmicro"
			(at -2.91 151.15 0)
			(layer "B.Fab")
			(hide yes)
			(effects
				(font
					(size 1 1)
					(thickness 0.15)
				)
				(justify mirror)
			)
		)
		(property "Current" "1A"
			(at -2.91 151.15 0)
			(layer "B.Fab")
			(hide yes)
			(effects
				(font
					(size 1 1)
					(thickness 0.15)
				)
				(justify mirror)
			)
		)
		(property "License" "Apache-2.0"
			(at -2.91 151.15 0)
			(layer "B.Fab")
			(hide yes)
			(effects
				(font
					(size 1 1)
					(thickness 0.15)
				)
				(justify mirror)
			)
		)
		(property "MPN" "ERJ2GE0R00X"
			(at -2.91 151.15 0)
			(layer "B.Fab")
			(hide yes)
			(effects
				(font
					(size 1 1)
					(thickness 0.15)
				)
				(justify mirror)
			)
		)
		(property "Manufacturer" "Panasonic"
			(at -2.91 151.15 0)
			(layer "B.Fab")
			(hide yes)
			(effects
				(font
					(size 1 1)
					(thickness 0.15)
				)
				(justify mirror)
			)
		)
		(property "Tolerance" ""
			(at -2.91 151.15 0)
			(layer "B.Fab")
			(hide yes)
			(effects
				(font
					(size 1 1)
					(thickness 0.15)
				)
				(justify mirror)
			)
		)
		(property "Val" "0R"
			(at -2.91 151.15 0)
			(layer "B.Fab")
			(hide yes)
			(effects
				(font
					(size 1 1)
					(thickness 0.15)
				)
				(justify mirror)
			)
		)
		(sheetname "Supply")
		(sheetfile "supply.kicad_sch")
		(attr smd exclude_from_pos_files exclude_from_bom dnp)
		(fp_rect
			(start -0.925 0.47)
			(end 0.925 -0.47)
			(stroke
				(width 0.05)
				(type default)
			)
			(fill none)
			(layer "B.CrtYd")
		)
		(fp_rect
			(start -0.5 0.25)
			(end 0.5 -0.25)
			(stroke
				(width 0.15)
				(type solid)
			)
			(fill none)
			(layer "B.Fab")
		)
		(fp_text user "Author: Antmicro"
			(at -0.95 -4.169 90)
			(layer "B.Fab")
			(hide yes)
			(effects
				(font
					(size 0.7 0.7)
					(thickness 0.15)
				)
				(justify left bottom mirror)
			)
		)
		(fp_text user "License: Apache-2.0"
			(at -0.95 -5.169 90)
			(layer "B.Fab")
			(hide yes)
			(effects
				(font
					(size 0.7 0.7)
					(thickness 0.15)
				)
				(justify left bottom mirror)
			)
		)
		(fp_text user "${REFERENCE}"
			(at -0.95 -3.168 90)
			(layer "B.Fab")
			(hide yes)
			(effects
				(font
					(size 0.7 0.7)
					(thickness 0.15)
				)
				(justify left bottom mirror)
			)
		)
		(pad "1" smd roundrect
			(at -0.48 0 270)
			(size 0.59 0.64)
			(layers "B.Cu" "B.Paste" "B.Mask")
			(roundrect_rratio 0.25)
			(net 86 "~{RESET}")
			(pintype "passive")
		)
		(pad "2" smd roundrect
			(at 0.48 0 270)
			(size 0.59 0.64)
			(layers "B.Cu" "B.Paste" "B.Mask")
			(roundrect_rratio 0.25)
			(net 117 "3V3_STDB")
			(pintype "passive")
		)
	)
	(footprint "antmicro-footprints:LED_0603_1608Metric_G"
		(layer "B.Cu")
		(at 136.7 126 90)
		(descr "LED SMD 0603 Green")
		(tags "LED SMD 0603 Green")
		(property "Reference" "D54"
			(at -2.3 -1.15 180)
			(layer "B.SilkS")
			(effects
				(font
					(size 0.7 0.7)
					(thickness 0.15)
				)
				(justify right bottom mirror)
			)
		)
		(property "Value" "LED_G_0603_LTST-C190GKT"
			(at -0.001 -1.599 90)
			(layer "B.Fab")
			(effects
				(font
					(size 0.7 0.7)
					(thickness 0.15)
				)
				(justify right bottom mirror)
			)
		)
		(property "Footprint" "antmicro-footprints:LED_0603_1608Metric_G"
			(at 0 0 90)
			(layer "F.Fab")
			(hide yes)
			(effects
				(font
					(size 1.27 1.27)
					(thickness 0.15)
				)
			)
		)
		(property "Datasheet" "https://media.digikey.com/pdf/Data%20Sheets/Lite-On%20PDFs/LTST-C190GKT.pdf"
			(at 0 0 90)
			(layer "F.Fab")
			(hide yes)
			(effects
				(font
					(size 1.27 1.27)
					(thickness 0.15)
				)
			)
		)
		(property "Author" "Antmicro"
			(at 262.7 -10.7 0)
			(layer "B.Fab")
			(hide yes)
			(effects
				(font
					(size 1 1)
					(thickness 0.15)
				)
				(justify mirror)
			)
		)
		(property "Color" "Green"
			(at 262.7 -10.7 0)
			(layer "B.Fab")
			(hide yes)
			(effects
				(font
					(size 1 1)
					(thickness 0.15)
				)
				(justify mirror)
			)
		)
		(property "License" "Apache-2.0"
			(at 262.7 -10.7 0)
			(layer "B.Fab")
			(hide yes)
			(effects
				(font
					(size 1 1)
					(thickness 0.15)
				)
				(justify mirror)
			)
		)
		(property "MPN" "LTST-C190GKT"
			(at 262.7 -10.7 0)
			(layer "B.Fab")
			(hide yes)
			(effects
				(font
					(size 1 1)
					(thickness 0.15)
				)
				(justify mirror)
			)
		)
		(property "Manufacturer" "Lite-On"
			(at 262.7 -10.7 0)
			(layer "B.Fab")
			(hide yes)
			(effects
				(font
					(size 1 1)
					(thickness 0.15)
				)
				(justify mirror)
			)
		)
		(sheetname "Peripherals")
		(sheetfile "peripherals.kicad_sch")
		(attr smd)
		(fp_line
			(start -0.22 -0.35)
			(end 0.22 -0.35)
			(stroke
				(width 0.15)
				(type solid)
			)
			(layer "B.SilkS")
		)
		(fp_line
			(start -1.18 -0.321)
			(end -1.18 0.319)
			(stroke
				(width 0.15)
				(type solid)
			)
			(layer "B.SilkS")
		)
		(fp_line
			(start -0.094672 -0.001008)
			(end 0.105328 -0.201008)
			(stroke
				(width 0.1)
				(type solid)
			)
			(layer "B.SilkS")
		)
		(fp_line
			(start -0.24 -0.001008)
			(end -0.094672 -0.001008)
			(stroke
				(width 0.1)
				(type solid)
			)
			(layer "B.SilkS")
		)
		(fp_line
			(start 0.24 -0.001)
			(end 0.105328 -0.001008)
			(stroke
				(width 0.1)
				(type solid)
			)
			(layer "B.SilkS")
		)
		(fp_line
			(start 0.105328 0.198992)
			(end 0.105328 -0.201008)
			(stroke
				(width 0.1)
				(type solid)
			)
			(layer "B.SilkS")
		)
		(fp_line
			(start 0.105328 0.198992)
			(end -0.094672 -0.001008)
			(stroke
				(width 0.1)
				(type solid)
			)
			(layer "B.SilkS")
		)
		(fp_line
			(start -0.094672 0.198992)
			(end -0.094672 -0.201008)
			(stroke
				(width 0.1)
				(type solid)
			)
			(layer "B.SilkS")
		)
		(fp_line
			(start -0.22 0.35)
			(end 0.22 0.35)
			(stroke
				(width 0.15)
				(type solid)
			)
			(layer "B.SilkS")
		)
		(fp_rect
			(start 1.25 -0.65)
			(end -1.25 0.65)
			(stroke
				(width 0.05)
				(type solid)
			)
			(fill none)
			(layer "B.CrtYd")
		)
		(fp_line
			(start 0.201 -0.2)
			(end -0.101 0)
			(stroke
				(width 0.15)
				(type solid)
			)
			(layer "B.Fab")
		)
		(fp_line
			(start -0.199 -0.1)
			(end -0.199 -0.2)
			(stroke
				(width 0.15)
				(type solid)
			)
			(layer "B.Fab")
		)
		(fp_line
			(start -0.199 -0.1)
			(end -0.199 0.202)
			(stroke
				(width 0.15)
				(type solid)
			)
			(layer "B.Fab")
		)
		(fp_line
			(start 0.201 0)
			(end 0.201 -0.2)
			(stroke
				(width 0.15)
				(type solid)
			)
			(layer "B.Fab")
		)
		(fp_line
			(start 0.201 0)
			(end 0.599 0)
			(stroke
				(width 0.15)
				(type solid)
			)
			(layer "B.Fab")
		)
		(fp_line
			(start -0.101 0)
			(end 0.201 0.202)
			(stroke
				(width 0.15)
				(type solid)
			)
			(layer "B.Fab")
		)
		(fp_line
			(start -0.597 0)
			(end -0.199 0)
			(stroke
				(width 0.15)
				(type solid)
			)
			(layer "B.Fab")
		)
		(fp_line
			(start 0.201 0.202)
			(end 0.201 0)
			(stroke
				(width 0.15)
				(type solid)
			)
			(layer "B.Fab")
		)
		(fp_rect
			(start 0.848 -0.4)
			(end -0.85 0.402)
			(stroke
				(width 0.15)
				(type solid)
			)
			(fill none)
			(layer "B.Fab")
		)
		(fp_text user "Author: Antmicro"
			(at -1.4224 -4.799 90)
			(layer "B.Fab")
			(hide yes)
			(effects
				(font
					(size 0.7 0.7)
					(thickness 0.15)
				)
				(justify right bottom mirror)
			)
		)
		(fp_text user "License: Apache-2.0"
			(at -1.4224 -3.599 90)
			(layer "B.Fab")
			(hide yes)
			(effects
				(font
					(size 0.7 0.7)
					(thickness 0.15)
				)
				(justify right bottom mirror)
			)
		)
		(fp_text user "${REFERENCE}"
			(at -1.4224 -5.999 90)
			(layer "B.Fab")
			(hide yes)
			(effects
				(font
					(size 0.7 0.7)
					(thickness 0.15)
				)
				(justify right bottom mirror)
			)
		)
		(pad "1" smd roundrect
			(at -0.7 0 270)
			(size 0.8 1)
			(layers "B.Cu" "B.Paste" "B.Mask")
			(roundrect_rratio 0.2)
			(net 1 "GND")
			(pinfunction "C")
			(pintype "passive")
		)
		(pad "2" smd roundrect
			(at 0.7 0 270)
			(size 0.8 1)
			(layers "B.Cu" "B.Paste" "B.Mask")
			(roundrect_rratio 0.2)
			(net 661 "Net-(D54-A)")
			(pinfunction "A")
			(pintype "passive")
		)
	)
	(footprint "antmicro-footprints:R_0402_1005Metric"
		(layer "B.Cu")
		(at 85.5 106.4 -45)
		(descr "Resistor SMD 0402")
		(tags "resistor SMD 0402")
		(property "Reference" "R207"
			(at -0.035355 2.227386 -45)
			(layer "B.SilkS")
			(effects
				(font
					(size 0.7 0.7)
					(thickness 0.15)
				)
				(justify left bottom mirror)
			)
		)
		(property "Value" "R_100k_0402"
			(at 0 -1.399999 135)
			(layer "B.Fab")
			(effects
				(font
					(size 0.7 0.7)
					(thickness 0.15)
				)
				(justify left bottom mirror)
			)
		)
		(property "Footprint" "antmicro-footprints:R_0402_1005Metric"
			(at 0 0 -45)
			(layer "F.Fab")
			(hide yes)
			(effects
				(font
					(size 1.27 1.27)
					(thickness 0.15)
				)
			)
		)
		(property "Datasheet" "https://www.bourns.com/docs/product-datasheets/cr.pdf"
			(at 0 0 -45)
			(layer "F.Fab")
			(hide yes)
			(effects
				(font
					(size 1.27 1.27)
					(thickness 0.15)
				)
			)
		)
		(property "Author" "Antmicro"
			(at -50.193792 91.621468 0)
			(layer "B.Fab")
			(hide yes)
			(effects
				(font
					(size 1 1)
					(thickness 0.15)
				)
				(justify mirror)
			)
		)
		(property "License" "Apache-2.0"
			(at -50.193792 91.621468 0)
			(layer "B.Fab")
			(hide yes)
			(effects
				(font
					(size 1 1)
					(thickness 0.15)
				)
				(justify mirror)
			)
		)
		(property "MPN" "CR0402-FX-1003GLF"
			(at -50.193792 91.621468 0)
			(layer "B.Fab")
			(hide yes)
			(effects
				(font
					(size 1 1)
					(thickness 0.15)
				)
				(justify mirror)
			)
		)
		(property "Manufacturer" "Bourns"
			(at -50.193792 91.621468 0)
			(layer "B.Fab")
			(hide yes)
			(effects
				(font
					(size 1 1)
					(thickness 0.15)
				)
				(justify mirror)
			)
		)
		(property "Tolerance" "1%"
			(at -50.193792 91.621468 0)
			(layer "B.Fab")
			(hide yes)
			(effects
				(font
					(size 1 1)
					(thickness 0.15)
				)
				(justify mirror)
			)
		)
		(property "Val" "100k"
			(at -50.193792 91.621468 0)
			(layer "B.Fab")
			(hide yes)
			(effects
				(font
					(size 1 1)
					(thickness 0.15)
				)
				(justify mirror)
			)
		)
		(sheetname "USB Debug, DP")
		(sheetfile "usb.kicad_sch")
		(attr smd)
		(fp_poly
			(pts
				(xy -0.925 0.47) (xy 0.925 0.47) (xy 0.925 -0.47) (xy -0.925 -0.47)
			)
			(stroke
				(width 0.05)
				(type default)
			)
			(fill none)
			(layer "B.CrtYd")
		)
		(fp_poly
			(pts
				(xy -0.5 0.25) (xy 0.5 0.25) (xy 0.5 -0.25) (xy -0.5 -0.25)
			)
			(stroke
				(width 0.15)
				(type solid)
			)
			(fill none)
			(layer "B.Fab")
		)
		(fp_text user "${REFERENCE}"
			(at -0.95 -3.168 135)
			(layer "B.Fab")
			(hide yes)
			(effects
				(font
					(size 0.7 0.7)
					(thickness 0.15)
				)
				(justify left bottom mirror)
			)
		)
		(fp_text user "Author: Antmicro"
			(at -0.95 -4.169 135)
			(layer "B.Fab")
			(hide yes)
			(effects
				(font
					(size 0.7 0.7)
					(thickness 0.15)
				)
				(justify left bottom mirror)
			)
		)
		(fp_text user "License: Apache-2.0"
			(at -0.949999 -5.169 135)
			(layer "B.Fab")
			(hide yes)
			(effects
				(font
					(size 0.7 0.7)
					(thickness 0.15)
				)
				(justify left bottom mirror)
			)
		)
		(pad "1" smd roundrect
			(at -0.48 0 315)
			(size 0.59 0.64)
			(layers "B.Cu" "B.Paste" "B.Mask")
			(roundrect_rratio 0.25)
			(net 35 "DP1_AUX_N")
			(pintype "passive")
		)
		(pad "2" smd roundrect
			(at 0.48 0 315)
			(size 0.59 0.64)
			(layers "B.Cu" "B.Paste" "B.Mask")
			(roundrect_rratio 0.25)
			(net 87 "+3V3")
			(pintype "passive")
		)
	)
	(footprint "antmicro-footprints:R_0402_1005Metric"
		(layer "B.Cu")
		(at 56.84 80.7)
		(descr "Resistor SMD 0402")
		(tags "resistor SMD 0402")
		(property "Reference" "R236"
			(at 2.535 1.25 180)
			(layer "B.SilkS")
			(effects
				(font
					(size 0.7 0.7)
					(thickness 0.15)
				)
				(justify left bottom mirror)
			)
		)
		(property "Value" "R_200R_0402"
			(at 0 -1.4 180)
			(layer "B.Fab")
			(effects
				(font
					(size 0.7 0.7)
					(thickness 0.15)
				)
				(justify left bottom mirror)
			)
		)
		(property "Footprint" "antmicro-footprints:R_0402_1005Metric"
			(at 0 0 0)
			(layer "F.Fab")
			(hide yes)
			(effects
				(font
					(size 1.27 1.27)
					(thickness 0.15)
				)
			)
		)
		(property "Datasheet" "https://www.bourns.com/docs/product-datasheets/cr.pdf"
			(at 0 0 0)
			(layer "F.Fab")
			(hide yes)
			(effects
				(font
					(size 1.27 1.27)
					(thickness 0.15)
				)
			)
		)
		(property "Author" "Antmicro"
			(at 0 0 0)
			(layer "B.Fab")
			(hide yes)
			(effects
				(font
					(size 1 1)
					(thickness 0.15)
				)
				(justify mirror)
			)
		)
		(property "License" "Apache-2.0"
			(at 0 0 0)
			(layer "B.Fab")
			(hide yes)
			(effects
				(font
					(size 1 1)
					(thickness 0.15)
				)
				(justify mirror)
			)
		)
		(property "MPN" "CR0402-FX-2000GLF"
			(at 0 0 0)
			(layer "B.Fab")
			(hide yes)
			(effects
				(font
					(size 1 1)
					(thickness 0.15)
				)
				(justify mirror)
			)
		)
		(property "Manufacturer" "Bourns"
			(at 0 0 0)
			(layer "B.Fab")
			(hide yes)
			(effects
				(font
					(size 1 1)
					(thickness 0.15)
				)
				(justify mirror)
			)
		)
		(property "Tolerance" "1%"
			(at 0 0 0)
			(layer "B.Fab")
			(hide yes)
			(effects
				(font
					(size 1 1)
					(thickness 0.15)
				)
				(justify mirror)
			)
		)
		(property "Val" "200R"
			(at 0 0 0)
			(layer "B.Fab")
			(hide yes)
			(effects
				(font
					(size 1 1)
					(thickness 0.15)
				)
				(justify mirror)
			)
		)
		(sheetname "Supply")
		(sheetfile "supply.kicad_sch")
		(attr smd)
		(fp_rect
			(start -0.925 0.47)
			(end 0.925 -0.47)
			(stroke
				(width 0.05)
				(type default)
			)
			(fill none)
			(layer "B.CrtYd")
		)
		(fp_rect
			(start -0.5 0.25)
			(end 0.5 -0.25)
			(stroke
				(width 0.15)
				(type solid)
			)
			(fill none)
			(layer "B.Fab")
		)
		(fp_text user "Author: Antmicro"
			(at -0.95 -4.169 180)
			(layer "B.Fab")
			(hide yes)
			(effects
				(font
					(size 0.7 0.7)
					(thickness 0.15)
				)
				(justify left bottom mirror)
			)
		)
		(fp_text user "${REFERENCE}"
			(at -0.95 -3.168 180)
			(layer "B.Fab")
			(hide yes)
			(effects
				(font
					(size 0.7 0.7)
					(thickness 0.15)
				)
				(justify left bottom mirror)
			)
		)
		(fp_text user "License: Apache-2.0"
			(at -0.95 -5.169 180)
			(layer "B.Fab")
			(hide yes)
			(effects
				(font
					(size 0.7 0.7)
					(thickness 0.15)
				)
				(justify left bottom mirror)
			)
		)
		(pad "1" smd roundrect
			(at -0.48 0)
			(size 0.59 0.64)
			(layers "B.Cu" "B.Paste" "B.Mask")
			(roundrect_rratio 0.25)
			(net 342 "Net-(D37-C)")
			(pintype "passive")
		)
		(pad "2" smd roundrect
			(at 0.48 0)
			(size 0.59 0.64)
			(layers "B.Cu" "B.Paste" "B.Mask")
			(roundrect_rratio 0.25)
			(net 474 "~{SHUTDOWN_REQ}")
			(pintype "passive")
		)
	)
	(footprint "antmicro-footprints:C_0402_1005Metric"
		(layer "B.Cu")
		(at 61.5 107.2 -90)
		(descr "Capacitor SMD 0402")
		(tags "capacitor SMD 0402")
		(property "Reference" "C64"
			(at -1.04 -1.23 90)
			(layer "B.SilkS")
			(effects
				(font
					(size 0.7 0.7)
					(thickness 0.15)
				)
				(justify left bottom mirror)
			)
		)
		(property "Value" "C_100n_0402"
			(at 0 -1.4 90)
			(layer "B.Fab")
			(effects
				(font
					(size 0.7 0.7)
					(thickness 0.15)
				)
				(justify left bottom mirror)
			)
		)
		(property "Footprint" "antmicro-footprints:C_0402_1005Metric"
			(at 0 0 -90)
			(layer "F.Fab")
			(hide yes)
			(effects
				(font
					(size 1.27 1.27)
					(thickness 0.15)
				)
			)
		)
		(property "Datasheet" "https://www.murata.com/products/productdetail?partno=GRM155R61H104KE14%23"
			(at 0 0 -90)
			(layer "F.Fab")
			(hide yes)
			(effects
				(font
					(size 1.27 1.27)
					(thickness 0.15)
				)
			)
		)
		(property "Author" "Antmicro"
			(at -45.7 168.7 0)
			(layer "B.Fab")
			(hide yes)
			(effects
				(font
					(size 1 1)
					(thickness 0.15)
				)
				(justify mirror)
			)
		)
		(property "Dielectric" "X5R"
			(at -45.7 168.7 0)
			(layer "B.Fab")
			(hide yes)
			(effects
				(font
					(size 1 1)
					(thickness 0.15)
				)
				(justify mirror)
			)
		)
		(property "License" "Apache-2.0"
			(at -45.7 168.7 0)
			(layer "B.Fab")
			(hide yes)
			(effects
				(font
					(size 1 1)
					(thickness 0.15)
				)
				(justify mirror)
			)
		)
		(property "MPN" "GRM155R61H104KE14D"
			(at -45.7 168.7 0)
			(layer "B.Fab")
			(hide yes)
			(effects
				(font
					(size 1 1)
					(thickness 0.15)
				)
				(justify mirror)
			)
		)
		(property "Manufacturer" "Murata"
			(at -45.7 168.7 0)
			(layer "B.Fab")
			(hide yes)
			(effects
				(font
					(size 1 1)
					(thickness 0.15)
				)
				(justify mirror)
			)
		)
		(property "Val" "100n"
			(at -45.7 168.7 0)
			(layer "B.Fab")
			(hide yes)
			(effects
				(font
					(size 1 1)
					(thickness 0.15)
				)
				(justify mirror)
			)
		)
		(property "Voltage" "50V"
			(at -45.7 168.7 0)
			(layer "B.Fab")
			(hide yes)
			(effects
				(font
					(size 1 1)
					(thickness 0.15)
				)
				(justify mirror)
			)
		)
		(sheetname "USB Debug, DP")
		(sheetfile "usb.kicad_sch")
		(attr smd)
		(fp_rect
			(start -0.925 0.47)
			(end 0.925 -0.47)
			(stroke
				(width 0.05)
				(type default)
			)
			(fill none)
			(layer "B.CrtYd")
		)
		(fp_line
			(start -0.494 0.25)
			(end -0.494 -0.248)
			(stroke
				(width 0.15)
				(type solid)
			)
			(layer "B.Fab")
		)
		(fp_line
			(start 0.504 0.25)
			(end -0.494 0.25)
			(stroke
				(width 0.15)
				(type solid)
			)
			(layer "B.Fab")
		)
		(fp_line
			(start -0.494 -0.248)
			(end 0.504 -0.248)
			(stroke
				(width 0.15)
				(type solid)
			)
			(layer "B.Fab")
		)
		(fp_line
			(start 0.504 -0.248)
			(end 0.504 0.25)
			(stroke
				(width 0.15)
				(type solid)
			)
			(layer "B.Fab")
		)
		(fp_text user "${REFERENCE}"
			(at -0.932 -3.168 90)
			(layer "B.Fab")
			(hide yes)
			(effects
				(font
					(size 0.7 0.7)
					(thickness 0.15)
				)
				(justify left bottom mirror)
			)
		)
		(fp_text user "Author: Antmicro"
			(at -0.932 -4.17 90)
			(layer "B.Fab")
			(hide yes)
			(effects
				(font
					(size 0.7 0.7)
					(thickness 0.15)
				)
				(justify left bottom mirror)
			)
		)
		(fp_text user "License: Apache-2.0"
			(at -0.932 -5.17 90)
			(layer "B.Fab")
			(hide yes)
			(effects
				(font
					(size 0.7 0.7)
					(thickness 0.15)
				)
				(justify left bottom mirror)
			)
		)
		(pad "1" smd roundrect
			(at -0.48 0 270)
			(size 0.59 0.64)
			(layers "B.Cu" "B.Paste" "B.Mask")
			(roundrect_rratio 0.25)
			(net 196 "/USB Debug, DP/USBC3_VBUS")
			(pintype "passive")
		)
		(pad "2" smd roundrect
			(at 0.48 0 270)
			(size 0.59 0.64)
			(layers "B.Cu" "B.Paste" "B.Mask")
			(roundrect_rratio 0.25)
			(net 1 "GND")
			(pintype "passive")
		)
	)
	(footprint "antmicro-footprints:TP_SMD_0.75mm"
		(layer "B.Cu")
		(at 70 96.4)
		(property "Reference" "TP18"
			(at 3.36 1 0)
			(layer "B.SilkS")
			(hide yes)
			(effects
				(font
					(size 0.7 0.7)
					(thickness 0.15)
				)
				(justify left bottom mirror)
			)
		)
		(property "Value" "TP_0.75mm_SMD"
			(at 0 -1.2 180)
			(layer "B.Fab")
			(effects
				(font
					(size 0.7 0.7)
					(thickness 0.15)
				)
				(justify left bottom mirror)
			)
		)
		(property "Footprint" "antmicro-footprints:TP_SMD_0.75mm"
			(at 0 0 0)
			(layer "F.Fab")
			(hide yes)
			(effects
				(font
					(size 1.27 1.27)
					(thickness 0.15)
				)
			)
		)
		(property "Author" "Antmicro"
			(at 0 0 0)
			(layer "B.Fab")
			(hide yes)
			(effects
				(font
					(size 1 1)
					(thickness 0.15)
				)
				(justify mirror)
			)
		)
		(property "License" "Apache-2.0"
			(at 0 0 0)
			(layer "B.Fab")
			(hide yes)
			(effects
				(font
					(size 1 1)
					(thickness 0.15)
				)
				(justify mirror)
			)
		)
		(property "MPN" ""
			(at 0 0 0)
			(layer "B.Fab")
			(hide yes)
			(effects
				(font
					(size 1 1)
					(thickness 0.15)
				)
				(justify mirror)
			)
		)
		(property "Manufacturer" ""
			(at 0 0 0)
			(layer "B.Fab")
			(hide yes)
			(effects
				(font
					(size 1 1)
					(thickness 0.15)
				)
				(justify mirror)
			)
		)
		(sheetname "USB Debug, DP")
		(sheetfile "usb.kicad_sch")
		(attr exclude_from_pos_files exclude_from_bom)
		(fp_circle
			(center 0 0)
			(end 0.475 0)
			(stroke
				(width 0.05)
				(type default)
			)
			(fill none)
			(layer "B.CrtYd")
		)
		(fp_text user "${REFERENCE}"
			(at -0.4 -2.7 180)
			(layer "B.Fab")
			(hide yes)
			(effects
				(font
					(size 0.7 0.7)
					(thickness 0.15)
				)
				(justify left bottom mirror)
			)
		)
		(fp_text user "Author: Antmicro"
			(at -0.4 -3.901 180)
			(layer "B.Fab")
			(hide yes)
			(effects
				(font
					(size 0.7 0.7)
					(thickness 0.15)
				)
				(justify left bottom mirror)
			)
		)
		(fp_text user "License: Apache-2.0"
			(at -0.4 -5.101 180)
			(layer "B.Fab")
			(hide yes)
			(effects
				(font
					(size 0.7 0.7)
					(thickness 0.15)
				)
				(justify left bottom mirror)
			)
		)
		(pad "1" smd circle
			(at 0 0)
			(size 0.75 0.75)
			(layers "B.Cu" "B.Mask")
			(net 394 "/USB Debug, DP/PDC_I2C2_IRQn")
			(pinfunction "1")
			(pintype "passive")
		)
	)
	(footprint "antmicro-footprints:SOD-523"
		(layer "B.Cu")
		(at 68.85 97.71 180)
		(property "Reference" "D35"
			(at -0.89 -1.48 0)
			(layer "B.SilkS")
			(effects
				(font
					(size 0.7 0.7)
					(thickness 0.15)
				)
				(justify left bottom mirror)
			)
		)
		(property "Value" "RB521S30T1G"
			(at 0 -1.499 0)
			(layer "B.Fab")
			(effects
				(font
					(size 0.7 0.7)
					(thickness 0.15)
				)
				(justify left bottom mirror)
			)
		)
		(property "Footprint" "antmicro-footprints:SOD-523"
			(at 0 0 180)
			(layer "F.Fab")
			(hide yes)
			(effects
				(font
					(size 1.27 1.27)
					(thickness 0.15)
				)
			)
		)
		(property "Datasheet" "https://www.onsemi.com/pdf/datasheet/rb521s30t1-d.pdf"
			(at 0 0 180)
			(layer "F.Fab")
			(hide yes)
			(effects
				(font
					(size 1.27 1.27)
					(thickness 0.15)
				)
			)
		)
		(property "Author" "Antmicro"
			(at 137.7 195.42 0)
			(layer "B.Fab")
			(hide yes)
			(effects
				(font
					(size 1 1)
					(thickness 0.15)
				)
				(justify mirror)
			)
		)
		(property "License" "Apache-2.0"
			(at 137.7 195.42 0)
			(layer "B.Fab")
			(hide yes)
			(effects
				(font
					(size 1 1)
					(thickness 0.15)
				)
				(justify mirror)
			)
		)
		(property "MPN" "RB521S30T1G"
			(at 137.7 195.42 0)
			(layer "B.Fab")
			(hide yes)
			(effects
				(font
					(size 1 1)
					(thickness 0.15)
				)
				(justify mirror)
			)
		)
		(property "Manufacturer" "ON Semiconductor"
			(at 137.7 195.42 0)
			(layer "B.Fab")
			(hide yes)
			(effects
				(font
					(size 1 1)
					(thickness 0.15)
				)
				(justify mirror)
			)
		)
		(sheetname "USB Debug, DP")
		(sheetfile "usb.kicad_sch")
		(attr smd)
		(fp_line
			(start -0.35 -0.5)
			(end -0.35 0.5)
			(stroke
				(width 0.15)
				(type solid)
			)
			(layer "B.SilkS")
		)
		(fp_rect
			(start -1 0.6)
			(end 1 -0.6)
			(stroke
				(width 0.05)
				(type solid)
			)
			(fill none)
			(layer "B.CrtYd")
		)
		(fp_line
			(start 0.65 0.425)
			(end -0.652 0.425)
			(stroke
				(width 0.15)
				(type solid)
			)
			(layer "B.Fab")
		)
		(fp_line
			(start 0.65 -0.423)
			(end 0.65 0.425)
			(stroke
				(width 0.15)
				(type solid)
			)
			(layer "B.Fab")
		)
		(fp_line
			(start 0.65 -0.423)
			(end -0.652 -0.423)
			(stroke
				(width 0.15)
				(type solid)
			)
			(layer "B.Fab")
		)
		(fp_line
			(start -0.35 -0.4)
			(end -0.35 0.4)
			(stroke
				(width 0.15)
				(type solid)
			)
			(layer "B.Fab")
		)
		(fp_line
			(start -0.652 0.425)
			(end -0.652 -0.423)
			(stroke
				(width 0.15)
				(type solid)
			)
			(layer "B.Fab")
		)
		(fp_text user "${REFERENCE}"
			(at -1.276 -3.499 0)
			(layer "B.Fab")
			(hide yes)
			(effects
				(font
					(size 0.7 0.7)
					(thickness 0.15)
				)
				(justify left bottom mirror)
			)
		)
		(fp_text user "License: Apache-2.0"
			(at -1.276 -5.9 0)
			(layer "B.Fab")
			(hide yes)
			(effects
				(font
					(size 0.7 0.7)
					(thickness 0.15)
				)
				(justify left bottom mirror)
			)
		)
		(fp_text user "Author: Antmicro"
			(at -1.276 -4.7 0)
			(layer "B.Fab")
			(hide yes)
			(effects
				(font
					(size 0.7 0.7)
					(thickness 0.15)
				)
				(justify left bottom mirror)
			)
		)
		(pad "1" smd roundrect
			(at -0.701 0 180)
			(size 0.5 0.6)
			(layers "B.Cu" "B.Paste" "B.Mask")
			(roundrect_rratio 0.25)
			(net 98 "EEPROM_PWR")
			(pinfunction "C")
			(pintype "passive")
		)
		(pad "2" smd roundrect
			(at 0.699 0 180)
			(size 0.5 0.6)
			(layers "B.Cu" "B.Paste" "B.Mask")
			(roundrect_rratio 0.25)
			(net 134 "/USB Debug, DP/PDC_LDO_3V3")
			(pinfunction "A")
			(pintype "passive")
		)
	)
	(footprint "antmicro-footprints:R_0402_1005Metric"
		(layer "B.Cu")
		(at 102.7 76.7 180)
		(descr "Resistor SMD 0402")
		(tags "resistor SMD 0402")
		(property "Reference" "R206"
			(at -3.7 -0.45 0)
			(layer "B.SilkS")
			(effects
				(font
					(size 0.7 0.7)
					(thickness 0.15)
				)
				(justify left bottom mirror)
			)
		)
		(property "Value" "R_470R_0402"
			(at 0 -1.4 0)
			(layer "B.Fab")
			(effects
				(font
					(size 0.7 0.7)
					(thickness 0.15)
				)
				(justify left bottom mirror)
			)
		)
		(property "Footprint" "antmicro-footprints:R_0402_1005Metric"
			(at 0 0 180)
			(layer "F.Fab")
			(hide yes)
			(effects
				(font
					(size 1.27 1.27)
					(thickness 0.15)
				)
			)
		)
		(property "Datasheet" "https://www.bourns.com/docs/product-datasheets/cr.pdf"
			(at 0 0 180)
			(layer "F.Fab")
			(hide yes)
			(effects
				(font
					(size 1.27 1.27)
					(thickness 0.15)
				)
			)
		)
		(property "Author" "Antmicro"
			(at 205.4 153.4 0)
			(layer "B.Fab")
			(hide yes)
			(effects
				(font
					(size 1 1)
					(thickness 0.15)
				)
				(justify mirror)
			)
		)
		(property "License" "Apache-2.0"
			(at 205.4 153.4 0)
			(layer "B.Fab")
			(hide yes)
			(effects
				(font
					(size 1 1)
					(thickness 0.15)
				)
				(justify mirror)
			)
		)
		(property "MPN" "CR0402-FX-4700GLF"
			(at 205.4 153.4 0)
			(layer "B.Fab")
			(hide yes)
			(effects
				(font
					(size 1 1)
					(thickness 0.15)
				)
				(justify mirror)
			)
		)
		(property "Manufacturer" "Bourns"
			(at 205.4 153.4 0)
			(layer "B.Fab")
			(hide yes)
			(effects
				(font
					(size 1 1)
					(thickness 0.15)
				)
				(justify mirror)
			)
		)
		(property "Tolerance" "1%"
			(at 205.4 153.4 0)
			(layer "B.Fab")
			(hide yes)
			(effects
				(font
					(size 1 1)
					(thickness 0.15)
				)
				(justify mirror)
			)
		)
		(property "Val" "470R"
			(at 205.4 153.4 0)
			(layer "B.Fab")
			(hide yes)
			(effects
				(font
					(size 1 1)
					(thickness 0.15)
				)
				(justify mirror)
			)
		)
		(sheetname "CSI")
		(sheetfile "csi.kicad_sch")
		(attr smd)
		(fp_rect
			(start -0.925 0.47)
			(end 0.925 -0.47)
			(stroke
				(width 0.05)
				(type default)
			)
			(fill none)
			(layer "B.CrtYd")
		)
		(fp_rect
			(start -0.5 0.25)
			(end 0.5 -0.25)
			(stroke
				(width 0.15)
				(type solid)
			)
			(fill none)
			(layer "B.Fab")
		)
		(fp_text user "${REFERENCE}"
			(at -0.95 -3.168 0)
			(layer "B.Fab")
			(hide yes)
			(effects
				(font
					(size 0.7 0.7)
					(thickness 0.15)
				)
				(justify left bottom mirror)
			)
		)
		(fp_text user "License: Apache-2.0"
			(at -0.95 -5.169 0)
			(layer "B.Fab")
			(hide yes)
			(effects
				(font
					(size 0.7 0.7)
					(thickness 0.15)
				)
				(justify left bottom mirror)
			)
		)
		(fp_text user "Author: Antmicro"
			(at -0.95 -4.169 0)
			(layer "B.Fab")
			(hide yes)
			(effects
				(font
					(size 0.7 0.7)
					(thickness 0.15)
				)
				(justify left bottom mirror)
			)
		)
		(pad "1" smd roundrect
			(at -0.48 0 180)
			(size 0.59 0.64)
			(layers "B.Cu" "B.Paste" "B.Mask")
			(roundrect_rratio 0.25)
			(net 162 "Net-(D25-A)")
			(pintype "passive")
		)
		(pad "2" smd roundrect
			(at 0.48 0 180)
			(size 0.59 0.64)
			(layers "B.Cu" "B.Paste" "B.Mask")
			(roundrect_rratio 0.25)
			(net 111 "/CSI/CSIB_5V")
			(pintype "passive")
		)
	)
	(footprint "antmicro-footprints:TP_SMD_0.75mm"
		(layer "B.Cu")
		(at 68.165 127.57 180)
		(property "Reference" "TP23"
			(at -1.3 0.55 0)
			(layer "B.SilkS")
			(hide yes)
			(effects
				(font
					(size 0.7 0.7)
					(thickness 0.15)
				)
				(justify left bottom mirror)
			)
		)
		(property "Value" "TP_0.75mm_SMD"
			(at 0 -1.2 0)
			(layer "B.Fab")
			(effects
				(font
					(size 0.7 0.7)
					(thickness 0.15)
				)
				(justify left bottom mirror)
			)
		)
		(property "Footprint" "antmicro-footprints:TP_SMD_0.75mm"
			(at 0 0 180)
			(layer "F.Fab")
			(hide yes)
			(effects
				(font
					(size 1.27 1.27)
					(thickness 0.15)
				)
			)
		)
		(property "Author" "Antmicro"
			(at 136.33 255.14 0)
			(layer "B.Fab")
			(hide yes)
			(effects
				(font
					(size 1 1)
					(thickness 0.15)
				)
				(justify mirror)
			)
		)
		(property "License" "Apache-2.0"
			(at 136.33 255.14 0)
			(layer "B.Fab")
			(hide yes)
			(effects
				(font
					(size 1 1)
					(thickness 0.15)
				)
				(justify mirror)
			)
		)
		(property "MPN" ""
			(at 136.33 255.14 0)
			(layer "B.Fab")
			(hide yes)
			(effects
				(font
					(size 1 1)
					(thickness 0.15)
				)
				(justify mirror)
			)
		)
		(property "Manufacturer" ""
			(at 136.33 255.14 0)
			(layer "B.Fab")
			(hide yes)
			(effects
				(font
					(size 1 1)
					(thickness 0.15)
				)
				(justify mirror)
			)
		)
		(sheetname "Supply")
		(sheetfile "supply.kicad_sch")
		(attr exclude_from_pos_files exclude_from_bom)
		(fp_circle
			(center 0 0)
			(end 0.475 0)
			(stroke
				(width 0.05)
				(type default)
			)
			(fill none)
			(layer "B.CrtYd")
		)
		(fp_text user "License: Apache-2.0"
			(at -0.4 -5.101 0)
			(layer "B.Fab")
			(hide yes)
			(effects
				(font
					(size 0.7 0.7)
					(thickness 0.15)
				)
				(justify left bottom mirror)
			)
		)
		(fp_text user "${REFERENCE}"
			(at -0.4 -2.7 0)
			(layer "B.Fab")
			(hide yes)
			(effects
				(font
					(size 0.7 0.7)
					(thickness 0.15)
				)
				(justify left bottom mirror)
			)
		)
		(fp_text user "Author: Antmicro"
			(at -0.4 -3.901 0)
			(layer "B.Fab")
			(hide yes)
			(effects
				(font
					(size 0.7 0.7)
					(thickness 0.15)
				)
				(justify left bottom mirror)
			)
		)
		(pad "1" smd circle
			(at 0 0 180)
			(size 0.75 0.75)
			(layers "B.Cu" "B.Mask")
			(net 1 "GND")
			(pinfunction "1")
			(pintype "passive")
		)
	)
	(footprint "antmicro-footprints:SOD-523"
		(layer "B.Cu")
		(at 56.6 78.8)
		(property "Reference" "D37"
			(at 20.01 9.2 0)
			(layer "B.SilkS")
			(effects
				(font
					(size 0.7 0.7)
					(thickness 0.15)
				)
				(justify right bottom mirror)
			)
		)
		(property "Value" "RB521S30T1G"
			(at 0 -1.499 0)
			(layer "B.Fab")
			(effects
				(font
					(size 0.7 0.7)
					(thickness 0.15)
				)
				(justify right bottom mirror)
			)
		)
		(property "Footprint" "antmicro-footprints:SOD-523"
			(at 0 0 0)
			(layer "F.Fab")
			(hide yes)
			(effects
				(font
					(size 1.27 1.27)
					(thickness 0.15)
				)
			)
		)
		(property "Datasheet" "https://www.onsemi.com/pdf/datasheet/rb521s30t1-d.pdf"
			(at 0 0 0)
			(layer "F.Fab")
			(hide yes)
			(effects
				(font
					(size 1.27 1.27)
					(thickness 0.15)
				)
			)
		)
		(property "Author" "Antmicro"
			(at 0 0 0)
			(layer "B.Fab")
			(hide yes)
			(effects
				(font
					(size 1 1)
					(thickness 0.15)
				)
				(justify mirror)
			)
		)
		(property "License" "Apache-2.0"
			(at 0 0 0)
			(layer "B.Fab")
			(hide yes)
			(effects
				(font
					(size 1 1)
					(thickness 0.15)
				)
				(justify mirror)
			)
		)
		(property "MPN" "RB521S30T1G"
			(at 0 0 0)
			(layer "B.Fab")
			(hide yes)
			(effects
				(font
					(size 1 1)
					(thickness 0.15)
				)
				(justify mirror)
			)
		)
		(property "Manufacturer" "ON Semiconductor"
			(at 0 0 0)
			(layer "B.Fab")
			(hide yes)
			(effects
				(font
					(size 1 1)
					(thickness 0.15)
				)
				(justify mirror)
			)
		)
		(sheetname "Supply")
		(sheetfile "supply.kicad_sch")
		(attr smd)
		(fp_line
			(start -0.35 -0.5)
			(end -0.35 0.5)
			(stroke
				(width 0.15)
				(type solid)
			)
			(layer "B.SilkS")
		)
		(fp_rect
			(start -1 0.6)
			(end 1 -0.6)
			(stroke
				(width 0.05)
				(type solid)
			)
			(fill none)
			(layer "B.CrtYd")
		)
		(fp_line
			(start -0.652 0.425)
			(end -0.652 -0.423)
			(stroke
				(width 0.15)
				(type solid)
			)
			(layer "B.Fab")
		)
		(fp_line
			(start -0.35 -0.4)
			(end -0.35 0.4)
			(stroke
				(width 0.15)
				(type solid)
			)
			(layer "B.Fab")
		)
		(fp_line
			(start 0.65 -0.423)
			(end -0.652 -0.423)
			(stroke
				(width 0.15)
				(type solid)
			)
			(layer "B.Fab")
		)
		(fp_line
			(start 0.65 -0.423)
			(end 0.65 0.425)
			(stroke
				(width 0.15)
				(type solid)
			)
			(layer "B.Fab")
		)
		(fp_line
			(start 0.65 0.425)
			(end -0.652 0.425)
			(stroke
				(width 0.15)
				(type solid)
			)
			(layer "B.Fab")
		)
		(fp_text user "Author: Antmicro"
			(at -1.276 -4.7 0)
			(layer "B.Fab")
			(hide yes)
			(effects
				(font
					(size 0.7 0.7)
					(thickness 0.15)
				)
				(justify right bottom mirror)
			)
		)
		(fp_text user "${REFERENCE}"
			(at -1.276 -3.499 0)
			(layer "B.Fab")
			(hide yes)
			(effects
				(font
					(size 0.7 0.7)
					(thickness 0.15)
				)
				(justify right bottom mirror)
			)
		)
		(fp_text user "License: Apache-2.0"
			(at -1.276 -5.9 0)
			(layer "B.Fab")
			(hide yes)
			(effects
				(font
					(size 0.7 0.7)
					(thickness 0.15)
				)
				(justify right bottom mirror)
			)
		)
		(pad "1" smd roundrect
			(at -0.701 0)
			(size 0.5 0.6)
			(layers "B.Cu" "B.Paste" "B.Mask")
			(roundrect_rratio 0.25)
			(net 342 "Net-(D37-C)")
			(pinfunction "C")
			(pintype "passive")
		)
		(pad "2" smd roundrect
			(at 0.699 0)
			(size 0.5 0.6)
			(layers "B.Cu" "B.Paste" "B.Mask")
			(roundrect_rratio 0.25)
			(net 629 "Net-(D37-A)")
			(pinfunction "A")
			(pintype "passive")
		)
	)
	(footprint "antmicro-footprints:R_0402_1005Metric"
		(layer "B.Cu")
		(at 41.2 119.3 90)
		(descr "Resistor SMD 0402")
		(tags "resistor SMD 0402")
		(property "Reference" "R152"
			(at 3.68 0.4 -90)
			(layer "B.SilkS")
			(effects
				(font
					(size 0.7 0.7)
					(thickness 0.15)
				)
				(justify left bottom mirror)
			)
		)
		(property "Value" "R_200R_0402"
			(at 0 -1.4 -90)
			(layer "B.Fab")
			(effects
				(font
					(size 0.7 0.7)
					(thickness 0.15)
				)
				(justify left bottom mirror)
			)
		)
		(property "Footprint" "antmicro-footprints:R_0402_1005Metric"
			(at 0 0 90)
			(layer "F.Fab")
			(hide yes)
			(effects
				(font
					(size 1.27 1.27)
					(thickness 0.15)
				)
			)
		)
		(property "Datasheet" "https://www.bourns.com/docs/product-datasheets/cr.pdf"
			(at 0 0 90)
			(layer "F.Fab")
			(hide yes)
			(effects
				(font
					(size 1.27 1.27)
					(thickness 0.15)
				)
			)
		)
		(property "Author" "Antmicro"
			(at 160.5 78.1 0)
			(layer "B.Fab")
			(hide yes)
			(effects
				(font
					(size 1 1)
					(thickness 0.15)
				)
				(justify mirror)
			)
		)
		(property "License" "Apache-2.0"
			(at 160.5 78.1 0)
			(layer "B.Fab")
			(hide yes)
			(effects
				(font
					(size 1 1)
					(thickness 0.15)
				)
				(justify mirror)
			)
		)
		(property "MPN" "CR0402-FX-2000GLF"
			(at 160.5 78.1 0)
			(layer "B.Fab")
			(hide yes)
			(effects
				(font
					(size 1 1)
					(thickness 0.15)
				)
				(justify mirror)
			)
		)
		(property "Manufacturer" "Bourns"
			(at 160.5 78.1 0)
			(layer "B.Fab")
			(hide yes)
			(effects
				(font
					(size 1 1)
					(thickness 0.15)
				)
				(justify mirror)
			)
		)
		(property "Tolerance" "1%"
			(at 160.5 78.1 0)
			(layer "B.Fab")
			(hide yes)
			(effects
				(font
					(size 1 1)
					(thickness 0.15)
				)
				(justify mirror)
			)
		)
		(property "Val" "200R"
			(at 160.5 78.1 0)
			(layer "B.Fab")
			(hide yes)
			(effects
				(font
					(size 1 1)
					(thickness 0.15)
				)
				(justify mirror)
			)
		)
		(sheetname "Ethernet")
		(sheetfile "ethernet.kicad_sch")
		(attr smd)
		(fp_rect
			(start -0.925 0.47)
			(end 0.925 -0.47)
			(stroke
				(width 0.05)
				(type default)
			)
			(fill none)
			(layer "B.CrtYd")
		)
		(fp_rect
			(start -0.5 0.25)
			(end 0.5 -0.25)
			(stroke
				(width 0.15)
				(type solid)
			)
			(fill none)
			(layer "B.Fab")
		)
		(fp_text user "License: Apache-2.0"
			(at -0.95 -5.169 -90)
			(layer "B.Fab")
			(hide yes)
			(effects
				(font
					(size 0.7 0.7)
					(thickness 0.15)
				)
				(justify left bottom mirror)
			)
		)
		(fp_text user "${REFERENCE}"
			(at -0.95 -3.168 -90)
			(layer "B.Fab")
			(hide yes)
			(effects
				(font
					(size 0.7 0.7)
					(thickness 0.15)
				)
				(justify left bottom mirror)
			)
		)
		(fp_text user "Author: Antmicro"
			(at -0.95 -4.169 -90)
			(layer "B.Fab")
			(hide yes)
			(effects
				(font
					(size 0.7 0.7)
					(thickness 0.15)
				)
				(justify left bottom mirror)
			)
		)
		(pad "1" smd roundrect
			(at -0.48 0 90)
			(size 0.59 0.64)
			(layers "B.Cu" "B.Paste" "B.Mask")
			(roundrect_rratio 0.25)
			(net 551 "Net-(J6-LED_GRN-)")
			(pintype "passive")
		)
		(pad "2" smd roundrect
			(at 0.48 0 90)
			(size 0.59 0.64)
			(layers "B.Cu" "B.Paste" "B.Mask")
			(roundrect_rratio 0.25)
			(net 457 "GBE_LED_LINK")
			(pintype "passive")
		)
	)
	(footprint "antmicro-footprints:R_0402_1005Metric"
		(layer "B.Cu")
		(at 96.49 99.575 180)
		(descr "Resistor SMD 0402")
		(tags "resistor SMD 0402")
		(property "Reference" "R167"
			(at 1.63 1.575 -90)
			(layer "B.SilkS")
			(effects
				(font
					(size 0.7 0.7)
					(thickness 0.15)
				)
				(justify left bottom mirror)
			)
		)
		(property "Value" "R_0R_0402"
			(at 0 -1.4 0)
			(layer "B.Fab")
			(effects
				(font
					(size 0.7 0.7)
					(thickness 0.15)
				)
				(justify left bottom mirror)
			)
		)
		(property "Footprint" "antmicro-footprints:R_0402_1005Metric"
			(at 0 0 180)
			(layer "F.Fab")
			(hide yes)
			(effects
				(font
					(size 1.27 1.27)
					(thickness 0.15)
				)
			)
		)
		(property "Datasheet" "https://industrial.panasonic.com/cdbs/www-data/pdf/RDA0000/AOA0000C301.pdf"
			(at 0 0 180)
			(layer "F.Fab")
			(hide yes)
			(effects
				(font
					(size 1.27 1.27)
					(thickness 0.15)
				)
			)
		)
		(property "Author" "Antmicro"
			(at 192.98 199.15 0)
			(layer "B.Fab")
			(hide yes)
			(effects
				(font
					(size 1 1)
					(thickness 0.15)
				)
				(justify mirror)
			)
		)
		(property "Current" "1A"
			(at 192.98 199.15 0)
			(layer "B.Fab")
			(hide yes)
			(effects
				(font
					(size 1 1)
					(thickness 0.15)
				)
				(justify mirror)
			)
		)
		(property "License" "Apache-2.0"
			(at 192.98 199.15 0)
			(layer "B.Fab")
			(hide yes)
			(effects
				(font
					(size 1 1)
					(thickness 0.15)
				)
				(justify mirror)
			)
		)
		(property "MPN" "ERJ2GE0R00X"
			(at 192.98 199.15 0)
			(layer "B.Fab")
			(hide yes)
			(effects
				(font
					(size 1 1)
					(thickness 0.15)
				)
				(justify mirror)
			)
		)
		(property "Manufacturer" "Panasonic"
			(at 192.98 199.15 0)
			(layer "B.Fab")
			(hide yes)
			(effects
				(font
					(size 1 1)
					(thickness 0.15)
				)
				(justify mirror)
			)
		)
		(property "Tolerance" ""
			(at 192.98 199.15 0)
			(layer "B.Fab")
			(hide yes)
			(effects
				(font
					(size 1 1)
					(thickness 0.15)
				)
				(justify mirror)
			)
		)
		(property "Val" "0R"
			(at 192.98 199.15 0)
			(layer "B.Fab")
			(hide yes)
			(effects
				(font
					(size 1 1)
					(thickness 0.15)
				)
				(justify mirror)
			)
		)
		(sheetname "CSI")
		(sheetfile "csi.kicad_sch")
		(attr smd exclude_from_pos_files exclude_from_bom dnp)
		(fp_rect
			(start -0.925 0.47)
			(end 0.925 -0.47)
			(stroke
				(width 0.05)
				(type default)
			)
			(fill none)
			(layer "B.CrtYd")
		)
		(fp_rect
			(start -0.5 0.25)
			(end 0.5 -0.25)
			(stroke
				(width 0.15)
				(type solid)
			)
			(fill none)
			(layer "B.Fab")
		)
		(fp_text user "License: Apache-2.0"
			(at -0.95 -5.169 0)
			(layer "B.Fab")
			(hide yes)
			(effects
				(font
					(size 0.7 0.7)
					(thickness 0.15)
				)
				(justify left bottom mirror)
			)
		)
		(fp_text user "Author: Antmicro"
			(at -0.95 -4.169 0)
			(layer "B.Fab")
			(hide yes)
			(effects
				(font
					(size 0.7 0.7)
					(thickness 0.15)
				)
				(justify left bottom mirror)
			)
		)
		(fp_text user "${REFERENCE}"
			(at -0.95 -3.168 0)
			(layer "B.Fab")
			(hide yes)
			(effects
				(font
					(size 0.7 0.7)
					(thickness 0.15)
				)
				(justify left bottom mirror)
			)
		)
		(pad "1" smd roundrect
			(at -0.48 0 180)
			(size 0.59 0.64)
			(layers "B.Cu" "B.Paste" "B.Mask")
			(roundrect_rratio 0.25)
			(net 325 "/CSI/I2C_MUX_A0")
			(pintype "passive")
		)
		(pad "2" smd roundrect
			(at 0.48 0 180)
			(size 0.59 0.64)
			(layers "B.Cu" "B.Paste" "B.Mask")
			(roundrect_rratio 0.25)
			(net 112 "+1V8")
			(pintype "passive")
		)
	)
	(footprint "antmicro-footprints:R_Array_4x0201_Panasonic_EXB18V"
		(layer "B.Cu")
		(at 123.08 74.36 90)
		(property "Reference" "R103"
			(at -0.94 1.52 -90)
			(layer "B.SilkS")
			(effects
				(font
					(size 0.7 0.7)
					(thickness 0.15)
				)
				(justify right bottom mirror)
			)
		)
		(property "Value" "R_4x0R_0201_array"
			(at -1.1 -1.8 -90)
			(layer "B.Fab")
			(effects
				(font
					(size 0.7 0.7)
					(thickness 0.15)
				)
				(justify left bottom mirror)
			)
		)
		(property "Footprint" "antmicro-footprints:R_Array_4x0201_Panasonic_EXB18V"
			(at 0 0 90)
			(layer "F.Fab")
			(hide yes)
			(effects
				(font
					(size 1.27 1.27)
					(thickness 0.15)
				)
			)
		)
		(property "Datasheet" "http://industrial.panasonic.com/cdbs/www-data/pdf/AOC0000/AOC0000C14.pdf"
			(at 0 0 90)
			(layer "F.Fab")
			(hide yes)
			(effects
				(font
					(size 1.27 1.27)
					(thickness 0.15)
				)
			)
		)
		(property "Author" "Antmicro"
			(at 197.44 -48.72 0)
			(layer "B.Fab")
			(hide yes)
			(effects
				(font
					(size 1 1)
					(thickness 0.15)
				)
				(justify mirror)
			)
		)
		(property "License" "Apache-2.0"
			(at 197.44 -48.72 0)
			(layer "B.Fab")
			(hide yes)
			(effects
				(font
					(size 1 1)
					(thickness 0.15)
				)
				(justify mirror)
			)
		)
		(property "MPN" "EXB-18VR000X"
			(at 197.44 -48.72 0)
			(layer "B.Fab")
			(hide yes)
			(effects
				(font
					(size 1 1)
					(thickness 0.15)
				)
				(justify mirror)
			)
		)
		(property "Manufacturer" "Panasonic"
			(at 197.44 -48.72 0)
			(layer "B.Fab")
			(hide yes)
			(effects
				(font
					(size 1 1)
					(thickness 0.15)
				)
				(justify mirror)
			)
		)
		(property "Val" "4x0R_0201"
			(at 197.44 -48.72 0)
			(layer "B.Fab")
			(hide yes)
			(effects
				(font
					(size 1 1)
					(thickness 0.15)
				)
				(justify mirror)
			)
		)
		(sheetname "CSI")
		(sheetfile "csi.kicad_sch")
		(attr smd exclude_from_pos_files exclude_from_bom dnp)
		(fp_line
			(start 0.8 -0.45)
			(end 0.8 0.45)
			(stroke
				(width 0.12)
				(type solid)
			)
			(layer "B.SilkS")
		)
		(fp_line
			(start -0.8 -0.45)
			(end -0.8 0.45)
			(stroke
				(width 0.12)
				(type solid)
			)
			(layer "B.SilkS")
		)
		(fp_rect
			(start -0.898 0.66)
			(end 0.898 -0.65)
			(stroke
				(width 0.05)
				(type solid)
			)
			(fill none)
			(layer "B.CrtYd")
		)
		(fp_text user "License: Apache-2.0"
			(at -1.051 -6 -90)
			(layer "B.Fab")
			(hide yes)
			(effects
				(font
					(size 0.7 0.7)
					(thickness 0.15)
				)
				(justify left bottom mirror)
			)
		)
		(fp_text user "${REFERENCE}"
			(at -1.051 -3.2 -90)
			(layer "B.Fab")
			(hide yes)
			(effects
				(font
					(size 0.7 0.7)
					(thickness 0.15)
				)
				(justify left bottom mirror)
			)
		)
		(fp_text user "Author: Antmicro"
			(at -1.051 -4.599 -90)
			(layer "B.Fab")
			(hide yes)
			(effects
				(font
					(size 0.7 0.7)
					(thickness 0.15)
				)
				(justify left bottom mirror)
			)
		)
		(pad "1" smd roundrect
			(at -0.6 -0.298 90)
			(size 0.2 0.4)
			(layers "B.Cu" "B.Paste" "B.Mask")
			(roundrect_rratio 0.25)
			(net 4 "CSI1_D0_P")
			(pinfunction "R1.1")
			(pintype "passive")
		)
		(pad "2" smd roundrect
			(at -0.202 -0.298 90)
			(size 0.2 0.4)
			(layers "B.Cu" "B.Paste" "B.Mask")
			(roundrect_rratio 0.25)
			(net 2 "CSI1_D0_N")
			(pinfunction "R2.1")
			(pintype "passive")
		)
		(pad "3" smd roundrect
			(at 0.2 -0.298 90)
			(size 0.2 0.4)
			(layers "B.Cu" "B.Paste" "B.Mask")
			(roundrect_rratio 0.25)
			(net 12 "CSI1_D1_P")
			(pinfunction "R3.1")
			(pintype "passive")
		)
		(pad "4" smd roundrect
			(at 0.598 -0.298 90)
			(size 0.2 0.4)
			(layers "B.Cu" "B.Paste" "B.Mask")
			(roundrect_rratio 0.25)
			(net 10 "CSI1_D1_N")
			(pinfunction "R4.1")
			(pintype "passive")
		)
		(pad "5" smd roundrect
			(at 0.598 0.3 90)
			(size 0.2 0.4)
			(layers "B.Cu" "B.Paste" "B.Mask")
			(roundrect_rratio 0.25)
			(net 204 "/CSI/CSI1_0_D1_N")
			(pinfunction "R4.2")
			(pintype "passive")
		)
		(pad "6" smd roundrect
			(at 0.2 0.3 90)
			(size 0.2 0.4)
			(layers "B.Cu" "B.Paste" "B.Mask")
			(roundrect_rratio 0.25)
			(net 205 "/CSI/CSI1_0_D1_P")
			(pinfunction "R3.2")
			(pintype "passive")
		)
		(pad "7" smd roundrect
			(at -0.202 0.3 90)
			(size 0.2 0.4)
			(layers "B.Cu" "B.Paste" "B.Mask")
			(roundrect_rratio 0.25)
			(net 206 "/CSI/CSI1_0_D0_N")
			(pinfunction "R2.2")
			(pintype "passive")
		)
		(pad "8" smd roundrect
			(at -0.6 0.3 90)
			(size 0.2 0.4)
			(layers "B.Cu" "B.Paste" "B.Mask")
			(roundrect_rratio 0.25)
			(net 207 "/CSI/CSI1_0_D0_P")
			(pinfunction "R1.2")
			(pintype "passive")
		)
	)
	(footprint "antmicro-footprints:LED_0603_1608Metric_G"
		(layer "B.Cu")
		(at 47.1 126.95)
		(descr "LED SMD 0603 Green")
		(tags "LED SMD 0603 Green")
		(property "Reference" "D2"
			(at -7.4 1.27 0)
			(layer "B.SilkS")
			(effects
				(font
					(size 0.7 0.7)
					(thickness 0.15)
				)
				(justify right bottom mirror)
			)
		)
		(property "Value" "LED_G_0603_LTST-C190GKT"
			(at -0.001 -1.599 0)
			(layer "B.Fab")
			(effects
				(font
					(size 0.7 0.7)
					(thickness 0.15)
				)
				(justify right bottom mirror)
			)
		)
		(property "Footprint" "antmicro-footprints:LED_0603_1608Metric_G"
			(at 0 0 0)
			(layer "F.Fab")
			(hide yes)
			(effects
				(font
					(size 1.27 1.27)
					(thickness 0.15)
				)
			)
		)
		(property "Datasheet" "https://media.digikey.com/pdf/Data%20Sheets/Lite-On%20PDFs/LTST-C190GKT.pdf"
			(at 0 0 0)
			(layer "F.Fab")
			(hide yes)
			(effects
				(font
					(size 1.27 1.27)
					(thickness 0.15)
				)
			)
		)
		(property "Author" "Antmicro"
			(at 0 0 0)
			(layer "B.Fab")
			(hide yes)
			(effects
				(font
					(size 1 1)
					(thickness 0.15)
				)
				(justify mirror)
			)
		)
		(property "Color" "Green"
			(at 0 0 0)
			(layer "B.Fab")
			(hide yes)
			(effects
				(font
					(size 1 1)
					(thickness 0.15)
				)
				(justify mirror)
			)
		)
		(property "License" "Apache-2.0"
			(at 0 0 0)
			(layer "B.Fab")
			(hide yes)
			(effects
				(font
					(size 1 1)
					(thickness 0.15)
				)
				(justify mirror)
			)
		)
		(property "MPN" "LTST-C190GKT"
			(at 0 0 0)
			(layer "B.Fab")
			(hide yes)
			(effects
				(font
					(size 1 1)
					(thickness 0.15)
				)
				(justify mirror)
			)
		)
		(property "Manufacturer" "Lite-On"
			(at 0 0 0)
			(layer "B.Fab")
			(hide yes)
			(effects
				(font
					(size 1 1)
					(thickness 0.15)
				)
				(justify mirror)
			)
		)
		(sheetname "USB Debug, DP")
		(sheetfile "usb.kicad_sch")
		(attr smd)
		(fp_line
			(start -1.18 -0.321)
			(end -1.18 0.319)
			(stroke
				(width 0.15)
				(type solid)
			)
			(layer "B.SilkS")
		)
		(fp_line
			(start -0.24 -0.001008)
			(end -0.094672 -0.001008)
			(stroke
				(width 0.1)
				(type solid)
			)
			(layer "B.SilkS")
		)
		(fp_line
			(start -0.22 -0.35)
			(end 0.22 -0.35)
			(stroke
				(width 0.15)
				(type solid)
			)
			(layer "B.SilkS")
		)
		(fp_line
			(start -0.22 0.35)
			(end 0.22 0.35)
			(stroke
				(width 0.15)
				(type solid)
			)
			(layer "B.SilkS")
		)
		(fp_line
			(start -0.094672 -0.001008)
			(end 0.105328 -0.201008)
			(stroke
				(width 0.1)
				(type solid)
			)
			(layer "B.SilkS")
		)
		(fp_line
			(start -0.094672 0.198992)
			(end -0.094672 -0.201008)
			(stroke
				(width 0.1)
				(type solid)
			)
			(layer "B.SilkS")
		)
		(fp_line
			(start 0.105328 0.198992)
			(end -0.094672 -0.001008)
			(stroke
				(width 0.1)
				(type solid)
			)
			(layer "B.SilkS")
		)
		(fp_line
			(start 0.105328 0.198992)
			(end 0.105328 -0.201008)
			(stroke
				(width 0.1)
				(type solid)
			)
			(layer "B.SilkS")
		)
		(fp_line
			(start 0.24 -0.001)
			(end 0.105328 -0.001008)
			(stroke
				(width 0.1)
				(type solid)
			)
			(layer "B.SilkS")
		)
		(fp_rect
			(start 1.25 -0.65)
			(end -1.25 0.65)
			(stroke
				(width 0.05)
				(type solid)
			)
			(fill none)
			(layer "B.CrtYd")
		)
		(fp_line
			(start -0.597 0)
			(end -0.199 0)
			(stroke
				(width 0.15)
				(type solid)
			)
			(layer "B.Fab")
		)
		(fp_line
			(start -0.199 -0.1)
			(end -0.199 -0.2)
			(stroke
				(width 0.15)
				(type solid)
			)
			(layer "B.Fab")
		)
		(fp_line
			(start -0.199 -0.1)
			(end -0.199 0.202)
			(stroke
				(width 0.15)
				(type solid)
			)
			(layer "B.Fab")
		)
		(fp_line
			(start -0.101 0)
			(end 0.201 0.202)
			(stroke
				(width 0.15)
				(type solid)
			)
			(layer "B.Fab")
		)
		(fp_line
			(start 0.201 -0.2)
			(end -0.101 0)
			(stroke
				(width 0.15)
				(type solid)
			)
			(layer "B.Fab")
		)
		(fp_line
			(start 0.201 0)
			(end 0.201 -0.2)
			(stroke
				(width 0.15)
				(type solid)
			)
			(layer "B.Fab")
		)
		(fp_line
			(start 0.201 0)
			(end 0.599 0)
			(stroke
				(width 0.15)
				(type solid)
			)
			(layer "B.Fab")
		)
		(fp_line
			(start 0.201 0.202)
			(end 0.201 0)
			(stroke
				(width 0.15)
				(type solid)
			)
			(layer "B.Fab")
		)
		(fp_rect
			(start 0.848 -0.4)
			(end -0.85 0.402)
			(stroke
				(width 0.15)
				(type solid)
			)
			(fill none)
			(layer "B.Fab")
		)
		(fp_text user "Author: Antmicro"
			(at -1.4224 -4.799 0)
			(layer "B.Fab")
			(hide yes)
			(effects
				(font
					(size 0.7 0.7)
					(thickness 0.15)
				)
				(justify right bottom mirror)
			)
		)
		(fp_text user "${REFERENCE}"
			(at -1.4224 -5.999 0)
			(layer "B.Fab")
			(hide yes)
			(effects
				(font
					(size 0.7 0.7)
					(thickness 0.15)
				)
				(justify right bottom mirror)
			)
		)
		(fp_text user "License: Apache-2.0"
			(at -1.4224 -3.599 0)
			(layer "B.Fab")
			(hide yes)
			(effects
				(font
					(size 0.7 0.7)
					(thickness 0.15)
				)
				(justify right bottom mirror)
			)
		)
		(pad "1" smd roundrect
			(at -0.7 0 180)
			(size 0.8 1)
			(layers "B.Cu" "B.Paste" "B.Mask")
			(roundrect_rratio 0.2)
			(net 271 "/USB Debug, DP/FTDI_LED_TX")
			(pinfunction "C")
			(pintype "passive")
		)
		(pad "2" smd roundrect
			(at 0.7 0 180)
			(size 0.8 1)
			(layers "B.Cu" "B.Paste" "B.Mask")
			(roundrect_rratio 0.2)
			(net 142 "Net-(D2-A)")
			(pinfunction "A")
			(pintype "passive")
		)
	)
	(footprint "antmicro-footprints:VQFN-24-1EP_3.8x3.8x1.0mm_P0.5mm"
		(layer "B.Cu")
		(at 99.96 100.24 -90)
		(property "Reference" "U26"
			(at -2.52 0.07 180)
			(layer "B.SilkS")
			(effects
				(font
					(size 0.7 0.7)
					(thickness 0.15)
				)
				(justify left bottom mirror)
			)
		)
		(property "Value" "PI4MSD5V9548AZDEX"
			(at 0 -3.6 90)
			(layer "B.Fab")
			(effects
				(font
					(size 0.7 0.7)
					(thickness 0.15)
				)
				(justify right bottom mirror)
			)
		)
		(property "Footprint" "antmicro-footprints:VQFN-24-1EP_3.8x3.8x1.0mm_P0.5mm"
			(at 0 0 -90)
			(layer "F.Fab")
			(hide yes)
			(effects
				(font
					(size 1.27 1.27)
					(thickness 0.15)
				)
			)
		)
		(property "Datasheet" "https://www.mouser.com/datasheet/2/115/DIOD_S_A0003139195_1-2542233.pdf"
			(at 0 0 -90)
			(layer "F.Fab")
			(hide yes)
			(effects
				(font
					(size 1.27 1.27)
					(thickness 0.15)
				)
			)
		)
		(property "Author" "Antmicro"
			(at -0.28 200.2 0)
			(layer "B.Fab")
			(hide yes)
			(effects
				(font
					(size 1 1)
					(thickness 0.15)
				)
				(justify mirror)
			)
		)
		(property "License" "Apache-2.0"
			(at -0.28 200.2 0)
			(layer "B.Fab")
			(hide yes)
			(effects
				(font
					(size 1 1)
					(thickness 0.15)
				)
				(justify mirror)
			)
		)
		(property "MPN" "PI4MSD5V9548AZDEX"
			(at -0.28 200.2 0)
			(layer "B.Fab")
			(hide yes)
			(effects
				(font
					(size 1 1)
					(thickness 0.15)
				)
				(justify mirror)
			)
		)
		(property "Manufacturer" "Diodes Incorporated"
			(at -0.28 200.2 0)
			(layer "B.Fab")
			(hide yes)
			(effects
				(font
					(size 1 1)
					(thickness 0.15)
				)
				(justify mirror)
			)
		)
		(sheetname "CSI")
		(sheetfile "csi.kicad_sch")
		(attr smd)
		(fp_line
			(start -1.524 1.905)
			(end -1.905 1.524)
			(stroke
				(width 0.15)
				(type solid)
			)
			(layer "B.SilkS")
		)
		(fp_line
			(start 1.523 1.905)
			(end 1.904 1.905)
			(stroke
				(width 0.15)
				(type solid)
			)
			(layer "B.SilkS")
		)
		(fp_line
			(start 1.904 1.905)
			(end 1.904 1.524)
			(stroke
				(width 0.15)
				(type solid)
			)
			(layer "B.SilkS")
		)
		(fp_line
			(start 1.904 -1.523)
			(end 1.904 -1.904)
			(stroke
				(width 0.15)
				(type solid)
			)
			(layer "B.SilkS")
		)
		(fp_line
			(start -1.905 -1.904)
			(end -1.905 -1.523)
			(stroke
				(width 0.15)
				(type solid)
			)
			(layer "B.SilkS")
		)
		(fp_line
			(start -1.524 -1.904)
			(end -1.905 -1.904)
			(stroke
				(width 0.15)
				(type solid)
			)
			(layer "B.SilkS")
		)
		(fp_line
			(start 1.904 -1.904)
			(end 1.523 -1.904)
			(stroke
				(width 0.15)
				(type solid)
			)
			(layer "B.SilkS")
		)
		(fp_circle
			(center -2.2 2.2)
			(end -2.15 2.2)
			(stroke
				(width 0.15)
				(type solid)
			)
			(fill solid)
			(layer "B.SilkS")
		)
		(fp_rect
			(start -2.5 2.5)
			(end 2.5 -2.5)
			(stroke
				(width 0.05)
				(type solid)
			)
			(fill none)
			(layer "B.CrtYd")
		)
		(fp_line
			(start -1.524 1.905)
			(end -1.905 1.524)
			(stroke
				(width 0.15)
				(type solid)
			)
			(layer "B.Fab")
		)
		(fp_rect
			(start -1.905 -1.904)
			(end 1.904 1.905)
			(stroke
				(width 0.15)
				(type solid)
			)
			(fill none)
			(layer "B.Fab")
		)
		(fp_text user "License: Apache-2.0"
			(at -2.286 -7.32 90)
			(layer "B.Fab")
			(hide yes)
			(effects
				(font
					(size 0.7 0.7)
					(thickness 0.15)
				)
				(justify left bottom mirror)
			)
		)
		(fp_text user "Author: Antmicro"
			(at -2.286 -6.119 90)
			(layer "B.Fab")
			(hide yes)
			(effects
				(font
					(size 0.7 0.7)
					(thickness 0.15)
				)
				(justify left bottom mirror)
			)
		)
		(fp_text user "${REFERENCE}"
			(at -2.286 -4.919 90)
			(layer "B.Fab")
			(hide yes)
			(effects
				(font
					(size 0.7 0.7)
					(thickness 0.15)
				)
				(justify left bottom mirror)
			)
		)
		(pad "1" smd roundrect
			(at -1.901 1.25 180)
			(size 0.25 0.6)
			(layers "B.Cu" "B.Paste" "B.Mask")
			(roundrect_rratio 0.25)
			(net 320 "/CSI/SDA_CAM0")
			(pinfunction "SD0")
			(pintype "bidirectional")
		)
		(pad "2" smd roundrect
			(at -1.901 0.75 180)
			(size 0.25 0.6)
			(layers "B.Cu" "B.Paste" "B.Mask")
			(roundrect_rratio 0.25)
			(net 323 "/CSI/SCL_CAM0")
			(pinfunction "SC0")
			(pintype "bidirectional")
		)
		(pad "3" smd roundrect
			(at -1.901 0.25 180)
			(size 0.25 0.6)
			(layers "B.Cu" "B.Paste" "B.Mask")
			(roundrect_rratio 0.25)
			(net 329 "/CSI/SDA_CAM1")
			(pinfunction "SD1")
			(pintype "bidirectional")
		)
		(pad "4" smd roundrect
			(at -1.901 -0.248 180)
			(size 0.25 0.6)
			(layers "B.Cu" "B.Paste" "B.Mask")
			(roundrect_rratio 0.25)
			(net 330 "/CSI/SCL_CAM1")
			(pinfunction "SC1")
			(pintype "bidirectional")
		)
		(pad "5" smd roundrect
			(at -1.901 -0.748 180)
			(size 0.25 0.6)
			(layers "B.Cu" "B.Paste" "B.Mask")
			(roundrect_rratio 0.25)
			(net 331 "/CSI/SDA_CAM2")
			(pinfunction "SD2")
			(pintype "bidirectional")
		)
		(pad "6" smd roundrect
			(at -1.901 -1.249 180)
			(size 0.25 0.6)
			(layers "B.Cu" "B.Paste" "B.Mask")
			(roundrect_rratio 0.25)
			(net 333 "/CSI/SCL_CAM2")
			(pinfunction "SC2")
			(pintype "bidirectional")
		)
		(pad "7" smd roundrect
			(at -1.252 -1.898 90)
			(size 0.25 0.6)
			(layers "B.Cu" "B.Paste" "B.Mask")
			(roundrect_rratio 0.25)
			(net 336 "/CSI/SDA_CAM3")
			(pinfunction "SD3")
			(pintype "bidirectional")
		)
		(pad "8" smd roundrect
			(at -0.751 -1.898 90)
			(size 0.25 0.6)
			(layers "B.Cu" "B.Paste" "B.Mask")
			(roundrect_rratio 0.25)
			(net 337 "/CSI/SCL_CAM3")
			(pinfunction "SC3")
			(pintype "bidirectional")
		)
		(pad "9" smd roundrect
			(at -0.25 -1.898 90)
			(size 0.25 0.6)
			(layers "B.Cu" "B.Paste" "B.Mask")
			(roundrect_rratio 0.25)
			(net 1 "GND")
			(pinfunction "GND")
			(pintype "power_in")
		)
		(pad "10" smd roundrect
			(at 0.248 -1.898 90)
			(size 0.25 0.6)
			(layers "B.Cu" "B.Paste" "B.Mask")
			(roundrect_rratio 0.25)
			(net 535 "/CSI/MUX_I2C_4_SDA")
			(pinfunction "SD4")
			(pintype "bidirectional")
		)
		(pad "11" smd roundrect
			(at 0.748 -1.898 90)
			(size 0.25 0.6)
			(layers "B.Cu" "B.Paste" "B.Mask")
			(roundrect_rratio 0.25)
			(net 536 "/CSI/MUX_I2C_4_SCL")
			(pinfunction "SC4")
			(pintype "bidirectional")
		)
		(pad "12" smd roundrect
			(at 1.249 -1.898 90)
			(size 0.25 0.6)
			(layers "B.Cu" "B.Paste" "B.Mask")
			(roundrect_rratio 0.25)
			(net 537 "/CSI/MUX_I2C_5_SDA")
			(pinfunction "SD5")
			(pintype "bidirectional")
		)
		(pad "13" smd roundrect
			(at 1.898 -1.249)
			(size 0.25 0.6)
			(layers "B.Cu" "B.Paste" "B.Mask")
			(roundrect_rratio 0.25)
			(net 538 "/CSI/MUX_I2C_5_SCL")
			(pinfunction "SC5")
			(pintype "bidirectional")
		)
		(pad "14" smd roundrect
			(at 1.898 -0.748)
			(size 0.25 0.6)
			(layers "B.Cu" "B.Paste" "B.Mask")
			(roundrect_rratio 0.25)
			(net 539 "/CSI/MUX_I2C_6_SDA")
			(pinfunction "SD6")
			(pintype "bidirectional")
		)
		(pad "15" smd roundrect
			(at 1.898 -0.248)
			(size 0.25 0.6)
			(layers "B.Cu" "B.Paste" "B.Mask")
			(roundrect_rratio 0.25)
			(net 542 "/CSI/MUX_I2C_6_SCL")
			(pinfunction "SC6")
			(pintype "bidirectional")
		)
		(pad "16" smd roundrect
			(at 1.898 0.25)
			(size 0.25 0.6)
			(layers "B.Cu" "B.Paste" "B.Mask")
			(roundrect_rratio 0.25)
			(net 543 "/CSI/MUX_I2C_7_SDA")
			(pinfunction "SD7")
			(pintype "bidirectional")
		)
		(pad "17" smd roundrect
			(at 1.898 0.75)
			(size 0.25 0.6)
			(layers "B.Cu" "B.Paste" "B.Mask")
			(roundrect_rratio 0.25)
			(net 544 "/CSI/MUX_I2C_7_SCL")
			(pinfunction "SC7")
			(pintype "bidirectional")
		)
		(pad "18" smd roundrect
			(at 1.898 1.252)
			(size 0.25 0.6)
			(layers "B.Cu" "B.Paste" "B.Mask")
			(roundrect_rratio 0.25)
			(net 1 "GND")
			(pinfunction "A2")
			(pintype "input")
		)
		(pad "19" smd roundrect
			(at 1.249 1.901 270)
			(size 0.25 0.6)
			(layers "B.Cu" "B.Paste" "B.Mask")
			(roundrect_rratio 0.25)
			(net 512 "/CSI/I2C_MUX_SCL")
			(pinfunction "SCL")
			(pintype "bidirectional")
		)
		(pad "20" smd roundrect
			(at 0.748 1.901 270)
			(size 0.25 0.6)
			(layers "B.Cu" "B.Paste" "B.Mask")
			(roundrect_rratio 0.25)
			(net 511 "/CSI/I2C_MUX_SDA")
			(pinfunction "SDA")
			(pintype "bidirectional")
		)
		(pad "21" smd roundrect
			(at 0.248 1.901 270)
			(size 0.25 0.6)
			(layers "B.Cu" "B.Paste" "B.Mask")
			(roundrect_rratio 0.25)
			(net 112 "+1V8")
			(pinfunction "VCC")
			(pintype "power_in")
		)
		(pad "22" smd roundrect
			(at -0.25 1.901 270)
			(size 0.25 0.6)
			(layers "B.Cu" "B.Paste" "B.Mask")
			(roundrect_rratio 0.25)
			(net 325 "/CSI/I2C_MUX_A0")
			(pinfunction "A0")
			(pintype "input")
		)
		(pad "23" smd roundrect
			(at -0.75 1.901 270)
			(size 0.25 0.6)
			(layers "B.Cu" "B.Paste" "B.Mask")
			(roundrect_rratio 0.25)
			(net 1 "GND")
			(pinfunction "A1")
			(pintype "input")
		)
		(pad "24" smd roundrect
			(at -1.252 1.901 270)
			(size 0.25 0.6)
			(layers "B.Cu" "B.Paste" "B.Mask")
			(roundrect_rratio 0.25)
			(net 324 "/CSI/I2C_MUX_RESET")
			(pinfunction "~{RESET}")
			(pintype "input")
		)
		(pad "25" smd roundrect
			(at 0 0.001 270)
			(size 2.1 2.1)
			(layers "B.Cu" "B.Paste" "B.Mask")
			(roundrect_rratio 0.05)
			(net 710 "unconnected-(U26-EP-Pad25)")
			(pinfunction "EP")
			(pintype "power_in+no_connect")
		)
	)
	(footprint "antmicro-footprints:R_0402_1005Metric"
		(layer "B.Cu")
		(at 59.14 98.62 90)
		(descr "Resistor SMD 0402")
		(tags "resistor SMD 0402")
		(property "Reference" "R70"
			(at -3.03 0.5 90)
			(layer "B.SilkS")
			(effects
				(font
					(size 0.7 0.7)
					(thickness 0.15)
				)
				(justify right bottom mirror)
			)
		)
		(property "Value" "R_0R_0402"
			(at 0 -1.4 90)
			(layer "B.Fab")
			(effects
				(font
					(size 0.7 0.7)
					(thickness 0.15)
				)
				(justify right bottom mirror)
			)
		)
		(property "Footprint" "antmicro-footprints:R_0402_1005Metric"
			(at 0 0 90)
			(layer "F.Fab")
			(hide yes)
			(effects
				(font
					(size 1.27 1.27)
					(thickness 0.15)
				)
			)
		)
		(property "Datasheet" "https://industrial.panasonic.com/cdbs/www-data/pdf/RDA0000/AOA0000C301.pdf"
			(at 0 0 90)
			(layer "F.Fab")
			(hide yes)
			(effects
				(font
					(size 1.27 1.27)
					(thickness 0.15)
				)
			)
		)
		(property "Author" "Antmicro"
			(at 157.76 39.48 0)
			(layer "B.Fab")
			(hide yes)
			(effects
				(font
					(size 1 1)
					(thickness 0.15)
				)
				(justify mirror)
			)
		)
		(property "Current" "1A"
			(at 157.76 39.48 0)
			(layer "B.Fab")
			(hide yes)
			(effects
				(font
					(size 1 1)
					(thickness 0.15)
				)
				(justify mirror)
			)
		)
		(property "License" "Apache-2.0"
			(at 157.76 39.48 0)
			(layer "B.Fab")
			(hide yes)
			(effects
				(font
					(size 1 1)
					(thickness 0.15)
				)
				(justify mirror)
			)
		)
		(property "MPN" "ERJ2GE0R00X"
			(at 157.76 39.48 0)
			(layer "B.Fab")
			(hide yes)
			(effects
				(font
					(size 1 1)
					(thickness 0.15)
				)
				(justify mirror)
			)
		)
		(property "Manufacturer" "Panasonic"
			(at 157.76 39.48 0)
			(layer "B.Fab")
			(hide yes)
			(effects
				(font
					(size 1 1)
					(thickness 0.15)
				)
				(justify mirror)
			)
		)
		(property "Tolerance" ""
			(at 157.76 39.48 0)
			(layer "B.Fab")
			(hide yes)
			(effects
				(font
					(size 1 1)
					(thickness 0.15)
				)
				(justify mirror)
			)
		)
		(property "Val" "0R"
			(at 157.76 39.48 0)
			(layer "B.Fab")
			(hide yes)
			(effects
				(font
					(size 1 1)
					(thickness 0.15)
				)
				(justify mirror)
			)
		)
		(sheetname "USB Debug, DP")
		(sheetfile "usb.kicad_sch")
		(attr smd)
		(fp_rect
			(start -0.925 0.47)
			(end 0.925 -0.47)
			(stroke
				(width 0.05)
				(type default)
			)
			(fill none)
			(layer "B.CrtYd")
		)
		(fp_rect
			(start -0.5 0.25)
			(end 0.5 -0.25)
			(stroke
				(width 0.15)
				(type solid)
			)
			(fill none)
			(layer "B.Fab")
		)
		(fp_text user "License: Apache-2.0"
			(at -0.95 -5.169 90)
			(layer "B.Fab")
			(hide yes)
			(effects
				(font
					(size 0.7 0.7)
					(thickness 0.15)
				)
				(justify right bottom mirror)
			)
		)
		(fp_text user "${REFERENCE}"
			(at -0.95 -3.168 90)
			(layer "B.Fab")
			(hide yes)
			(effects
				(font
					(size 0.7 0.7)
					(thickness 0.15)
				)
				(justify right bottom mirror)
			)
		)
		(fp_text user "Author: Antmicro"
			(at -0.95 -4.169 90)
			(layer "B.Fab")
			(hide yes)
			(effects
				(font
					(size 0.7 0.7)
					(thickness 0.15)
				)
				(justify right bottom mirror)
			)
		)
		(pad "1" smd roundrect
			(at -0.48 0 90)
			(size 0.59 0.64)
			(layers "B.Cu" "B.Paste" "B.Mask")
			(roundrect_rratio 0.25)
			(net 252 "SYS_SCL")
			(pintype "passive")
		)
		(pad "2" smd roundrect
			(at 0.48 0 90)
			(size 0.59 0.64)
			(layers "B.Cu" "B.Paste" "B.Mask")
			(roundrect_rratio 0.25)
			(net 302 "/USB Debug, DP/PDC_I2C1_SCL")
			(pintype "passive")
		)
	)
	(footprint "antmicro-footprints:Spacer_Drill3.7mm_H6.5mm_9774065151R"
		(locked yes)
		(layer "B.Cu")
		(at 39.75 123.75 180)
		(descr "Spacer M=3 h=6.5mm fi=5.1mm")
		(property "Reference" "H4"
			(at 1.63 2.62 0)
			(layer "B.SilkS")
			(effects
				(font
					(size 0.7 0.7)
					(thickness 0.15)
				)
				(justify left bottom mirror)
			)
		)
		(property "Value" "Spacer_Drill3.7mm_H6.5mm_9774065151R"
			(at 0 -4 0)
			(layer "B.Fab")
			(effects
				(font
					(size 0.7 0.7)
					(thickness 0.15)
				)
				(justify left bottom mirror)
			)
		)
		(property "Footprint" "antmicro-footprints:Spacer_Drill3.7mm_H6.5mm_9774065151R"
			(at 0 0 180)
			(layer "F.Fab")
			(hide yes)
			(effects
				(font
					(size 1.27 1.27)
					(thickness 0.15)
				)
			)
		)
		(property "Datasheet" "https://www.we-online.com/components/products/datasheet/9774065151R.pdf"
			(at 0 0 180)
			(layer "F.Fab")
			(hide yes)
			(effects
				(font
					(size 1.27 1.27)
					(thickness 0.15)
				)
			)
		)
		(property "Author" "Antmicro"
			(at 79.5 247.5 0)
			(layer "B.Fab")
			(hide yes)
			(effects
				(font
					(size 1 1)
					(thickness 0.15)
				)
				(justify mirror)
			)
		)
		(property "License" "Apache-2.0"
			(at 79.5 247.5 0)
			(layer "B.Fab")
			(hide yes)
			(effects
				(font
					(size 1 1)
					(thickness 0.15)
				)
				(justify mirror)
			)
		)
		(property "MPN" "9774065151R"
			(at 79.5 247.5 0)
			(layer "B.Fab")
			(hide yes)
			(effects
				(font
					(size 1 1)
					(thickness 0.15)
				)
				(justify mirror)
			)
		)
		(property "Manufacturer" "Würth Elektronik"
			(at 79.5 247.5 0)
			(layer "B.Fab")
			(hide yes)
			(effects
				(font
					(size 1 1)
					(thickness 0.15)
				)
				(justify mirror)
			)
		)
		(sheetname "Root")
		(sheetfile "jetson-orin-baseboard.kicad_sch")
		(solder_paste_ratio -1)
		(attr smd)
		(fp_circle
			(center 0 0)
			(end 3.05 0)
			(stroke
				(width 0.05)
				(type solid)
			)
			(fill none)
			(layer "B.CrtYd")
		)
		(fp_circle
			(center 0 0)
			(end 2.6 0)
			(stroke
				(width 0.15)
				(type solid)
			)
			(fill none)
			(layer "B.Fab")
		)
		(fp_text user "Author: Antmicro"
			(at -9.6 -7.7 0)
			(layer "B.Fab")
			(hide yes)
			(effects
				(font
					(size 0.7 0.7)
					(thickness 0.15)
				)
				(justify left bottom mirror)
			)
		)
		(fp_text user "License: Apache-2.0"
			(at -9.6 -8.9 0)
			(layer "B.Fab")
			(hide yes)
			(effects
				(font
					(size 0.7 0.7)
					(thickness 0.15)
				)
				(justify left bottom mirror)
			)
		)
		(fp_text user "${REFERENCE}"
			(at -9.6 -6.5 0)
			(layer "B.Fab")
			(hide yes)
			(effects
				(font
					(size 0.7 0.7)
					(thickness 0.15)
				)
				(justify left bottom mirror)
			)
		)
		(pad "" smd custom
			(at -1.7 -1.7 90)
			(size 0.62 0.62)
			(layers "B.Paste")
			(thermal_bridge_angle 90)
			(options
				(clearance outline)
				(anchor circle)
			)
			(primitives
				(gr_arc
					(start 1.266786 0.24747)
					(mid 0.285453 -0.29439)
					(end -0.250195 -1.279127)
					(width 0.2)
				)
				(gr_arc
					(start 1.259603 0.339191)
					(mid 0.218448 -0.232561)
					(end -0.34334 -1.279127)
					(width 0.2)
				)
				(gr_arc
					(start 1.255279 0.431435)
					(mid 0.152481 -0.169693)
					(end -0.436309 -1.279127)
					(width 0.2)
				)
				(gr_arc
					(start 1.253811 0.524161)
					(mid 0.087542 -0.105784)
					(end -0.529126 -1.279127)
					(width 0.2)
				)
				(gr_arc
					(start 1.275473 0.621136)
					(mid 0.0309 -0.033527)
					(end -0.621807 -1.279127)
					(width 0.2)
				)
				(gr_arc
					(start 1.263664 0.711602)
					(mid -0.037759 0.026651)
					(end -0.71437 -1.279127)
					(width 0.2)
				)
				(gr_arc
					(start 1.253435 0.802342)
					(mid -0.105837 0.087395)
					(end -0.806826 -1.279127)
					(width 0.2)
				)
				(gr_arc
					(start 1.267475 0.897258)
					(mid -0.165236 0.156885)
					(end -0.899187 -1.279127)
					(width 0.2)
				)
				(gr_arc
					(start 1.270645 0.990112)
					(mid -0.228522 0.222449)
					(end -0.991463 -1.279127)
					(width 0.2)
				)
				(gr_arc
					(start 1.266278 1.081674)
					(mid -0.294507 0.285313)
					(end -1.083663 -1.279127)
					(width 0.2)
				)
				(gr_line
					(start 1.279127 1.083663)
					(end 1.279127 0.250195)
					(width 0.2)
				)
				(gr_line
					(start -1.083663 -1.279127)
					(end -0.250195 -1.279127)
					(width 0.2)
				)
			)
		)
		(pad "" smd custom
			(at -1.7 1.7 180)
			(size 0.62 0.62)
			(layers "B.Paste")
			(thermal_bridge_angle 90)
			(options
				(clearance outline)
				(anchor circle)
			)
			(primitives
				(gr_arc
					(start 1.266786 0.24747)
					(mid 0.285453 -0.29439)
					(end -0.250195 -1.279127)
					(width 0.2)
				)
				(gr_arc
					(start 1.259603 0.339191)
					(mid 0.218448 -0.232561)
					(end -0.34334 -1.279127)
					(width 0.2)
				)
				(gr_arc
					(start 1.255279 0.431435)
					(mid 0.152481 -0.169693)
					(end -0.436309 -1.279127)
					(width 0.2)
				)
				(gr_arc
					(start 1.253811 0.524161)
					(mid 0.087542 -0.105784)
					(end -0.529126 -1.279127)
					(width 0.2)
				)
				(gr_arc
					(start 1.275473 0.621136)
					(mid 0.0309 -0.033527)
					(end -0.621807 -1.279127)
					(width 0.2)
				)
				(gr_arc
					(start 1.263664 0.711602)
					(mid -0.037759 0.026651)
					(end -0.71437 -1.279127)
					(width 0.2)
				)
				(gr_arc
					(start 1.253435 0.802342)
					(mid -0.105837 0.087395)
					(end -0.806826 -1.279127)
					(width 0.2)
				)
				(gr_arc
					(start 1.267475 0.897258)
					(mid -0.165236 0.156885)
					(end -0.899187 -1.279127)
					(width 0.2)
				)
				(gr_arc
					(start 1.270645 0.990112)
					(mid -0.228522 0.222449)
					(end -0.991463 -1.279127)
					(width 0.2)
				)
				(gr_arc
					(start 1.266278 1.081674)
					(mid -0.294507 0.285313)
					(end -1.083663 -1.279127)
					(width 0.2)
				)
				(gr_line
					(start 1.279127 1.083663)
					(end 1.279127 0.250195)
					(width 0.2)
				)
				(gr_line
					(start -1.083663 -1.279127)
					(end -0.250195 -1.279127)
					(width 0.2)
				)
			)
		)
		(pad "" smd custom
			(at 1.7 -1.7)
			(size 0.62 0.62)
			(layers "B.Paste")
			(thermal_bridge_angle 90)
			(options
				(clearance outline)
				(anchor circle)
			)
			(primitives
				(gr_arc
					(start 1.266786 0.24747)
					(mid 0.285453 -0.29439)
					(end -0.250195 -1.279127)
					(width 0.2)
				)
				(gr_arc
					(start 1.259603 0.339191)
					(mid 0.218448 -0.232561)
					(end -0.34334 -1.279127)
					(width 0.2)
				)
				(gr_arc
					(start 1.255279 0.431435)
					(mid 0.152481 -0.169693)
					(end -0.436309 -1.279127)
					(width 0.2)
				)
				(gr_arc
					(start 1.253811 0.524161)
					(mid 0.087542 -0.105784)
					(end -0.529126 -1.279127)
					(width 0.2)
				)
				(gr_arc
					(start 1.275473 0.621136)
					(mid 0.0309 -0.033527)
					(end -0.621807 -1.279127)
					(width 0.2)
				)
				(gr_arc
					(start 1.263664 0.711602)
					(mid -0.037759 0.026651)
					(end -0.71437 -1.279127)
					(width 0.2)
				)
				(gr_arc
					(start 1.253435 0.802342)
					(mid -0.105837 0.087395)
					(end -0.806826 -1.279127)
					(width 0.2)
				)
				(gr_arc
					(start 1.267475 0.897258)
					(mid -0.165236 0.156885)
					(end -0.899187 -1.279127)
					(width 0.2)
				)
				(gr_arc
					(start 1.270645 0.990112)
					(mid -0.228522 0.222449)
					(end -0.991463 -1.279127)
					(width 0.2)
				)
				(gr_arc
					(start 1.266278 1.081674)
					(mid -0.294507 0.285313)
					(end -1.083663 -1.279127)
					(width 0.2)
				)
				(gr_line
					(start 1.279127 1.083663)
					(end 1.279127 0.250195)
					(width 0.2)
				)
				(gr_line
					(start -1.083663 -1.279127)
					(end -0.250195 -1.279127)
					(width 0.2)
				)
			)
		)
		(pad "" smd custom
			(at 1.7 1.7 270)
			(size 0.62 0.62)
			(layers "B.Paste")
			(thermal_bridge_angle 90)
			(options
				(clearance outline)
				(anchor circle)
			)
			(primitives
				(gr_arc
					(start 1.266786 0.24747)
					(mid 0.285453 -0.29439)
					(end -0.250195 -1.279127)
					(width 0.2)
				)
				(gr_arc
					(start 1.259603 0.339191)
					(mid 0.218448 -0.232561)
					(end -0.34334 -1.279127)
					(width 0.2)
				)
				(gr_arc
					(start 1.255279 0.431435)
					(mid 0.152481 -0.169693)
					(end -0.436309 -1.279127)
					(width 0.2)
				)
				(gr_arc
					(start 1.253811 0.524161)
					(mid 0.087542 -0.105784)
					(end -0.529126 -1.279127)
					(width 0.2)
				)
				(gr_arc
					(start 1.275473 0.621136)
					(mid 0.0309 -0.033527)
					(end -0.621807 -1.279127)
					(width 0.2)
				)
				(gr_arc
					(start 1.263664 0.711602)
					(mid -0.037759 0.026651)
					(end -0.71437 -1.279127)
					(width 0.2)
				)
				(gr_arc
					(start 1.253435 0.802342)
					(mid -0.105837 0.087395)
					(end -0.806826 -1.279127)
					(width 0.2)
				)
				(gr_arc
					(start 1.267475 0.897258)
					(mid -0.165236 0.156885)
					(end -0.899187 -1.279127)
					(width 0.2)
				)
				(gr_arc
					(start 1.270645 0.990112)
					(mid -0.228522 0.222449)
					(end -0.991463 -1.279127)
					(width 0.2)
				)
				(gr_arc
					(start 1.266278 1.081674)
					(mid -0.294507 0.285313)
					(end -1.083663 -1.279127)
					(width 0.2)
				)
				(gr_line
					(start 1.279127 1.083663)
					(end 1.279127 0.250195)
					(width 0.2)
				)
				(gr_line
					(start -1.083663 -1.279127)
					(end -0.250195 -1.279127)
					(width 0.2)
				)
			)
		)
		(pad "1" thru_hole circle
			(at 0 0 180)
			(size 6 6)
			(drill 3.7)
			(layers "*.Cu" "*.Mask")
			(remove_unused_layers no)
			(net 1 "GND")
			(pintype "passive")
		)
	)
	(footprint "antmicro-footprints:TP_SMD_0.75mm"
		(layer "B.Cu")
		(at 103.275 102.55 -90)
		(property "Reference" "TP37"
			(at -1.04 -1.365 90)
			(layer "B.SilkS")
			(hide yes)
			(effects
				(font
					(size 0.7 0.7)
					(thickness 0.15)
				)
				(justify left bottom mirror)
			)
		)
		(property "Value" "TP_0.75mm_SMD"
			(at 0 -1.2 90)
			(layer "B.Fab")
			(effects
				(font
					(size 0.7 0.7)
					(thickness 0.15)
				)
				(justify left bottom mirror)
			)
		)
		(property "Footprint" "antmicro-footprints:TP_SMD_0.75mm"
			(at 0 0 -90)
			(layer "F.Fab")
			(hide yes)
			(effects
				(font
					(size 1.27 1.27)
					(thickness 0.15)
				)
			)
		)
		(property "Author" "Antmicro"
			(at 0.725 205.825 0)
			(layer "B.Fab")
			(hide yes)
			(effects
				(font
					(size 1 1)
					(thickness 0.15)
				)
				(justify mirror)
			)
		)
		(property "License" "Apache-2.0"
			(at 0.725 205.825 0)
			(layer "B.Fab")
			(hide yes)
			(effects
				(font
					(size 1 1)
					(thickness 0.15)
				)
				(justify mirror)
			)
		)
		(property "MPN" ""
			(at 0.725 205.825 0)
			(layer "B.Fab")
			(hide yes)
			(effects
				(font
					(size 1 1)
					(thickness 0.15)
				)
				(justify mirror)
			)
		)
		(property "Manufacturer" ""
			(at 0.725 205.825 0)
			(layer "B.Fab")
			(hide yes)
			(effects
				(font
					(size 1 1)
					(thickness 0.15)
				)
				(justify mirror)
			)
		)
		(sheetname "CSI")
		(sheetfile "csi.kicad_sch")
		(attr exclude_from_pos_files exclude_from_bom)
		(fp_circle
			(center 0 0)
			(end 0.475 0)
			(stroke
				(width 0.05)
				(type default)
			)
			(fill none)
			(layer "B.CrtYd")
		)
		(fp_text user "License: Apache-2.0"
			(at -0.4 -5.101 90)
			(layer "B.Fab")
			(hide yes)
			(effects
				(font
					(size 0.7 0.7)
					(thickness 0.15)
				)
				(justify left bottom mirror)
			)
		)
		(fp_text user "Author: Antmicro"
			(at -0.4 -3.901 90)
			(layer "B.Fab")
			(hide yes)
			(effects
				(font
					(size 0.7 0.7)
					(thickness 0.15)
				)
				(justify left bottom mirror)
			)
		)
		(fp_text user "${REFERENCE}"
			(at -0.4 -2.7 90)
			(layer "B.Fab")
			(hide yes)
			(effects
				(font
					(size 0.7 0.7)
					(thickness 0.15)
				)
				(justify left bottom mirror)
			)
		)
		(pad "1" smd circle
			(at 0 0 270)
			(size 0.75 0.75)
			(layers "B.Cu" "B.Mask")
			(net 536 "/CSI/MUX_I2C_4_SCL")
			(pinfunction "1")
			(pintype "passive")
		)
	)
	(footprint "antmicro-footprints:R_0402_1005Metric"
		(layer "B.Cu")
		(at 46.54 73.475 180)
		(descr "Resistor SMD 0402")
		(tags "resistor SMD 0402")
		(property "Reference" "R251"
			(at -1.36 -2.225 180)
			(layer "B.SilkS")
			(effects
				(font
					(size 0.7 0.7)
					(thickness 0.15)
				)
				(justify left bottom mirror)
			)
		)
		(property "Value" "R_10k_0402"
			(at 0 -1.4 0)
			(layer "B.Fab")
			(effects
				(font
					(size 0.7 0.7)
					(thickness 0.15)
				)
				(justify left bottom mirror)
			)
		)
		(property "Footprint" "antmicro-footprints:R_0402_1005Metric"
			(at 0 0 180)
			(layer "F.Fab")
			(hide yes)
			(effects
				(font
					(size 1.27 1.27)
					(thickness 0.15)
				)
			)
		)
		(property "Datasheet" "https://www.bourns.com/docs/product-datasheets/cr.pdf"
			(at 0 0 180)
			(layer "F.Fab")
			(hide yes)
			(effects
				(font
					(size 1.27 1.27)
					(thickness 0.15)
				)
			)
		)
		(property "Author" "Antmicro"
			(at 93.8 146.8 0)
			(layer "B.Fab")
			(hide yes)
			(effects
				(font
					(size 1 1)
					(thickness 0.15)
				)
				(justify mirror)
			)
		)
		(property "License" "Apache-2.0"
			(at 93.8 146.8 0)
			(layer "B.Fab")
			(hide yes)
			(effects
				(font
					(size 1 1)
					(thickness 0.15)
				)
				(justify mirror)
			)
		)
		(property "MPN" "CR0402-FX-1002GLF"
			(at 93.8 146.8 0)
			(layer "B.Fab")
			(hide yes)
			(effects
				(font
					(size 1 1)
					(thickness 0.15)
				)
				(justify mirror)
			)
		)
		(property "Manufacturer" "Bourns"
			(at 93.8 146.8 0)
			(layer "B.Fab")
			(hide yes)
			(effects
				(font
					(size 1 1)
					(thickness 0.15)
				)
				(justify mirror)
			)
		)
		(property "Tolerance" "1%"
			(at 93.8 146.8 0)
			(layer "B.Fab")
			(hide yes)
			(effects
				(font
					(size 1 1)
					(thickness 0.15)
				)
				(justify mirror)
			)
		)
		(property "Val" "10k"
			(at 93.8 146.8 0)
			(layer "B.Fab")
			(hide yes)
			(effects
				(font
					(size 1 1)
					(thickness 0.15)
				)
				(justify mirror)
			)
		)
		(sheetname "Supply")
		(sheetfile "supply.kicad_sch")
		(attr smd)
		(fp_rect
			(start -0.925 0.47)
			(end 0.925 -0.47)
			(stroke
				(width 0.05)
				(type default)
			)
			(fill none)
			(layer "B.CrtYd")
		)
		(fp_rect
			(start -0.5 0.25)
			(end 0.5 -0.25)
			(stroke
				(width 0.15)
				(type solid)
			)
			(fill none)
			(layer "B.Fab")
		)
		(fp_text user "${REFERENCE}"
			(at -0.95 -3.168 0)
			(layer "B.Fab")
			(hide yes)
			(effects
				(font
					(size 0.7 0.7)
					(thickness 0.15)
				)
				(justify left bottom mirror)
			)
		)
		(fp_text user "Author: Antmicro"
			(at -0.95 -4.169 0)
			(layer "B.Fab")
			(hide yes)
			(effects
				(font
					(size 0.7 0.7)
					(thickness 0.15)
				)
				(justify left bottom mirror)
			)
		)
		(fp_text user "License: Apache-2.0"
			(at -0.95 -5.169 0)
			(layer "B.Fab")
			(hide yes)
			(effects
				(font
					(size 0.7 0.7)
					(thickness 0.15)
				)
				(justify left bottom mirror)
			)
		)
		(pad "1" smd roundrect
			(at -0.48 0 180)
			(size 0.59 0.64)
			(layers "B.Cu" "B.Paste" "B.Mask")
			(roundrect_rratio 0.25)
			(net 1 "GND")
			(pintype "passive")
		)
		(pad "2" smd roundrect
			(at 0.48 0 180)
			(size 0.59 0.64)
			(layers "B.Cu" "B.Paste" "B.Mask")
			(roundrect_rratio 0.25)
			(net 718 "Net-(Q14-Pad2)")
			(pintype "passive")
		)
	)
	(footprint "antmicro-footprints:C_0402_1005Metric"
		(layer "B.Cu")
		(at 136.7 117.55)
		(descr "Capacitor SMD 0402")
		(tags "capacitor SMD 0402")
		(property "Reference" "C42"
			(at 1.1 1.3 180)
			(layer "B.SilkS")
			(effects
				(font
					(size 0.7 0.7)
					(thickness 0.15)
				)
				(justify left bottom mirror)
			)
		)
		(property "Value" "C_100n_0402"
			(at 0 -1.4 180)
			(layer "B.Fab")
			(effects
				(font
					(size 0.7 0.7)
					(thickness 0.15)
				)
				(justify left bottom mirror)
			)
		)
		(property "Footprint" "antmicro-footprints:C_0402_1005Metric"
			(at 0 0 0)
			(layer "F.Fab")
			(hide yes)
			(effects
				(font
					(size 1.27 1.27)
					(thickness 0.15)
				)
			)
		)
		(property "Datasheet" "https://www.murata.com/products/productdetail?partno=GRM155R61H104KE14%23"
			(at 0 0 0)
			(layer "F.Fab")
			(hide yes)
			(effects
				(font
					(size 1.27 1.27)
					(thickness 0.15)
				)
			)
		)
		(property "Author" "Antmicro"
			(at 0 0 0)
			(layer "B.Fab")
			(hide yes)
			(effects
				(font
					(size 1 1)
					(thickness 0.15)
				)
				(justify mirror)
			)
		)
		(property "Dielectric" "X5R"
			(at 0 0 0)
			(layer "B.Fab")
			(hide yes)
			(effects
				(font
					(size 1 1)
					(thickness 0.15)
				)
				(justify mirror)
			)
		)
		(property "License" "Apache-2.0"
			(at 0 0 0)
			(layer "B.Fab")
			(hide yes)
			(effects
				(font
					(size 1 1)
					(thickness 0.15)
				)
				(justify mirror)
			)
		)
		(property "MPN" "GRM155R61H104KE14D"
			(at 0 0 0)
			(layer "B.Fab")
			(hide yes)
			(effects
				(font
					(size 1 1)
					(thickness 0.15)
				)
				(justify mirror)
			)
		)
		(property "Manufacturer" "Murata"
			(at 0 0 0)
			(layer "B.Fab")
			(hide yes)
			(effects
				(font
					(size 1 1)
					(thickness 0.15)
				)
				(justify mirror)
			)
		)
		(property "Val" "100n"
			(at 0 0 0)
			(layer "B.Fab")
			(hide yes)
			(effects
				(font
					(size 1 1)
					(thickness 0.15)
				)
				(justify mirror)
			)
		)
		(property "Voltage" "50V"
			(at 0 0 0)
			(layer "B.Fab")
			(hide yes)
			(effects
				(font
					(size 1 1)
					(thickness 0.15)
				)
				(justify mirror)
			)
		)
		(sheetname "CSI")
		(sheetfile "csi.kicad_sch")
		(attr smd)
		(fp_rect
			(start -0.925 0.47)
			(end 0.925 -0.47)
			(stroke
				(width 0.05)
				(type default)
			)
			(fill none)
			(layer "B.CrtYd")
		)
		(fp_line
			(start -0.494 -0.248)
			(end 0.504 -0.248)
			(stroke
				(width 0.15)
				(type solid)
			)
			(layer "B.Fab")
		)
		(fp_line
			(start -0.494 0.25)
			(end -0.494 -0.248)
			(stroke
				(width 0.15)
				(type solid)
			)
			(layer "B.Fab")
		)
		(fp_line
			(start 0.504 -0.248)
			(end 0.504 0.25)
			(stroke
				(width 0.15)
				(type solid)
			)
			(layer "B.Fab")
		)
		(fp_line
			(start 0.504 0.25)
			(end -0.494 0.25)
			(stroke
				(width 0.15)
				(type solid)
			)
			(layer "B.Fab")
		)
		(fp_text user "${REFERENCE}"
			(at -0.932 -3.168 180)
			(layer "B.Fab")
			(hide yes)
			(effects
				(font
					(size 0.7 0.7)
					(thickness 0.15)
				)
				(justify left bottom mirror)
			)
		)
		(fp_text user "License: Apache-2.0"
			(at -0.932 -5.17 180)
			(layer "B.Fab")
			(hide yes)
			(effects
				(font
					(size 0.7 0.7)
					(thickness 0.15)
				)
				(justify left bottom mirror)
			)
		)
		(fp_text user "Author: Antmicro"
			(at -0.932 -4.17 180)
			(layer "B.Fab")
			(hide yes)
			(effects
				(font
					(size 0.7 0.7)
					(thickness 0.15)
				)
				(justify left bottom mirror)
			)
		)
		(pad "1" smd roundrect
			(at -0.48 0)
			(size 0.59 0.64)
			(layers "B.Cu" "B.Paste" "B.Mask")
			(roundrect_rratio 0.25)
			(net 99 "+5V")
			(pintype "passive")
		)
		(pad "2" smd roundrect
			(at 0.48 0)
			(size 0.59 0.64)
			(layers "B.Cu" "B.Paste" "B.Mask")
			(roundrect_rratio 0.25)
			(net 1 "GND")
			(pintype "passive")
		)
	)
	(footprint "antmicro-footprints:Mech_M2_2280_H2.5mm"
		(layer "B.Cu")
		(at 40.74 86.7795 -90)
		(property "Reference" "M3"
			(at 4.4205 0.74 0)
			(layer "B.SilkS")
			(effects
				(font
					(size 0.7 0.7)
					(thickness 0.15)
				)
				(justify left top mirror)
			)
		)
		(property "Value" "Mech_M2_2280_H2.5mm"
			(at 0 -6.857 90)
			(layer "B.Fab")
			(effects
				(font
					(size 0.7 0.7)
					(thickness 0.15)
				)
				(justify right bottom mirror)
			)
		)
		(property "Footprint" "antmicro-footprints:Mech_M2_2280_H2.5mm"
			(at 0 0 90)
			(layer "B.Fab")
			(hide yes)
			(effects
				(font
					(size 1.27 1.27)
					(thickness 0.15)
				)
			)
		)
		(property "Manufacturer" ""
			(at 0 0 -90)
			(unlocked yes)
			(layer "B.Fab")
			(hide yes)
			(effects
				(font
					(size 1 1)
					(thickness 0.15)
				)
				(justify mirror)
			)
		)
		(property "MPN" ""
			(at 0 0 -90)
			(unlocked yes)
			(layer "B.Fab")
			(hide yes)
			(effects
				(font
					(size 1 1)
					(thickness 0.15)
				)
				(justify mirror)
			)
		)
		(property "Author" "Antmicro"
			(at 0 0 -90)
			(unlocked yes)
			(layer "B.Fab")
			(hide yes)
			(effects
				(font
					(size 1 1)
					(thickness 0.15)
				)
				(justify mirror)
			)
		)
		(property "License" "Apache-2.0"
			(at 0 0 -90)
			(unlocked yes)
			(layer "B.Fab")
			(hide yes)
			(effects
				(font
					(size 1 1)
					(thickness 0.15)
				)
				(justify mirror)
			)
		)
		(sheetname "M.2")
		(sheetfile "m-2.kicad_sch")
		(attr exclude_from_pos_files exclude_from_bom allow_missing_courtyard dnp)
		(fp_rect
			(start -10.922 -0.0508)
			(end 11.0236 -80.0608)
			(stroke
				(width 0.15)
				(type solid)
			)
			(fill none)
			(layer "B.Fab")
		)
		(fp_text user "License: Apache-2.0"
			(at -12.2428 -84.3922 90)
			(layer "B.Fab")
			(hide yes)
			(effects
				(font
					(size 0.7 0.7)
					(thickness 0.15)
				)
				(justify left bottom mirror)
			)
		)
		(fp_text user "Author: Antmicro"
			(at -12.2428 -83.1912 90)
			(layer "B.Fab")
			(hide yes)
			(effects
				(font
					(size 0.7 0.7)
					(thickness 0.15)
				)
				(justify left bottom mirror)
			)
		)
		(fp_text user "${REFERENCE}"
			(at -12.2428 -81.9912 90)
			(layer "B.Fab")
			(hide yes)
			(effects
				(font
					(size 0.7 0.7)
					(thickness 0.15)
				)
				(justify left bottom mirror)
			)
		)
	)
	(footprint "antmicro-footprints:SOD-523"
		(layer "B.Cu")
		(at 55.25 80.75 90)
		(property "Reference" "D34"
			(at -0.25 1.375 -90)
			(layer "B.SilkS")
			(effects
				(font
					(size 0.7 0.7)
					(thickness 0.15)
				)
				(justify left bottom mirror)
			)
		)
		(property "Value" "RB521S30T1G"
			(at 0 -1.499 -90)
			(layer "B.Fab")
			(effects
				(font
					(size 0.7 0.7)
					(thickness 0.15)
				)
				(justify left bottom mirror)
			)
		)
		(property "Footprint" "antmicro-footprints:SOD-523"
			(at 0 0 90)
			(layer "F.Fab")
			(hide yes)
			(effects
				(font
					(size 1.27 1.27)
					(thickness 0.15)
				)
			)
		)
		(property "Datasheet" "https://www.onsemi.com/pdf/datasheet/rb521s30t1-d.pdf"
			(at 0 0 90)
			(layer "F.Fab")
			(hide yes)
			(effects
				(font
					(size 1.27 1.27)
					(thickness 0.15)
				)
			)
		)
		(property "Author" "Antmicro"
			(at 135.65 26.15 0)
			(layer "B.Fab")
			(hide yes)
			(effects
				(font
					(size 1 1)
					(thickness 0.15)
				)
				(justify mirror)
			)
		)
		(property "License" "Apache-2.0"
			(at 135.65 26.15 0)
			(layer "B.Fab")
			(hide yes)
			(effects
				(font
					(size 1 1)
					(thickness 0.15)
				)
				(justify mirror)
			)
		)
		(property "MPN" "RB521S30T1G"
			(at 135.65 26.15 0)
			(layer "B.Fab")
			(hide yes)
			(effects
				(font
					(size 1 1)
					(thickness 0.15)
				)
				(justify mirror)
			)
		)
		(property "Manufacturer" "ON Semiconductor"
			(at 135.65 26.15 0)
			(layer "B.Fab")
			(hide yes)
			(effects
				(font
					(size 1 1)
					(thickness 0.15)
				)
				(justify mirror)
			)
		)
		(sheetname "SoM")
		(sheetfile "som.kicad_sch")
		(attr smd)
		(fp_line
			(start -0.35 -0.5)
			(end -0.35 0.5)
			(stroke
				(width 0.15)
				(type solid)
			)
			(layer "B.SilkS")
		)
		(fp_rect
			(start -1 0.6)
			(end 1 -0.6)
			(stroke
				(width 0.05)
				(type solid)
			)
			(fill none)
			(layer "B.CrtYd")
		)
		(fp_line
			(start 0.65 -0.423)
			(end -0.652 -0.423)
			(stroke
				(width 0.15)
				(type solid)
			)
			(layer "B.Fab")
		)
		(fp_line
			(start 0.65 -0.423)
			(end 0.65 0.425)
			(stroke
				(width 0.15)
				(type solid)
			)
			(layer "B.Fab")
		)
		(fp_line
			(start -0.35 -0.4)
			(end -0.35 0.4)
			(stroke
				(width 0.15)
				(type solid)
			)
			(layer "B.Fab")
		)
		(fp_line
			(start 0.65 0.425)
			(end -0.652 0.425)
			(stroke
				(width 0.15)
				(type solid)
			)
			(layer "B.Fab")
		)
		(fp_line
			(start -0.652 0.425)
			(end -0.652 -0.423)
			(stroke
				(width 0.15)
				(type solid)
			)
			(layer "B.Fab")
		)
		(fp_text user "Author: Antmicro"
			(at -1.276 -4.7 -90)
			(layer "B.Fab")
			(hide yes)
			(effects
				(font
					(size 0.7 0.7)
					(thickness 0.15)
				)
				(justify left bottom mirror)
			)
		)
		(fp_text user "License: Apache-2.0"
			(at -1.276 -5.9 -90)
			(layer "B.Fab")
			(hide yes)
			(effects
				(font
					(size 0.7 0.7)
					(thickness 0.15)
				)
				(justify left bottom mirror)
			)
		)
		(fp_text user "${REFERENCE}"
			(at -1.276 -3.499 -90)
			(layer "B.Fab")
			(hide yes)
			(effects
				(font
					(size 0.7 0.7)
					(thickness 0.15)
				)
				(justify left bottom mirror)
			)
		)
		(pad "1" smd roundrect
			(at -0.701 0 90)
			(size 0.5 0.6)
			(layers "B.Cu" "B.Paste" "B.Mask")
			(roundrect_rratio 0.25)
			(net 85 "/SoM/PMIC_BBAT")
			(pinfunction "C")
			(pintype "passive")
		)
		(pad "2" smd roundrect
			(at 0.699 0 90)
			(size 0.5 0.6)
			(layers "B.Cu" "B.Paste" "B.Mask")
			(roundrect_rratio 0.25)
			(net 117 "3V3_STDB")
			(pinfunction "A")
			(pintype "passive")
		)
	)
	(footprint "antmicro-footprints:R_0402_1005Metric"
		(layer "B.Cu")
		(at 108.1 112 -90)
		(descr "Resistor SMD 0402")
		(tags "resistor SMD 0402")
		(property "Reference" "R24"
			(at 0.75 -0.4 90)
			(layer "B.SilkS")
			(effects
				(font
					(size 0.7 0.7)
					(thickness 0.15)
				)
				(justify left bottom mirror)
			)
		)
		(property "Value" "R_10k_0402"
			(at 0 -1.4 90)
			(layer "B.Fab")
			(effects
				(font
					(size 0.7 0.7)
					(thickness 0.15)
				)
				(justify left bottom mirror)
			)
		)
		(property "Footprint" "antmicro-footprints:R_0402_1005Metric"
			(at 0 0 -90)
			(layer "F.Fab")
			(hide yes)
			(effects
				(font
					(size 1.27 1.27)
					(thickness 0.15)
				)
			)
		)
		(property "Datasheet" "https://www.bourns.com/docs/product-datasheets/cr.pdf"
			(at 0 0 -90)
			(layer "F.Fab")
			(hide yes)
			(effects
				(font
					(size 1.27 1.27)
					(thickness 0.15)
				)
			)
		)
		(property "Author" "Antmicro"
			(at -3.9 220.1 0)
			(layer "B.Fab")
			(hide yes)
			(effects
				(font
					(size 1 1)
					(thickness 0.15)
				)
				(justify mirror)
			)
		)
		(property "License" "Apache-2.0"
			(at -3.9 220.1 0)
			(layer "B.Fab")
			(hide yes)
			(effects
				(font
					(size 1 1)
					(thickness 0.15)
				)
				(justify mirror)
			)
		)
		(property "MPN" "CR0402-FX-1002GLF"
			(at -3.9 220.1 0)
			(layer "B.Fab")
			(hide yes)
			(effects
				(font
					(size 1 1)
					(thickness 0.15)
				)
				(justify mirror)
			)
		)
		(property "Manufacturer" "Bourns"
			(at -3.9 220.1 0)
			(layer "B.Fab")
			(hide yes)
			(effects
				(font
					(size 1 1)
					(thickness 0.15)
				)
				(justify mirror)
			)
		)
		(property "Tolerance" "1%"
			(at -3.9 220.1 0)
			(layer "B.Fab")
			(hide yes)
			(effects
				(font
					(size 1 1)
					(thickness 0.15)
				)
				(justify mirror)
			)
		)
		(property "Val" "10k"
			(at -3.9 220.1 0)
			(layer "B.Fab")
			(hide yes)
			(effects
				(font
					(size 1 1)
					(thickness 0.15)
				)
				(justify mirror)
			)
		)
		(sheetname "USB3")
		(sheetfile "usb3.kicad_sch")
		(attr smd)
		(fp_rect
			(start -0.925 0.47)
			(end 0.925 -0.47)
			(stroke
				(width 0.05)
				(type default)
			)
			(fill none)
			(layer "B.CrtYd")
		)
		(fp_rect
			(start -0.5 0.25)
			(end 0.5 -0.25)
			(stroke
				(width 0.15)
				(type solid)
			)
			(fill none)
			(layer "B.Fab")
		)
		(fp_text user "${REFERENCE}"
			(at -0.95 -3.168 90)
			(layer "B.Fab")
			(hide yes)
			(effects
				(font
					(size 0.7 0.7)
					(thickness 0.15)
				)
				(justify left bottom mirror)
			)
		)
		(fp_text user "Author: Antmicro"
			(at -0.95 -4.169 90)
			(layer "B.Fab")
			(hide yes)
			(effects
				(font
					(size 0.7 0.7)
					(thickness 0.15)
				)
				(justify left bottom mirror)
			)
		)
		(fp_text user "License: Apache-2.0"
			(at -0.95 -5.169 90)
			(layer "B.Fab")
			(hide yes)
			(effects
				(font
					(size 0.7 0.7)
					(thickness 0.15)
				)
				(justify left bottom mirror)
			)
		)
		(pad "1" smd roundrect
			(at -0.48 0 270)
			(size 0.59 0.64)
			(layers "B.Cu" "B.Paste" "B.Mask")
			(roundrect_rratio 0.25)
			(net 632 "Net-(Q19-G)")
			(pintype "passive")
		)
		(pad "2" smd roundrect
			(at 0.48 0 270)
			(size 0.59 0.64)
			(layers "B.Cu" "B.Paste" "B.Mask")
			(roundrect_rratio 0.25)
			(net 284 "/USB3/USBC1_ID")
			(pintype "passive")
		)
	)
	(footprint "antmicro-footprints:R_0402_1005Metric"
		(layer "B.Cu")
		(at 51.02 83.92 180)
		(descr "Resistor SMD 0402")
		(tags "resistor SMD 0402")
		(property "Reference" "R148"
			(at 0.82 -0.53 180)
			(layer "B.SilkS")
			(effects
				(font
					(size 0.7 0.7)
					(thickness 0.15)
				)
				(justify left bottom mirror)
			)
		)
		(property "Value" "R_10k_0402"
			(at 0 -1.4 0)
			(layer "B.Fab")
			(effects
				(font
					(size 0.7 0.7)
					(thickness 0.15)
				)
				(justify left bottom mirror)
			)
		)
		(property "Footprint" "antmicro-footprints:R_0402_1005Metric"
			(at 0 0 180)
			(layer "F.Fab")
			(hide yes)
			(effects
				(font
					(size 1.27 1.27)
					(thickness 0.15)
				)
			)
		)
		(property "Datasheet" "https://www.bourns.com/docs/product-datasheets/cr.pdf"
			(at 0 0 180)
			(layer "F.Fab")
			(hide yes)
			(effects
				(font
					(size 1.27 1.27)
					(thickness 0.15)
				)
			)
		)
		(property "Author" "Antmicro"
			(at 103.8 167.475 0)
			(layer "B.Fab")
			(hide yes)
			(effects
				(font
					(size 1 1)
					(thickness 0.15)
				)
				(justify mirror)
			)
		)
		(property "License" "Apache-2.0"
			(at 103.8 167.475 0)
			(layer "B.Fab")
			(hide yes)
			(effects
				(font
					(size 1 1)
					(thickness 0.15)
				)
				(justify mirror)
			)
		)
		(property "MPN" "CR0402-FX-1002GLF"
			(at 103.8 167.475 0)
			(layer "B.Fab")
			(hide yes)
			(effects
				(font
					(size 1 1)
					(thickness 0.15)
				)
				(justify mirror)
			)
		)
		(property "Manufacturer" "Bourns"
			(at 103.8 167.475 0)
			(layer "B.Fab")
			(hide yes)
			(effects
				(font
					(size 1 1)
					(thickness 0.15)
				)
				(justify mirror)
			)
		)
		(property "Tolerance" "1%"
			(at 103.8 167.475 0)
			(layer "B.Fab")
			(hide yes)
			(effects
				(font
					(size 1 1)
					(thickness 0.15)
				)
				(justify mirror)
			)
		)
		(property "Val" "10k"
			(at 103.8 167.475 0)
			(layer "B.Fab")
			(hide yes)
			(effects
				(font
					(size 1 1)
					(thickness 0.15)
				)
				(justify mirror)
			)
		)
		(sheetname "Ethernet")
		(sheetfile "ethernet.kicad_sch")
		(attr smd)
		(fp_rect
			(start -0.925 0.47)
			(end 0.925 -0.47)
			(stroke
				(width 0.05)
				(type default)
			)
			(fill none)
			(layer "B.CrtYd")
		)
		(fp_rect
			(start -0.5 0.25)
			(end 0.5 -0.25)
			(stroke
				(width 0.15)
				(type solid)
			)
			(fill none)
			(layer "B.Fab")
		)
		(fp_text user "Author: Antmicro"
			(at -0.95 -4.169 0)
			(layer "B.Fab")
			(hide yes)
			(effects
				(font
					(size 0.7 0.7)
					(thickness 0.15)
				)
				(justify left bottom mirror)
			)
		)
		(fp_text user "License: Apache-2.0"
			(at -0.95 -5.169 0)
			(layer "B.Fab")
			(hide yes)
			(effects
				(font
					(size 0.7 0.7)
					(thickness 0.15)
				)
				(justify left bottom mirror)
			)
		)
		(fp_text user "${REFERENCE}"
			(at -0.95 -3.168 0)
			(layer "B.Fab")
			(hide yes)
			(effects
				(font
					(size 0.7 0.7)
					(thickness 0.15)
				)
				(justify left bottom mirror)
			)
		)
		(pad "1" smd roundrect
			(at -0.48 0 180)
			(size 0.59 0.64)
			(layers "B.Cu" "B.Paste" "B.Mask")
			(roundrect_rratio 0.25)
			(net 127 "/Ethernet/POE_ACTIVE")
			(pintype "passive")
		)
		(pad "2" smd roundrect
			(at 0.48 0 180)
			(size 0.59 0.64)
			(layers "B.Cu" "B.Paste" "B.Mask")
			(roundrect_rratio 0.25)
			(net 571 "/Ethernet/PG")
			(pintype "passive")
		)
	)
	(footprint "antmicro-footprints:SOT-23-6"
		(layer "B.Cu")
		(at 68.5 75.25 -90)
		(property "Reference" "U38"
			(at 2.09 -15.76 90)
			(layer "B.SilkS")
			(effects
				(font
					(size 0.7 0.7)
					(thickness 0.15)
				)
				(justify left bottom mirror)
			)
		)
		(property "Value" "74LVC1G175_SOT457"
			(at -1.75 -2.75 90)
			(layer "B.Fab")
			(effects
				(font
					(size 0.7 0.7)
					(thickness 0.15)
				)
				(justify left bottom mirror)
			)
		)
		(property "Footprint" "antmicro-footprints:SOT-23-6"
			(at 0 0 90)
			(layer "B.Fab")
			(hide yes)
			(effects
				(font
					(size 1.27 1.27)
					(thickness 0.15)
				)
			)
		)
		(property "Datasheet" "https://www.mouser.com/datasheet/2/916/74LVC1G175-1480578.pdf"
			(at 0 0 90)
			(layer "B.Fab")
			(hide yes)
			(effects
				(font
					(size 1.27 1.27)
					(thickness 0.15)
				)
			)
		)
		(property "MPN" "74LVC1G175GV,125"
			(at 0 0 -90)
			(unlocked yes)
			(layer "B.Fab")
			(hide yes)
			(effects
				(font
					(size 1 1)
					(thickness 0.15)
				)
				(justify mirror)
			)
		)
		(property "Manufacturer" "Nexperia"
			(at 0 0 -90)
			(unlocked yes)
			(layer "B.Fab")
			(hide yes)
			(effects
				(font
					(size 1 1)
					(thickness 0.15)
				)
				(justify mirror)
			)
		)
		(property "Author" "Antmicro"
			(at 0 0 -90)
			(unlocked yes)
			(layer "B.Fab")
			(hide yes)
			(effects
				(font
					(size 1 1)
					(thickness 0.15)
				)
				(justify mirror)
			)
		)
		(property "License" "Apache-2.0"
			(at 0 0 -90)
			(unlocked yes)
			(layer "B.Fab")
			(hide yes)
			(effects
				(font
					(size 1 1)
					(thickness 0.15)
				)
				(justify mirror)
			)
		)
		(sheetname "Supply")
		(sheetfile "supply.kicad_sch")
		(attr smd)
		(fp_line
			(start -1.45 0.757)
			(end -1.3 0.757)
			(stroke
				(width 0.12)
				(type solid)
			)
			(layer "B.SilkS")
		)
		(fp_line
			(start 1.45 0.757)
			(end 1.3 0.757)
			(stroke
				(width 0.12)
				(type solid)
			)
			(layer "B.SilkS")
		)
		(fp_line
			(start -1.45 0.457)
			(end -1.45 0.757)
			(stroke
				(width 0.12)
				(type solid)
			)
			(layer "B.SilkS")
		)
		(fp_line
			(start 1.45 0.457)
			(end 1.45 0.757)
			(stroke
				(width 0.12)
				(type solid)
			)
			(layer "B.SilkS")
		)
		(fp_line
			(start -1.45 -0.343)
			(end -1.45 -0.643)
			(stroke
				(width 0.12)
				(type solid)
			)
			(layer "B.SilkS")
		)
		(fp_line
			(start 1.45 -0.343)
			(end 1.45 -0.643)
			(stroke
				(width 0.12)
				(type solid)
			)
			(layer "B.SilkS")
		)
		(fp_line
			(start 1.45 -0.643)
			(end 1.3 -0.643)
			(stroke
				(width 0.12)
				(type solid)
			)
			(layer "B.SilkS")
		)
		(fp_rect
			(start -1.55 1.85)
			(end 1.55 -1.75)
			(stroke
				(width 0.05)
				(type solid)
			)
			(fill none)
			(layer "B.CrtYd")
		)
		(fp_line
			(start -1.5 0.757)
			(end -1.5 -0.643)
			(stroke
				(width 0.1)
				(type solid)
			)
			(layer "B.Fab")
		)
		(fp_line
			(start 1.5 0.757)
			(end -1.5 0.757)
			(stroke
				(width 0.1)
				(type solid)
			)
			(layer "B.Fab")
		)
		(fp_line
			(start -1.5 -0.643)
			(end 1.5 -0.643)
			(stroke
				(width 0.1)
				(type solid)
			)
			(layer "B.Fab")
		)
		(fp_line
			(start 1.5 -0.643)
			(end 1.5 0.757)
			(stroke
				(width 0.1)
				(type solid)
			)
			(layer "B.Fab")
		)
		(fp_text user "."
			(at -1.4 -1.2 90)
			(layer "B.SilkS")
			(effects
				(font
					(size 1 1)
					(thickness 0.15)
				)
				(justify mirror)
			)
		)
		(fp_text user "${REFERENCE}"
			(at -1.75 -4 90)
			(layer "B.Fab")
			(hide yes)
			(effects
				(font
					(size 0.7 0.7)
					(thickness 0.15)
				)
				(justify left bottom mirror)
			)
		)
		(fp_text user "License: Apache-2.0"
			(at -1.75 -6.5 90)
			(layer "B.Fab")
			(hide yes)
			(effects
				(font
					(size 0.7 0.7)
					(thickness 0.15)
				)
				(justify left bottom mirror)
			)
		)
		(fp_text user "Author: Antmicro"
			(at -1.829 -5.25 90)
			(layer "B.Fab")
			(hide yes)
			(effects
				(font
					(size 0.7 0.7)
					(thickness 0.15)
				)
				(justify left bottom mirror)
			)
		)
		(pad "1" smd roundrect
			(at -0.954 -1.1 270)
			(size 0.55 1)
			(layers "B.Cu" "B.Paste" "B.Mask")
			(roundrect_rratio 0.15)
			(net 688 "Net-(U38-CLK)")
			(pinfunction "CLK")
			(pintype "input")
		)
		(pad "2" smd roundrect
			(at -0.003 -1.1 270)
			(size 0.55 1)
			(layers "B.Cu" "B.Paste" "B.Mask")
			(roundrect_rratio 0.15)
			(net 1 "GND")
			(pinfunction "GND")
			(pintype "power_in")
		)
		(pad "3" smd roundrect
			(at 0.947 -1.1 270)
			(size 0.55 1)
			(layers "B.Cu" "B.Paste" "B.Mask")
			(roundrect_rratio 0.15)
			(net 117 "3V3_STDB")
			(pinfunction "D")
			(pintype "input")
		)
		(pad "4" smd roundrect
			(at 0.947 1.214 270)
			(size 0.55 1)
			(layers "B.Cu" "B.Paste" "B.Mask")
			(roundrect_rratio 0.15)
			(net 689 "Net-(U38-Q)")
			(pinfunction "Q")
			(pintype "output")
		)
		(pad "5" smd roundrect
			(at -0.003 1.214 270)
			(size 0.55 1)
			(layers "B.Cu" "B.Paste" "B.Mask")
			(roundrect_rratio 0.15)
			(net 117 "3V3_STDB")
			(pinfunction "VCC")
			(pintype "power_in")
		)
		(pad "6" smd roundrect
			(at -0.954 1.214 270)
			(size 0.55 1)
			(layers "B.Cu" "B.Paste" "B.Mask")
			(roundrect_rratio 0.15)
			(net 629 "Net-(D37-A)")
			(pinfunction "~{CLR}")
			(pintype "input")
		)
	)
	(footprint "antmicro-footprints:R_0402_1005Metric"
		(layer "B.Cu")
		(at 108.7 110.3)
		(descr "Resistor SMD 0402")
		(tags "resistor SMD 0402")
		(property "Reference" "R61"
			(at 2.97 0.52 180)
			(layer "B.SilkS")
			(effects
				(font
					(size 0.7 0.7)
					(thickness 0.15)
				)
				(justify left bottom mirror)
			)
		)
		(property "Value" "R_200k_0402"
			(at 0 -1.4 180)
			(layer "B.Fab")
			(effects
				(font
					(size 0.7 0.7)
					(thickness 0.15)
				)
				(justify left bottom mirror)
			)
		)
		(property "Footprint" "antmicro-footprints:R_0402_1005Metric"
			(at 0 0 0)
			(layer "F.Fab")
			(hide yes)
			(effects
				(font
					(size 1.27 1.27)
					(thickness 0.15)
				)
			)
		)
		(property "Datasheet" "https://www.bourns.com/docs/product-datasheets/cr.pdf"
			(at 0 0 0)
			(layer "F.Fab")
			(hide yes)
			(effects
				(font
					(size 1.27 1.27)
					(thickness 0.15)
				)
			)
		)
		(property "Author" "Antmicro"
			(at 0 0 0)
			(layer "B.Fab")
			(hide yes)
			(effects
				(font
					(size 1 1)
					(thickness 0.15)
				)
				(justify mirror)
			)
		)
		(property "License" "Apache-2.0"
			(at 0 0 0)
			(layer "B.Fab")
			(hide yes)
			(effects
				(font
					(size 1 1)
					(thickness 0.15)
				)
				(justify mirror)
			)
		)
		(property "MPN" "CR0402-FX-2003GLF"
			(at 0 0 0)
			(layer "B.Fab")
			(hide yes)
			(effects
				(font
					(size 1 1)
					(thickness 0.15)
				)
				(justify mirror)
			)
		)
		(property "Manufacturer" "Bourns"
			(at 0 0 0)
			(layer "B.Fab")
			(hide yes)
			(effects
				(font
					(size 1 1)
					(thickness 0.15)
				)
				(justify mirror)
			)
		)
		(property "Tolerance" "1%"
			(at 0 0 0)
			(layer "B.Fab")
			(hide yes)
			(effects
				(font
					(size 1 1)
					(thickness 0.15)
				)
				(justify mirror)
			)
		)
		(property "Val" "200k"
			(at 0 0 0)
			(layer "B.Fab")
			(hide yes)
			(effects
				(font
					(size 1 1)
					(thickness 0.15)
				)
				(justify mirror)
			)
		)
		(sheetname "USB3")
		(sheetfile "usb3.kicad_sch")
		(attr smd)
		(fp_rect
			(start -0.925 0.47)
			(end 0.925 -0.47)
			(stroke
				(width 0.05)
				(type default)
			)
			(fill none)
			(layer "B.CrtYd")
		)
		(fp_rect
			(start -0.5 0.25)
			(end 0.5 -0.25)
			(stroke
				(width 0.15)
				(type solid)
			)
			(fill none)
			(layer "B.Fab")
		)
		(fp_text user "Author: Antmicro"
			(at -0.95 -4.169 180)
			(layer "B.Fab")
			(hide yes)
			(effects
				(font
					(size 0.7 0.7)
					(thickness 0.15)
				)
				(justify left bottom mirror)
			)
		)
		(fp_text user "${REFERENCE}"
			(at -0.95 -3.168 180)
			(layer "B.Fab")
			(hide yes)
			(effects
				(font
					(size 0.7 0.7)
					(thickness 0.15)
				)
				(justify left bottom mirror)
			)
		)
		(fp_text user "License: Apache-2.0"
			(at -0.95 -5.169 180)
			(layer "B.Fab")
			(hide yes)
			(effects
				(font
					(size 0.7 0.7)
					(thickness 0.15)
				)
				(justify left bottom mirror)
			)
		)
		(pad "1" smd roundrect
			(at -0.48 0)
			(size 0.59 0.64)
			(layers "B.Cu" "B.Paste" "B.Mask")
			(roundrect_rratio 0.25)
			(net 1 "GND")
			(pintype "passive")
		)
		(pad "2" smd roundrect
			(at 0.48 0)
			(size 0.59 0.64)
			(layers "B.Cu" "B.Paste" "B.Mask")
			(roundrect_rratio 0.25)
			(net 632 "Net-(Q19-G)")
			(pintype "passive")
		)
	)
	(footprint "antmicro-footprints:R_0402_1005Metric"
		(layer "B.Cu")
		(at 47.55 120.65 180)
		(descr "Resistor SMD 0402")
		(tags "resistor SMD 0402")
		(property "Reference" "R270"
			(at 6.93 1.04 0)
			(layer "B.SilkS")
			(effects
				(font
					(size 0.7 0.7)
					(thickness 0.15)
				)
				(justify left bottom mirror)
			)
		)
		(property "Value" "R_100k_0402"
			(at -1.011843 -1.772047 0)
			(layer "B.Fab")
			(effects
				(font
					(size 0.7 0.7)
					(thickness 0.15)
				)
				(justify left bottom mirror)
			)
		)
		(property "Footprint" "antmicro-footprints:R_0402_1005Metric"
			(at 0 0 180)
			(layer "F.Fab")
			(hide yes)
			(effects
				(font
					(size 1.27 1.27)
					(thickness 0.15)
				)
			)
		)
		(property "Datasheet" "https://www.bourns.com/docs/product-datasheets/cr.pdf"
			(at 0 0 180)
			(layer "F.Fab")
			(hide yes)
			(effects
				(font
					(size 1.27 1.27)
					(thickness 0.15)
				)
			)
		)
		(property "Author" "Antmicro"
			(at 95.1 241.3 0)
			(layer "B.Fab")
			(hide yes)
			(effects
				(font
					(size 1 1)
					(thickness 0.15)
				)
				(justify mirror)
			)
		)
		(property "License" "Apache-2.0"
			(at 95.1 241.3 0)
			(layer "B.Fab")
			(hide yes)
			(effects
				(font
					(size 1 1)
					(thickness 0.15)
				)
				(justify mirror)
			)
		)
		(property "MPN" "CR0402-FX-1003GLF"
			(at 95.1 241.3 0)
			(layer "B.Fab")
			(hide yes)
			(effects
				(font
					(size 1 1)
					(thickness 0.15)
				)
				(justify mirror)
			)
		)
		(property "Manufacturer" "Bourns"
			(at 95.1 241.3 0)
			(layer "B.Fab")
			(hide yes)
			(effects
				(font
					(size 1 1)
					(thickness 0.15)
				)
				(justify mirror)
			)
		)
		(property "Tolerance" "1%"
			(at 95.1 241.3 0)
			(layer "B.Fab")
			(hide yes)
			(effects
				(font
					(size 1 1)
					(thickness 0.15)
				)
				(justify mirror)
			)
		)
		(property "Val" "100k"
			(at 95.1 241.3 0)
			(layer "B.Fab")
			(hide yes)
			(effects
				(font
					(size 1 1)
					(thickness 0.15)
				)
				(justify mirror)
			)
		)
		(sheetname "USB Debug, DP")
		(sheetfile "usb.kicad_sch")
		(attr smd)
		(fp_rect
			(start -0.925 0.47)
			(end 0.925 -0.47)
			(stroke
				(width 0.05)
				(type default)
			)
			(fill none)
			(layer "B.CrtYd")
		)
		(fp_rect
			(start -0.5 0.25)
			(end 0.5 -0.25)
			(stroke
				(width 0.15)
				(type solid)
			)
			(fill none)
			(layer "B.Fab")
		)
		(fp_text user "License: Apache-2.0"
			(at -0.95 -5.169 0)
			(layer "B.Fab")
			(hide yes)
			(effects
				(font
					(size 0.7 0.7)
					(thickness 0.15)
				)
				(justify left bottom mirror)
			)
		)
		(fp_text user "Author: Antmicro"
			(at -0.95 -4.169 0)
			(layer "B.Fab")
			(hide yes)
			(effects
				(font
					(size 0.7 0.7)
					(thickness 0.15)
				)
				(justify left bottom mirror)
			)
		)
		(fp_text user "${REFERENCE}"
			(at -0.95 -3.168 0)
			(layer "B.Fab")
			(hide yes)
			(effects
				(font
					(size 0.7 0.7)
					(thickness 0.15)
				)
				(justify left bottom mirror)
			)
		)
		(pad "1" smd roundrect
			(at -0.48 0 180)
			(size 0.59 0.64)
			(layers "B.Cu" "B.Paste" "B.Mask")
			(roundrect_rratio 0.25)
			(net 397 "/USB Debug, DP/FTDI_CBUS_EN")
			(pintype "passive")
		)
		(pad "2" smd roundrect
			(at 0.48 0 180)
			(size 0.59 0.64)
			(layers "B.Cu" "B.Paste" "B.Mask")
			(roundrect_rratio 0.25)
			(net 185 "/USB Debug, DP/FTDI_3V3")
			(pintype "passive")
		)
	)
	(footprint "antmicro-footprints:C_0402_1005Metric"
		(layer "B.Cu")
		(at 66.6 86.8 90)
		(descr "Capacitor SMD 0402")
		(tags "capacitor SMD 0402")
		(property "Reference" "C97"
			(at 0.92 -0.48 -90)
			(layer "B.SilkS")
			(effects
				(font
					(size 0.7 0.7)
					(thickness 0.15)
				)
				(justify left bottom mirror)
			)
		)
		(property "Value" "C_100n_0402"
			(at 0 -1.4 -90)
			(layer "B.Fab")
			(effects
				(font
					(size 0.7 0.7)
					(thickness 0.15)
				)
				(justify left bottom mirror)
			)
		)
		(property "Footprint" "antmicro-footprints:C_0402_1005Metric"
			(at 0 0 90)
			(layer "F.Fab")
			(hide yes)
			(effects
				(font
					(size 1.27 1.27)
					(thickness 0.15)
				)
			)
		)
		(property "Datasheet" "https://www.murata.com/products/productdetail?partno=GRM155R61H104KE14%23"
			(at 0 0 90)
			(layer "F.Fab")
			(hide yes)
			(effects
				(font
					(size 1.27 1.27)
					(thickness 0.15)
				)
			)
		)
		(property "Author" "Antmicro"
			(at 153.4 20.2 0)
			(layer "B.Fab")
			(hide yes)
			(effects
				(font
					(size 1 1)
					(thickness 0.15)
				)
				(justify mirror)
			)
		)
		(property "Dielectric" "X5R"
			(at 153.4 20.2 0)
			(layer "B.Fab")
			(hide yes)
			(effects
				(font
					(size 1 1)
					(thickness 0.15)
				)
				(justify mirror)
			)
		)
		(property "License" "Apache-2.0"
			(at 153.4 20.2 0)
			(layer "B.Fab")
			(hide yes)
			(effects
				(font
					(size 1 1)
					(thickness 0.15)
				)
				(justify mirror)
			)
		)
		(property "MPN" "GRM155R61H104KE14D"
			(at 153.4 20.2 0)
			(layer "B.Fab")
			(hide yes)
			(effects
				(font
					(size 1 1)
					(thickness 0.15)
				)
				(justify mirror)
			)
		)
		(property "Manufacturer" "Murata"
			(at 153.4 20.2 0)
			(layer "B.Fab")
			(hide yes)
			(effects
				(font
					(size 1 1)
					(thickness 0.15)
				)
				(justify mirror)
			)
		)
		(property "Val" "100n"
			(at 153.4 20.2 0)
			(layer "B.Fab")
			(hide yes)
			(effects
				(font
					(size 1 1)
					(thickness 0.15)
				)
				(justify mirror)
			)
		)
		(property "Voltage" "50V"
			(at 153.4 20.2 0)
			(layer "B.Fab")
			(hide yes)
			(effects
				(font
					(size 1 1)
					(thickness 0.15)
				)
				(justify mirror)
			)
		)
		(sheetname "CSI")
		(sheetfile "csi.kicad_sch")
		(attr smd)
		(fp_rect
			(start -0.925 0.47)
			(end 0.925 -0.47)
			(stroke
				(width 0.05)
				(type default)
			)
			(fill none)
			(layer "B.CrtYd")
		)
		(fp_line
			(start 0.504 -0.248)
			(end 0.504 0.25)
			(stroke
				(width 0.15)
				(type solid)
			)
			(layer "B.Fab")
		)
		(fp_line
			(start -0.494 -0.248)
			(end 0.504 -0.248)
			(stroke
				(width 0.15)
				(type solid)
			)
			(layer "B.Fab")
		)
		(fp_line
			(start 0.504 0.25)
			(end -0.494 0.25)
			(stroke
				(width 0.15)
				(type solid)
			)
			(layer "B.Fab")
		)
		(fp_line
			(start -0.494 0.25)
			(end -0.494 -0.248)
			(stroke
				(width 0.15)
				(type solid)
			)
			(layer "B.Fab")
		)
		(fp_text user "Author: Antmicro"
			(at -0.932 -4.17 -90)
			(layer "B.Fab")
			(hide yes)
			(effects
				(font
					(size 0.7 0.7)
					(thickness 0.15)
				)
				(justify left bottom mirror)
			)
		)
		(fp_text user "${REFERENCE}"
			(at -0.932 -3.168 -90)
			(layer "B.Fab")
			(hide yes)
			(effects
				(font
					(size 0.7 0.7)
					(thickness 0.15)
				)
				(justify left bottom mirror)
			)
		)
		(fp_text user "License: Apache-2.0"
			(at -0.932 -5.17 -90)
			(layer "B.Fab")
			(hide yes)
			(effects
				(font
					(size 0.7 0.7)
					(thickness 0.15)
				)
				(justify left bottom mirror)
			)
		)
		(pad "1" smd roundrect
			(at -0.48 0 90)
			(size 0.59 0.64)
			(layers "B.Cu" "B.Paste" "B.Mask")
			(roundrect_rratio 0.25)
			(net 1 "GND")
			(pintype "passive")
		)
		(pad "2" smd roundrect
			(at 0.48 0 90)
			(size 0.59 0.64)
			(layers "B.Cu" "B.Paste" "B.Mask")
			(roundrect_rratio 0.25)
			(net 112 "+1V8")
			(pintype "passive")
		)
	)
	(footprint "antmicro-footprints:XDFN-2_1x0.60mm"
		(layer "B.Cu")
		(at 117 71.1)
		(property "Reference" "D16"
			(at -0.53 1.4 180)
			(layer "B.SilkS")
			(effects
				(font
					(size 0.7 0.7)
					(thickness 0.15)
				)
				(justify right bottom mirror)
			)
		)
		(property "Value" "TPD1E0B04_XDFN-2"
			(at 0 -1.5 180)
			(layer "B.Fab")
			(effects
				(font
					(size 0.7 0.7)
					(thickness 0.15)
				)
				(justify left bottom mirror)
			)
		)
		(property "Footprint" "antmicro-footprints:XDFN-2_1x0.60mm"
			(at 0 0 0)
			(layer "F.Fab")
			(hide yes)
			(effects
				(font
					(size 1.27 1.27)
					(thickness 0.15)
				)
			)
		)
		(property "Datasheet" "https://www.ti.com/general/docs/suppproductinfo.tsp?distId=26&gotoUrl=https://www.ti.com/lit/gpn/tpd1e0b04"
			(at 0 0 0)
			(layer "F.Fab")
			(hide yes)
			(effects
				(font
					(size 1.27 1.27)
					(thickness 0.15)
				)
			)
		)
		(property "MPN" "TPD1E0B04DPYR"
			(at 0 0 0)
			(layer "B.Fab")
			(hide yes)
			(effects
				(font
					(size 1 1)
					(thickness 0.15)
				)
				(justify mirror)
			)
		)
		(property "Manufacturer" "Texas Instruments"
			(at 0 0 0)
			(layer "B.Fab")
			(hide yes)
			(effects
				(font
					(size 1 1)
					(thickness 0.15)
				)
				(justify mirror)
			)
		)
		(property "Author" "Antmicro"
			(at 0 0 0)
			(layer "B.Fab")
			(hide yes)
			(effects
				(font
					(size 1 1)
					(thickness 0.15)
				)
				(justify mirror)
			)
		)
		(property "License" "Apache-2.0"
			(at 0 0 0)
			(layer "B.Fab")
			(hide yes)
			(effects
				(font
					(size 1 1)
					(thickness 0.15)
				)
				(justify mirror)
			)
		)
		(sheetname "Peripherals")
		(sheetfile "peripherals.kicad_sch")
		(attr smd)
		(fp_rect
			(start -0.725 0.475)
			(end 0.725 -0.475)
			(stroke
				(width 0.05)
				(type solid)
			)
			(fill none)
			(layer "B.CrtYd")
		)
		(fp_rect
			(start -0.55 0.35)
			(end 0.55 -0.35)
			(stroke
				(width 0.15)
				(type solid)
			)
			(fill none)
			(layer "B.Fab")
		)
		(fp_text user "Author: Antmicro"
			(at -0.8 -4.4 180)
			(layer "B.Fab")
			(hide yes)
			(effects
				(font
					(size 0.7 0.7)
					(thickness 0.15)
				)
				(justify left bottom mirror)
			)
		)
		(fp_text user "${REFERENCE}"
			(at -0.8 -3.2 180)
			(layer "B.Fab")
			(hide yes)
			(effects
				(font
					(size 0.7 0.7)
					(thickness 0.15)
				)
				(justify left bottom mirror)
			)
		)
		(fp_text user "License: Apache-2.0"
			(at -0.8 -5.6 180)
			(layer "B.Fab")
			(hide yes)
			(effects
				(font
					(size 0.7 0.7)
					(thickness 0.15)
				)
				(justify left bottom mirror)
			)
		)
		(pad "1" smd roundrect
			(at -0.351 0)
			(size 0.3 0.5)
			(layers "B.Cu" "B.Paste" "B.Mask")
			(roundrect_rratio 0.25)
			(net 107 "USBSS1_RX_N")
			(pinfunction "C")
			(pintype "passive")
		)
		(pad "2" smd roundrect
			(at 0.349 0)
			(size 0.3 0.5)
			(layers "B.Cu" "B.Paste" "B.Mask")
			(roundrect_rratio 0.25)
			(net 1 "GND")
			(pinfunction "A")
			(pintype "passive")
		)
	)
	(footprint "antmicro-footprints:R_0402_1005Metric"
		(layer "B.Cu")
		(at 57.425 94.15 180)
		(descr "Resistor SMD 0402")
		(tags "resistor SMD 0402")
		(property "Reference" "R181"
			(at -1.5 -0.54 0)
			(layer "B.SilkS")
			(effects
				(font
					(size 0.7 0.7)
					(thickness 0.15)
				)
				(justify left top mirror)
			)
		)
		(property "Value" "R_10k_0402"
			(at -1.011843 -1.772047 0)
			(layer "B.Fab")
			(effects
				(font
					(size 0.7 0.7)
					(thickness 0.15)
				)
				(justify left top mirror)
			)
		)
		(property "Footprint" "antmicro-footprints:R_0402_1005Metric"
			(at 0 0 0)
			(layer "B.Fab")
			(hide yes)
			(effects
				(font
					(size 1.27 1.27)
					(thickness 0.15)
				)
				(justify mirror)
			)
		)
		(property "Datasheet" "https://www.bourns.com/docs/product-datasheets/cr.pdf"
			(at 0 0 0)
			(layer "B.Fab")
			(hide yes)
			(effects
				(font
					(size 1.27 1.27)
					(thickness 0.15)
				)
				(justify mirror)
			)
		)
		(property "Author" "Antmicro"
			(at 117.96 -178.14 0)
			(layer "B.Fab")
			(hide yes)
			(effects
				(font
					(size 1 1)
					(thickness 0.15)
				)
				(justify mirror)
			)
		)
		(property "License" "Apache-2.0"
			(at 117.96 -178.14 0)
			(layer "B.Fab")
			(hide yes)
			(effects
				(font
					(size 1 1)
					(thickness 0.15)
				)
				(justify mirror)
			)
		)
		(property "MPN" "CR0402-FX-1002GLF"
			(at 117.96 -178.14 0)
			(layer "B.Fab")
			(hide yes)
			(effects
				(font
					(size 1 1)
					(thickness 0.15)
				)
				(justify mirror)
			)
		)
		(property "Manufacturer" "Bourns"
			(at 117.96 -178.14 0)
			(layer "B.Fab")
			(hide yes)
			(effects
				(font
					(size 1 1)
					(thickness 0.15)
				)
				(justify mirror)
			)
		)
		(property "Tolerance" "1%"
			(at 117.96 -178.14 0)
			(layer "B.Fab")
			(hide yes)
			(effects
				(font
					(size 1 1)
					(thickness 0.15)
				)
				(justify mirror)
			)
		)
		(property "Val" "10k"
			(at 117.96 -178.14 0)
			(layer "B.Fab")
			(hide yes)
			(effects
				(font
					(size 1 1)
					(thickness 0.15)
				)
				(justify mirror)
			)
		)
		(sheetname "Supply")
		(sheetfile "supply.kicad_sch")
		(attr smd)
		(fp_rect
			(start -0.925 0.47)
			(end 0.925 -0.47)
			(stroke
				(width 0.05)
				(type default)
			)
			(fill none)
			(layer "B.CrtYd")
		)
		(fp_rect
			(start -0.5 0.25)
			(end 0.5 -0.25)
			(stroke
				(width 0.15)
				(type solid)
			)
			(fill none)
			(layer "B.Fab")
		)
		(fp_text user "License: Apache-2.0"
			(at -0.95 -5.169 0)
			(layer "B.Fab")
			(hide yes)
			(effects
				(font
					(size 0.7 0.7)
					(thickness 0.15)
				)
				(justify left top mirror)
			)
		)
		(fp_text user "Author: Antmicro"
			(at -0.95 -4.169 0)
			(layer "B.Fab")
			(hide yes)
			(effects
				(font
					(size 0.7 0.7)
					(thickness 0.15)
				)
				(justify left top mirror)
			)
		)
		(fp_text user "${REFERENCE}"
			(at -0.95 -3.168 0)
			(layer "B.Fab")
			(hide yes)
			(effects
				(font
					(size 0.7 0.7)
					(thickness 0.15)
				)
				(justify left top mirror)
			)
		)
		(pad "1" smd roundrect
			(at -0.48 0 180)
			(size 0.59 0.64)
			(layers "B.Cu" "B.Paste" "B.Mask")
			(roundrect_rratio 0.25)
			(net 768 "/Supply/5V_GATE")
			(pintype "passive")
		)
		(pad "2" smd roundrect
			(at 0.48 0 180)
			(size 0.59 0.64)
			(layers "B.Cu" "B.Paste" "B.Mask")
			(roundrect_rratio 0.25)
			(net 787 "+5V_SoM")
			(pintype "passive")
		)
	)
	(footprint "antmicro-footprints:C_0402_1005Metric"
		(layer "B.Cu")
		(at 93.15 85.85 -90)
		(descr "Capacitor SMD 0402")
		(tags "capacitor SMD 0402")
		(property "Reference" "C91"
			(at -1.09 0.61 90)
			(layer "B.SilkS")
			(effects
				(font
					(size 0.7 0.7)
					(thickness 0.15)
				)
				(justify left bottom mirror)
			)
		)
		(property "Value" "C_100n_0402"
			(at 0 -1.4 90)
			(layer "B.Fab")
			(effects
				(font
					(size 0.7 0.7)
					(thickness 0.15)
				)
				(justify left bottom mirror)
			)
		)
		(property "Footprint" "antmicro-footprints:C_0402_1005Metric"
			(at 0 0 -90)
			(layer "F.Fab")
			(hide yes)
			(effects
				(font
					(size 1.27 1.27)
					(thickness 0.15)
				)
			)
		)
		(property "Datasheet" "https://www.murata.com/products/productdetail?partno=GRM155R61H104KE14%23"
			(at 0 0 -90)
			(layer "F.Fab")
			(hide yes)
			(effects
				(font
					(size 1.27 1.27)
					(thickness 0.15)
				)
			)
		)
		(property "Author" "Antmicro"
			(at 7.3 179 0)
			(layer "B.Fab")
			(hide yes)
			(effects
				(font
					(size 1 1)
					(thickness 0.15)
				)
				(justify mirror)
			)
		)
		(property "Dielectric" "X5R"
			(at 7.3 179 0)
			(layer "B.Fab")
			(hide yes)
			(effects
				(font
					(size 1 1)
					(thickness 0.15)
				)
				(justify mirror)
			)
		)
		(property "License" "Apache-2.0"
			(at 7.3 179 0)
			(layer "B.Fab")
			(hide yes)
			(effects
				(font
					(size 1 1)
					(thickness 0.15)
				)
				(justify mirror)
			)
		)
		(property "MPN" "GRM155R61H104KE14D"
			(at 7.3 179 0)
			(layer "B.Fab")
			(hide yes)
			(effects
				(font
					(size 1 1)
					(thickness 0.15)
				)
				(justify mirror)
			)
		)
		(property "Manufacturer" "Murata"
			(at 7.3 179 0)
			(layer "B.Fab")
			(hide yes)
			(effects
				(font
					(size 1 1)
					(thickness 0.15)
				)
				(justify mirror)
			)
		)
		(property "Val" "100n"
			(at 7.3 179 0)
			(layer "B.Fab")
			(hide yes)
			(effects
				(font
					(size 1 1)
					(thickness 0.15)
				)
				(justify mirror)
			)
		)
		(property "Voltage" "50V"
			(at 7.3 179 0)
			(layer "B.Fab")
			(hide yes)
			(effects
				(font
					(size 1 1)
					(thickness 0.15)
				)
				(justify mirror)
			)
		)
		(sheetname "CSI")
		(sheetfile "csi.kicad_sch")
		(attr smd)
		(fp_rect
			(start -0.925 0.47)
			(end 0.925 -0.47)
			(stroke
				(width 0.05)
				(type default)
			)
			(fill none)
			(layer "B.CrtYd")
		)
		(fp_line
			(start -0.494 0.25)
			(end -0.494 -0.248)
			(stroke
				(width 0.15)
				(type solid)
			)
			(layer "B.Fab")
		)
		(fp_line
			(start 0.504 0.25)
			(end -0.494 0.25)
			(stroke
				(width 0.15)
				(type solid)
			)
			(layer "B.Fab")
		)
		(fp_line
			(start -0.494 -0.248)
			(end 0.504 -0.248)
			(stroke
				(width 0.15)
				(type solid)
			)
			(layer "B.Fab")
		)
		(fp_line
			(start 0.504 -0.248)
			(end 0.504 0.25)
			(stroke
				(width 0.15)
				(type solid)
			)
			(layer "B.Fab")
		)
		(fp_text user "Author: Antmicro"
			(at -0.932 -4.17 90)
			(layer "B.Fab")
			(hide yes)
			(effects
				(font
					(size 0.7 0.7)
					(thickness 0.15)
				)
				(justify left bottom mirror)
			)
		)
		(fp_text user "${REFERENCE}"
			(at -0.932 -3.168 90)
			(layer "B.Fab")
			(hide yes)
			(effects
				(font
					(size 0.7 0.7)
					(thickness 0.15)
				)
				(justify left bottom mirror)
			)
		)
		(fp_text user "License: Apache-2.0"
			(at -0.932 -5.17 90)
			(layer "B.Fab")
			(hide yes)
			(effects
				(font
					(size 0.7 0.7)
					(thickness 0.15)
				)
				(justify left bottom mirror)
			)
		)
		(pad "1" smd roundrect
			(at -0.48 0 270)
			(size 0.59 0.64)
			(layers "B.Cu" "B.Paste" "B.Mask")
			(roundrect_rratio 0.25)
			(net 87 "+3V3")
			(pintype "passive")
		)
		(pad "2" smd roundrect
			(at 0.48 0 270)
			(size 0.59 0.64)
			(layers "B.Cu" "B.Paste" "B.Mask")
			(roundrect_rratio 0.25)
			(net 1 "GND")
			(pintype "passive")
		)
	)
	(footprint "antmicro-footprints:R_0402_1005Metric"
		(layer "B.Cu")
		(at 91.71 102.99 -135)
		(descr "Resistor SMD 0402")
		(tags "resistor SMD 0402")
		(property "Reference" "R221"
			(at -2.884996 -1.343503 45)
			(layer "B.SilkS")
			(effects
				(font
					(size 0.7 0.7)
					(thickness 0.15)
				)
				(justify left bottom mirror)
			)
		)
		(property "Value" "R_499R_0402"
			(at -1.011843 -1.772046 45)
			(layer "B.Fab")
			(effects
				(font
					(size 0.7 0.7)
					(thickness 0.15)
				)
				(justify left bottom mirror)
			)
		)
		(property "Footprint" "antmicro-footprints:R_0402_1005Metric"
			(at 0 0 -135)
			(layer "F.Fab")
			(hide yes)
			(effects
				(font
					(size 1.27 1.27)
					(thickness 0.15)
				)
			)
		)
		(property "Datasheet" "https://www.mouser.com/datasheet/2/54/cr-1858361.pdf"
			(at 0 0 -135)
			(layer "F.Fab")
			(hide yes)
			(effects
				(font
					(size 1.27 1.27)
					(thickness 0.15)
				)
			)
		)
		(property "Author" "Antmicro"
			(at 83.733836 240.66369 0)
			(layer "B.Fab")
			(hide yes)
			(effects
				(font
					(size 1 1)
					(thickness 0.15)
				)
				(justify mirror)
			)
		)
		(property "License" "Apache-2.0"
			(at 83.733836 240.66369 0)
			(layer "B.Fab")
			(hide yes)
			(effects
				(font
					(size 1 1)
					(thickness 0.15)
				)
				(justify mirror)
			)
		)
		(property "MPN" "CR0402-FX-4990GLF"
			(at 83.733836 240.66369 0)
			(layer "B.Fab")
			(hide yes)
			(effects
				(font
					(size 1 1)
					(thickness 0.15)
				)
				(justify mirror)
			)
		)
		(property "Manufacturer" "Bourns"
			(at 83.733836 240.66369 0)
			(layer "B.Fab")
			(hide yes)
			(effects
				(font
					(size 1 1)
					(thickness 0.15)
				)
				(justify mirror)
			)
		)
		(property "Tolerance" "1%"
			(at 83.733836 240.66369 0)
			(layer "B.Fab")
			(hide yes)
			(effects
				(font
					(size 1 1)
					(thickness 0.15)
				)
				(justify mirror)
			)
		)
		(property "Val" "499R"
			(at 83.733836 240.66369 0)
			(layer "B.Fab")
			(hide yes)
			(effects
				(font
					(size 1 1)
					(thickness 0.15)
				)
				(justify mirror)
			)
		)
		(sheetname "HDMI")
		(sheetfile "hdmi.kicad_sch")
		(attr smd)
		(fp_poly
			(pts
				(xy -0.925 0.47) (xy 0.925 0.47) (xy 0.925 -0.47) (xy -0.925 -0.47)
			)
			(stroke
				(width 0.05)
				(type default)
			)
			(fill none)
			(layer "B.CrtYd")
		)
		(fp_poly
			(pts
				(xy -0.5 0.25) (xy 0.5 0.25) (xy 0.5 -0.25) (xy -0.5 -0.25)
			)
			(stroke
				(width 0.15)
				(type solid)
			)
			(fill none)
			(layer "B.Fab")
		)
		(fp_text user "Author: Antmicro"
			(at -0.95 -4.169 45)
			(layer "B.Fab")
			(hide yes)
			(effects
				(font
					(size 0.7 0.7)
					(thickness 0.15)
				)
				(justify left bottom mirror)
			)
		)
		(fp_text user "License: Apache-2.0"
			(at -0.949999 -5.169 45)
			(layer "B.Fab")
			(hide yes)
			(effects
				(font
					(size 0.7 0.7)
					(thickness 0.15)
				)
				(justify left bottom mirror)
			)
		)
		(fp_text user "${REFERENCE}"
			(at -0.95 -3.168 45)
			(layer "B.Fab")
			(hide yes)
			(effects
				(font
					(size 0.7 0.7)
					(thickness 0.15)
				)
				(justify left bottom mirror)
			)
		)
		(pad "1" smd roundrect
			(at -0.48 0 225)
			(size 0.59 0.64)
			(layers "B.Cu" "B.Paste" "B.Mask")
			(roundrect_rratio 0.25)
			(net 623 "Net-(Q2-D)")
			(pintype "passive")
		)
		(pad "2" smd roundrect
			(at 0.48 0 225)
			(size 0.59 0.64)
			(layers "B.Cu" "B.Paste" "B.Mask")
			(roundrect_rratio 0.25)
			(net 489 "/HDMI/HDMI_CLK_N")
			(pintype "passive")
		)
	)
	(footprint "antmicro-footprints:R_0402_1005Metric"
		(layer "B.Cu")
		(at 54.4 99.74 90)
		(descr "Resistor SMD 0402")
		(tags "resistor SMD 0402")
		(property "Reference" "R155"
			(at -1.4 -0.5 90)
			(layer "B.SilkS")
			(effects
				(font
					(size 0.7 0.7)
					(thickness 0.15)
				)
				(justify right bottom mirror)
			)
		)
		(property "Value" "R_1k_0402"
			(at 0 -1.4 90)
			(layer "B.Fab")
			(effects
				(font
					(size 0.7 0.7)
					(thickness 0.15)
				)
				(justify right bottom mirror)
			)
		)
		(property "Footprint" "antmicro-footprints:R_0402_1005Metric"
			(at 0 0 90)
			(layer "F.Fab")
			(hide yes)
			(effects
				(font
					(size 1.27 1.27)
					(thickness 0.15)
				)
			)
		)
		(property "Datasheet" "https://www.bourns.com/docs/product-datasheets/cr.pdf"
			(at 0 0 90)
			(layer "F.Fab")
			(hide yes)
			(effects
				(font
					(size 1.27 1.27)
					(thickness 0.15)
				)
			)
		)
		(property "Author" "Antmicro"
			(at 154.14 45.34 0)
			(layer "B.Fab")
			(hide yes)
			(effects
				(font
					(size 1 1)
					(thickness 0.15)
				)
				(justify mirror)
			)
		)
		(property "License" "Apache-2.0"
			(at 154.14 45.34 0)
			(layer "B.Fab")
			(hide yes)
			(effects
				(font
					(size 1 1)
					(thickness 0.15)
				)
				(justify mirror)
			)
		)
		(property "MPN" "CR0402-FX-1001GLF"
			(at 154.14 45.34 0)
			(layer "B.Fab")
			(hide yes)
			(effects
				(font
					(size 1 1)
					(thickness 0.15)
				)
				(justify mirror)
			)
		)
		(property "Manufacturer" "Bourns"
			(at 154.14 45.34 0)
			(layer "B.Fab")
			(hide yes)
			(effects
				(font
					(size 1 1)
					(thickness 0.15)
				)
				(justify mirror)
			)
		)
		(property "Tolerance" "1%"
			(at 154.14 45.34 0)
			(layer "B.Fab")
			(hide yes)
			(effects
				(font
					(size 1 1)
					(thickness 0.15)
				)
				(justify mirror)
			)
		)
		(property "Val" "1k"
			(at 154.14 45.34 0)
			(layer "B.Fab")
			(hide yes)
			(effects
				(font
					(size 1 1)
					(thickness 0.15)
				)
				(justify mirror)
			)
		)
		(sheetname "Ethernet")
		(sheetfile "ethernet.kicad_sch")
		(attr smd)
		(fp_rect
			(start -0.925 0.47)
			(end 0.925 -0.47)
			(stroke
				(width 0.05)
				(type default)
			)
			(fill none)
			(layer "B.CrtYd")
		)
		(fp_rect
			(start -0.5 0.25)
			(end 0.5 -0.25)
			(stroke
				(width 0.15)
				(type solid)
			)
			(fill none)
			(layer "B.Fab")
		)
		(fp_text user "${REFERENCE}"
			(at -0.95 -3.168 90)
			(layer "B.Fab")
			(hide yes)
			(effects
				(font
					(size 0.7 0.7)
					(thickness 0.15)
				)
				(justify right bottom mirror)
			)
		)
		(fp_text user "License: Apache-2.0"
			(at -0.95 -5.169 90)
			(layer "B.Fab")
			(hide yes)
			(effects
				(font
					(size 0.7 0.7)
					(thickness 0.15)
				)
				(justify right bottom mirror)
			)
		)
		(fp_text user "Author: Antmicro"
			(at -0.95 -4.169 90)
			(layer "B.Fab")
			(hide yes)
			(effects
				(font
					(size 0.7 0.7)
					(thickness 0.15)
				)
				(justify right bottom mirror)
			)
		)
		(pad "1" smd roundrect
			(at -0.48 0 90)
			(size 0.59 0.64)
			(layers "B.Cu" "B.Paste" "B.Mask")
			(roundrect_rratio 0.25)
			(net 106 "GNDD")
			(pintype "passive")
		)
		(pad "2" smd roundrect
			(at 0.48 0 90)
			(size 0.59 0.64)
			(layers "B.Cu" "B.Paste" "B.Mask")
			(roundrect_rratio 0.25)
			(net 730 "Net-(R155-Pad2)")
			(pintype "passive")
		)
	)
	(footprint "antmicro-footprints:C_0402_1005Metric"
		(layer "B.Cu")
		(at 106 92.02 180)
		(descr "Capacitor SMD 0402")
		(tags "capacitor SMD 0402")
		(property "Reference" "C8"
			(at 0.8 -0.45 0)
			(layer "B.SilkS")
			(effects
				(font
					(size 0.7 0.7)
					(thickness 0.15)
				)
				(justify left bottom mirror)
			)
		)
		(property "Value" "C_100n_0402"
			(at 0 -1.4 0)
			(layer "B.Fab")
			(effects
				(font
					(size 0.7 0.7)
					(thickness 0.15)
				)
				(justify left bottom mirror)
			)
		)
		(property "Footprint" "antmicro-footprints:C_0402_1005Metric"
			(at 0 0 180)
			(layer "F.Fab")
			(hide yes)
			(effects
				(font
					(size 1.27 1.27)
					(thickness 0.15)
				)
			)
		)
		(property "Datasheet" "https://www.murata.com/products/productdetail?partno=GRM155R61H104KE14%23"
			(at 0 0 180)
			(layer "F.Fab")
			(hide yes)
			(effects
				(font
					(size 1.27 1.27)
					(thickness 0.15)
				)
			)
		)
		(property "Author" "Antmicro"
			(at 212 184.04 0)
			(layer "B.Fab")
			(hide yes)
			(effects
				(font
					(size 1 1)
					(thickness 0.15)
				)
				(justify mirror)
			)
		)
		(property "Dielectric" "X5R"
			(at 212 184.04 0)
			(layer "B.Fab")
			(hide yes)
			(effects
				(font
					(size 1 1)
					(thickness 0.15)
				)
				(justify mirror)
			)
		)
		(property "License" "Apache-2.0"
			(at 212 184.04 0)
			(layer "B.Fab")
			(hide yes)
			(effects
				(font
					(size 1 1)
					(thickness 0.15)
				)
				(justify mirror)
			)
		)
		(property "MPN" "GRM155R61H104KE14D"
			(at 212 184.04 0)
			(layer "B.Fab")
			(hide yes)
			(effects
				(font
					(size 1 1)
					(thickness 0.15)
				)
				(justify mirror)
			)
		)
		(property "Manufacturer" "Murata"
			(at 212 184.04 0)
			(layer "B.Fab")
			(hide yes)
			(effects
				(font
					(size 1 1)
					(thickness 0.15)
				)
				(justify mirror)
			)
		)
		(property "Val" "100n"
			(at 212 184.04 0)
			(layer "B.Fab")
			(hide yes)
			(effects
				(font
					(size 1 1)
					(thickness 0.15)
				)
				(justify mirror)
			)
		)
		(property "Voltage" "50V"
			(at 212 184.04 0)
			(layer "B.Fab")
			(hide yes)
			(effects
				(font
					(size 1 1)
					(thickness 0.15)
				)
				(justify mirror)
			)
		)
		(sheetname "M.2")
		(sheetfile "m-2.kicad_sch")
		(attr smd)
		(fp_rect
			(start -0.925 0.47)
			(end 0.925 -0.47)
			(stroke
				(width 0.05)
				(type default)
			)
			(fill none)
			(layer "B.CrtYd")
		)
		(fp_line
			(start 0.504 0.25)
			(end -0.494 0.25)
			(stroke
				(width 0.15)
				(type solid)
			)
			(layer "B.Fab")
		)
		(fp_line
			(start 0.504 -0.248)
			(end 0.504 0.25)
			(stroke
				(width 0.15)
				(type solid)
			)
			(layer "B.Fab")
		)
		(fp_line
			(start -0.494 0.25)
			(end -0.494 -0.248)
			(stroke
				(width 0.15)
				(type solid)
			)
			(layer "B.Fab")
		)
		(fp_line
			(start -0.494 -0.248)
			(end 0.504 -0.248)
			(stroke
				(width 0.15)
				(type solid)
			)
			(layer "B.Fab")
		)
		(fp_text user "Author: Antmicro"
			(at -0.932 -4.17 0)
			(layer "B.Fab")
			(hide yes)
			(effects
				(font
					(size 0.7 0.7)
					(thickness 0.15)
				)
				(justify left bottom mirror)
			)
		)
		(fp_text user "${REFERENCE}"
			(at -0.932 -3.168 0)
			(layer "B.Fab")
			(hide yes)
			(effects
				(font
					(size 0.7 0.7)
					(thickness 0.15)
				)
				(justify left bottom mirror)
			)
		)
		(fp_text user "License: Apache-2.0"
			(at -0.932 -5.17 0)
			(layer "B.Fab")
			(hide yes)
			(effects
				(font
					(size 0.7 0.7)
					(thickness 0.15)
				)
				(justify left bottom mirror)
			)
		)
		(pad "1" smd roundrect
			(at -0.48 0 180)
			(size 0.59 0.64)
			(layers "B.Cu" "B.Paste" "B.Mask")
			(roundrect_rratio 0.25)
			(net 635 "/M.2/3V3_M2")
			(pintype "passive")
		)
		(pad "2" smd roundrect
			(at 0.48 0 180)
			(size 0.59 0.64)
			(layers "B.Cu" "B.Paste" "B.Mask")
			(roundrect_rratio 0.25)
			(net 1 "GND")
			(pintype "passive")
		)
	)
	(footprint "antmicro-footprints:TP_SMD_0.75mm"
		(layer "B.Cu")
		(at 79.625 114.83 180)
		(property "Reference" "TP30"
			(at -0.435 3.095 90)
			(layer "B.SilkS")
			(effects
				(font
					(size 0.7 0.7)
					(thickness 0.15)
				)
				(justify left bottom mirror)
			)
		)
		(property "Value" "TP_0.75mm_SMD"
			(at 0 -1.2 0)
			(layer "B.Fab")
			(effects
				(font
					(size 0.7 0.7)
					(thickness 0.15)
				)
				(justify left bottom mirror)
			)
		)
		(property "Footprint" "antmicro-footprints:TP_SMD_0.75mm"
			(at 0 0 180)
			(layer "F.Fab")
			(hide yes)
			(effects
				(font
					(size 1.27 1.27)
					(thickness 0.15)
				)
			)
		)
		(property "Author" "Antmicro"
			(at 159.25 229.66 0)
			(layer "B.Fab")
			(hide yes)
			(effects
				(font
					(size 1 1)
					(thickness 0.15)
				)
				(justify mirror)
			)
		)
		(property "License" "Apache-2.0"
			(at 159.25 229.66 0)
			(layer "B.Fab")
			(hide yes)
			(effects
				(font
					(size 1 1)
					(thickness 0.15)
				)
				(justify mirror)
			)
		)
		(property "MPN" ""
			(at 159.25 229.66 0)
			(layer "B.Fab")
			(hide yes)
			(effects
				(font
					(size 1 1)
					(thickness 0.15)
				)
				(justify mirror)
			)
		)
		(property "Manufacturer" ""
			(at 159.25 229.66 0)
			(layer "B.Fab")
			(hide yes)
			(effects
				(font
					(size 1 1)
					(thickness 0.15)
				)
				(justify mirror)
			)
		)
		(sheetname "USB Debug, DP")
		(sheetfile "usb.kicad_sch")
		(attr exclude_from_pos_files exclude_from_bom)
		(fp_circle
			(center 0 0)
			(end 0.475 0)
			(stroke
				(width 0.05)
				(type default)
			)
			(fill none)
			(layer "B.CrtYd")
		)
		(fp_text user "Author: Antmicro"
			(at -0.4 -3.901 0)
			(layer "B.Fab")
			(hide yes)
			(effects
				(font
					(size 0.7 0.7)
					(thickness 0.15)
				)
				(justify left bottom mirror)
			)
		)
		(fp_text user "${REFERENCE}"
			(at -0.4 -2.7 0)
			(layer "B.Fab")
			(hide yes)
			(effects
				(font
					(size 0.7 0.7)
					(thickness 0.15)
				)
				(justify left bottom mirror)
			)
		)
		(fp_text user "License: Apache-2.0"
			(at -0.4 -5.101 0)
			(layer "B.Fab")
			(hide yes)
			(effects
				(font
					(size 0.7 0.7)
					(thickness 0.15)
				)
				(justify left bottom mirror)
			)
		)
		(pad "1" smd circle
			(at 0 0 180)
			(size 0.75 0.75)
			(layers "B.Cu" "B.Mask")
			(net 677 "USBC_HPD")
			(pinfunction "1")
			(pintype "passive")
		)
	)
	(footprint "antmicro-footprints:R_0402_1005Metric"
		(layer "B.Cu")
		(at 46.9 89.6375)
		(descr "Resistor SMD 0402")
		(tags "resistor SMD 0402")
		(property "Reference" "R145"
			(at 0.335 -3.4775 180)
			(layer "B.SilkS")
			(effects
				(font
					(size 0.7 0.7)
					(thickness 0.15)
				)
				(justify left bottom mirror)
			)
		)
		(property "Value" "R_1k2_0402"
			(at 0 -1.4 180)
			(layer "B.Fab")
			(effects
				(font
					(size 0.7 0.7)
					(thickness 0.15)
				)
				(justify left bottom mirror)
			)
		)
		(property "Footprint" "antmicro-footprints:R_0402_1005Metric"
			(at 0 0 0)
			(layer "F.Fab")
			(hide yes)
			(effects
				(font
					(size 1.27 1.27)
					(thickness 0.15)
				)
			)
		)
		(property "Datasheet" "https://www.bourns.com/docs/product-datasheets/cr.pdf"
			(at 0 0 0)
			(layer "F.Fab")
			(hide yes)
			(effects
				(font
					(size 1.27 1.27)
					(thickness 0.15)
				)
			)
		)
		(property "Author" "Antmicro"
			(at 0 0 0)
			(layer "B.Fab")
			(hide yes)
			(effects
				(font
					(size 1 1)
					(thickness 0.15)
				)
				(justify mirror)
			)
		)
		(property "License" "Apache-2.0"
			(at 0 0 0)
			(layer "B.Fab")
			(hide yes)
			(effects
				(font
					(size 1 1)
					(thickness 0.15)
				)
				(justify mirror)
			)
		)
		(property "MPN" "CR0402-FX-1201GLF"
			(at 0 0 0)
			(layer "B.Fab")
			(hide yes)
			(effects
				(font
					(size 1 1)
					(thickness 0.15)
				)
				(justify mirror)
			)
		)
		(property "Manufacturer" "Bourns"
			(at 0 0 0)
			(layer "B.Fab")
			(hide yes)
			(effects
				(font
					(size 1 1)
					(thickness 0.15)
				)
				(justify mirror)
			)
		)
		(property "Tolerance" "1%"
			(at 0 0 0)
			(layer "B.Fab")
			(hide yes)
			(effects
				(font
					(size 1 1)
					(thickness 0.15)
				)
				(justify mirror)
			)
		)
		(property "Val" "1k2"
			(at 0 0 0)
			(layer "B.Fab")
			(hide yes)
			(effects
				(font
					(size 1 1)
					(thickness 0.15)
				)
				(justify mirror)
			)
		)
		(sheetname "Ethernet")
		(sheetfile "ethernet.kicad_sch")
		(attr smd)
		(fp_rect
			(start -0.925 0.47)
			(end 0.925 -0.47)
			(stroke
				(width 0.05)
				(type default)
			)
			(fill none)
			(layer "B.CrtYd")
		)
		(fp_rect
			(start -0.5 0.25)
			(end 0.5 -0.25)
			(stroke
				(width 0.15)
				(type solid)
			)
			(fill none)
			(layer "B.Fab")
		)
		(fp_text user "${REFERENCE}"
			(at -0.95 -3.168 180)
			(layer "B.Fab")
			(hide yes)
			(effects
				(font
					(size 0.7 0.7)
					(thickness 0.15)
				)
				(justify left bottom mirror)
			)
		)
		(fp_text user "License: Apache-2.0"
			(at -0.95 -5.169 180)
			(layer "B.Fab")
			(hide yes)
			(effects
				(font
					(size 0.7 0.7)
					(thickness 0.15)
				)
				(justify left bottom mirror)
			)
		)
		(fp_text user "Author: Antmicro"
			(at -0.95 -4.169 180)
			(layer "B.Fab")
			(hide yes)
			(effects
				(font
					(size 0.7 0.7)
					(thickness 0.15)
				)
				(justify left bottom mirror)
			)
		)
		(pad "1" smd roundrect
			(at -0.48 0)
			(size 0.59 0.64)
			(layers "B.Cu" "B.Paste" "B.Mask")
			(roundrect_rratio 0.25)
			(net 499 "/Ethernet/VSS")
			(pintype "passive")
		)
		(pad "2" smd roundrect
			(at 0.48 0)
			(size 0.59 0.64)
			(layers "B.Cu" "B.Paste" "B.Mask")
			(roundrect_rratio 0.25)
			(net 569 "/Ethernet/CLSB")
			(pintype "passive")
		)
	)
	(footprint "antmicro-footprints:R_0402_1005Metric"
		(layer "B.Cu")
		(at 76 105.3 -90)
		(descr "Resistor SMD 0402")
		(tags "resistor SMD 0402")
		(property "Reference" "R88"
			(at -5.03 -1.69 90)
			(layer "B.SilkS")
			(effects
				(font
					(size 0.7 0.7)
					(thickness 0.15)
				)
				(justify left bottom mirror)
			)
		)
		(property "Value" "R_1k_0402"
			(at 0 -1.4 90)
			(layer "B.Fab")
			(effects
				(font
					(size 0.7 0.7)
					(thickness 0.15)
				)
				(justify left bottom mirror)
			)
		)
		(property "Footprint" "antmicro-footprints:R_0402_1005Metric"
			(at 0 0 -90)
			(layer "F.Fab")
			(hide yes)
			(effects
				(font
					(size 1.27 1.27)
					(thickness 0.15)
				)
			)
		)
		(property "Datasheet" "https://www.bourns.com/docs/product-datasheets/cr.pdf"
			(at 0 0 -90)
			(layer "F.Fab")
			(hide yes)
			(effects
				(font
					(size 1.27 1.27)
					(thickness 0.15)
				)
			)
		)
		(property "Author" "Antmicro"
			(at -29.3 181.3 0)
			(layer "B.Fab")
			(hide yes)
			(effects
				(font
					(size 1 1)
					(thickness 0.15)
				)
				(justify mirror)
			)
		)
		(property "License" "Apache-2.0"
			(at -29.3 181.3 0)
			(layer "B.Fab")
			(hide yes)
			(effects
				(font
					(size 1 1)
					(thickness 0.15)
				)
				(justify mirror)
			)
		)
		(property "MPN" "CR0402-FX-1001GLF"
			(at -29.3 181.3 0)
			(layer "B.Fab")
			(hide yes)
			(effects
				(font
					(size 1 1)
					(thickness 0.15)
				)
				(justify mirror)
			)
		)
		(property "Manufacturer" "Bourns"
			(at -29.3 181.3 0)
			(layer "B.Fab")
			(hide yes)
			(effects
				(font
					(size 1 1)
					(thickness 0.15)
				)
				(justify mirror)
			)
		)
		(property "Tolerance" "1%"
			(at -29.3 181.3 0)
			(layer "B.Fab")
			(hide yes)
			(effects
				(font
					(size 1 1)
					(thickness 0.15)
				)
				(justify mirror)
			)
		)
		(property "Val" "1k"
			(at -29.3 181.3 0)
			(layer "B.Fab")
			(hide yes)
			(effects
				(font
					(size 1 1)
					(thickness 0.15)
				)
				(justify mirror)
			)
		)
		(sheetname "USB Debug, DP")
		(sheetfile "usb.kicad_sch")
		(attr smd exclude_from_pos_files exclude_from_bom dnp)
		(fp_rect
			(start -0.925 0.47)
			(end 0.925 -0.47)
			(stroke
				(width 0.05)
				(type default)
			)
			(fill none)
			(layer "B.CrtYd")
		)
		(fp_rect
			(start -0.5 0.25)
			(end 0.5 -0.25)
			(stroke
				(width 0.15)
				(type solid)
			)
			(fill none)
			(layer "B.Fab")
		)
		(fp_text user "License: Apache-2.0"
			(at -0.95 -5.169 90)
			(layer "B.Fab")
			(hide yes)
			(effects
				(font
					(size 0.7 0.7)
					(thickness 0.15)
				)
				(justify left bottom mirror)
			)
		)
		(fp_text user "${REFERENCE}"
			(at -0.95 -3.168 90)
			(layer "B.Fab")
			(hide yes)
			(effects
				(font
					(size 0.7 0.7)
					(thickness 0.15)
				)
				(justify left bottom mirror)
			)
		)
		(fp_text user "Author: Antmicro"
			(at -0.95 -4.169 90)
			(layer "B.Fab")
			(hide yes)
			(effects
				(font
					(size 0.7 0.7)
					(thickness 0.15)
				)
				(justify left bottom mirror)
			)
		)
		(pad "1" smd roundrect
			(at -0.48 0 270)
			(size 0.59 0.64)
			(layers "B.Cu" "B.Paste" "B.Mask")
			(roundrect_rratio 0.25)
			(net 305 "/USB Debug, DP/USBC0_SSEQ0")
			(pintype "passive")
		)
		(pad "2" smd roundrect
			(at 0.48 0 270)
			(size 0.59 0.64)
			(layers "B.Cu" "B.Paste" "B.Mask")
			(roundrect_rratio 0.25)
			(net 1 "GND")
			(pintype "passive")
		)
	)
	(footprint "antmicro-footprints:XDFN-2_1x0.60mm"
		(layer "B.Cu")
		(at 101.5 123.8)
		(property "Reference" "D55"
			(at -1.05 -0.6 180)
			(layer "B.SilkS")
			(effects
				(font
					(size 0.7 0.7)
					(thickness 0.15)
				)
				(justify right bottom mirror)
			)
		)
		(property "Value" "TPD1E0B04_XDFN-2"
			(at 0 -1.5 180)
			(layer "B.Fab")
			(effects
				(font
					(size 0.7 0.7)
					(thickness 0.15)
				)
				(justify left bottom mirror)
			)
		)
		(property "Footprint" "antmicro-footprints:XDFN-2_1x0.60mm"
			(at 0 0 0)
			(layer "F.Fab")
			(hide yes)
			(effects
				(font
					(size 1.27 1.27)
					(thickness 0.15)
				)
			)
		)
		(property "Datasheet" "https://www.ti.com/general/docs/suppproductinfo.tsp?distId=26&gotoUrl=https://www.ti.com/lit/gpn/tpd1e0b04"
			(at 0 0 0)
			(layer "F.Fab")
			(hide yes)
			(effects
				(font
					(size 1.27 1.27)
					(thickness 0.15)
				)
			)
		)
		(property "MPN" "TPD1E0B04DPYR"
			(at 0 0 0)
			(layer "B.Fab")
			(hide yes)
			(effects
				(font
					(size 1 1)
					(thickness 0.15)
				)
				(justify mirror)
			)
		)
		(property "Manufacturer" "Texas Instruments"
			(at 0 0 0)
			(layer "B.Fab")
			(hide yes)
			(effects
				(font
					(size 1 1)
					(thickness 0.15)
				)
				(justify mirror)
			)
		)
		(property "Author" "Antmicro"
			(at 0 0 0)
			(layer "B.Fab")
			(hide yes)
			(effects
				(font
					(size 1 1)
					(thickness 0.15)
				)
				(justify mirror)
			)
		)
		(property "License" "Apache-2.0"
			(at 0 0 0)
			(layer "B.Fab")
			(hide yes)
			(effects
				(font
					(size 1 1)
					(thickness 0.15)
				)
				(justify mirror)
			)
		)
		(sheetname "SoM")
		(sheetfile "som.kicad_sch")
		(attr smd)
		(fp_rect
			(start -0.725 0.475)
			(end 0.725 -0.475)
			(stroke
				(width 0.05)
				(type solid)
			)
			(fill none)
			(layer "B.CrtYd")
		)
		(fp_rect
			(start -0.55 0.35)
			(end 0.55 -0.35)
			(stroke
				(width 0.15)
				(type solid)
			)
			(fill none)
			(layer "B.Fab")
		)
		(fp_text user "Author: Antmicro"
			(at -0.8 -4.4 180)
			(layer "B.Fab")
			(hide yes)
			(effects
				(font
					(size 0.7 0.7)
					(thickness 0.15)
				)
				(justify left bottom mirror)
			)
		)
		(fp_text user "License: Apache-2.0"
			(at -0.8 -5.6 180)
			(layer "B.Fab")
			(hide yes)
			(effects
				(font
					(size 0.7 0.7)
					(thickness 0.15)
				)
				(justify left bottom mirror)
			)
		)
		(fp_text user "${REFERENCE}"
			(at -0.8 -3.2 180)
			(layer "B.Fab")
			(hide yes)
			(effects
				(font
					(size 0.7 0.7)
					(thickness 0.15)
				)
				(justify left bottom mirror)
			)
		)
		(pad "1" smd roundrect
			(at -0.351 0)
			(size 0.3 0.5)
			(layers "B.Cu" "B.Paste" "B.Mask")
			(roundrect_rratio 0.25)
			(net 1 "GND")
			(pinfunction "C")
			(pintype "passive")
		)
		(pad "2" smd roundrect
			(at 0.349 0)
			(size 0.3 0.5)
			(layers "B.Cu" "B.Paste" "B.Mask")
			(roundrect_rratio 0.25)
			(net 80 "/SoM/~{FORCE_RECOVERY}")
			(pinfunction "A")
			(pintype "passive")
		)
	)
	(footprint "antmicro-footprints:C_0402_1005Metric"
		(layer "B.Cu")
		(at 97.45 89.25)
		(descr "Capacitor SMD 0402")
		(tags "capacitor SMD 0402")
		(property "Reference" "C131"
			(at 3.8 0.07 180)
			(layer "B.SilkS")
			(effects
				(font
					(size 0.7 0.7)
					(thickness 0.15)
				)
				(justify left bottom mirror)
			)
		)
		(property "Value" "C_100n_0402"
			(at 0 -1.4 180)
			(layer "B.Fab")
			(effects
				(font
					(size 0.7 0.7)
					(thickness 0.15)
				)
				(justify left bottom mirror)
			)
		)
		(property "Footprint" "antmicro-footprints:C_0402_1005Metric"
			(at 0 0 0)
			(layer "F.Fab")
			(hide yes)
			(effects
				(font
					(size 1.27 1.27)
					(thickness 0.15)
				)
			)
		)
		(property "Datasheet" "https://www.murata.com/products/productdetail?partno=GRM155R61H104KE14%23"
			(at 0 0 0)
			(layer "F.Fab")
			(hide yes)
			(effects
				(font
					(size 1.27 1.27)
					(thickness 0.15)
				)
			)
		)
		(property "Author" "Antmicro"
			(at 0 0 0)
			(layer "B.Fab")
			(hide yes)
			(effects
				(font
					(size 1 1)
					(thickness 0.15)
				)
				(justify mirror)
			)
		)
		(property "Dielectric" "X5R"
			(at 0 0 0)
			(layer "B.Fab")
			(hide yes)
			(effects
				(font
					(size 1 1)
					(thickness 0.15)
				)
				(justify mirror)
			)
		)
		(property "License" "Apache-2.0"
			(at 0 0 0)
			(layer "B.Fab")
			(hide yes)
			(effects
				(font
					(size 1 1)
					(thickness 0.15)
				)
				(justify mirror)
			)
		)
		(property "MPN" "GRM155R61H104KE14D"
			(at 0 0 0)
			(layer "B.Fab")
			(hide yes)
			(effects
				(font
					(size 1 1)
					(thickness 0.15)
				)
				(justify mirror)
			)
		)
		(property "Manufacturer" "Murata"
			(at 0 0 0)
			(layer "B.Fab")
			(hide yes)
			(effects
				(font
					(size 1 1)
					(thickness 0.15)
				)
				(justify mirror)
			)
		)
		(property "Val" "100n"
			(at 0 0 0)
			(layer "B.Fab")
			(hide yes)
			(effects
				(font
					(size 1 1)
					(thickness 0.15)
				)
				(justify mirror)
			)
		)
		(property "Voltage" "50V"
			(at 0 0 0)
			(layer "B.Fab")
			(hide yes)
			(effects
				(font
					(size 1 1)
					(thickness 0.15)
				)
				(justify mirror)
			)
		)
		(sheetname "HDMI")
		(sheetfile "hdmi.kicad_sch")
		(attr smd)
		(fp_rect
			(start -0.925 0.47)
			(end 0.925 -0.47)
			(stroke
				(width 0.05)
				(type default)
			)
			(fill none)
			(layer "B.CrtYd")
		)
		(fp_line
			(start -0.494 -0.248)
			(end 0.504 -0.248)
			(stroke
				(width 0.15)
				(type solid)
			)
			(layer "B.Fab")
		)
		(fp_line
			(start -0.494 0.25)
			(end -0.494 -0.248)
			(stroke
				(width 0.15)
				(type solid)
			)
			(layer "B.Fab")
		)
		(fp_line
			(start 0.504 -0.248)
			(end 0.504 0.25)
			(stroke
				(width 0.15)
				(type solid)
			)
			(layer "B.Fab")
		)
		(fp_line
			(start 0.504 0.25)
			(end -0.494 0.25)
			(stroke
				(width 0.15)
				(type solid)
			)
			(layer "B.Fab")
		)
		(fp_text user "${REFERENCE}"
			(at -0.932 -3.168 180)
			(layer "B.Fab")
			(hide yes)
			(effects
				(font
					(size 0.7 0.7)
					(thickness 0.15)
				)
				(justify left bottom mirror)
			)
		)
		(fp_text user "Author: Antmicro"
			(at -0.932 -4.17 180)
			(layer "B.Fab")
			(hide yes)
			(effects
				(font
					(size 0.7 0.7)
					(thickness 0.15)
				)
				(justify left bottom mirror)
			)
		)
		(fp_text user "License: Apache-2.0"
			(at -0.932 -5.17 180)
			(layer "B.Fab")
			(hide yes)
			(effects
				(font
					(size 0.7 0.7)
					(thickness 0.15)
				)
				(justify left bottom mirror)
			)
		)
		(pad "1" smd roundrect
			(at -0.48 0)
			(size 0.59 0.64)
			(layers "B.Cu" "B.Paste" "B.Mask")
			(roundrect_rratio 0.25)
			(net 665 "/HDMI/DP_MUX_D0+")
			(pintype "passive")
		)
		(pad "2" smd roundrect
			(at 0.48 0)
			(size 0.59 0.64)
			(layers "B.Cu" "B.Paste" "B.Mask")
			(roundrect_rratio 0.25)
			(net 422 "DP1_TXD3_HDMI_TXC_P")
			(pintype "passive")
		)
	)
	(footprint "antmicro-footprints:C_1206_3216Metric"
		(layer "B.Cu")
		(at 31.5 72 -90)
		(descr "Capacitor SMD 1206")
		(tags "capacitor SMD 1206")
		(property "Reference" "C85"
			(at 0.8 -2 90)
			(layer "B.SilkS")
			(effects
				(font
					(size 0.7 0.7)
					(thickness 0.15)
				)
				(justify left bottom mirror)
			)
		)
		(property "Value" "C_47u_16V_1206"
			(at 0 -2.1 90)
			(layer "B.Fab")
			(effects
				(font
					(size 0.7 0.7)
					(thickness 0.15)
				)
				(justify left bottom mirror)
			)
		)
		(property "Footprint" "antmicro-footprints:C_1206_3216Metric"
			(at 0 0 -90)
			(layer "F.Fab")
			(hide yes)
			(effects
				(font
					(size 1.27 1.27)
					(thickness 0.15)
				)
			)
		)
		(property "Datasheet" "https://product.tdk.com/en/search/capacitor/ceramic/mlcc/info?part_no=C3216X5R1C476M160AB"
			(at 0 0 -90)
			(layer "F.Fab")
			(hide yes)
			(effects
				(font
					(size 1.27 1.27)
					(thickness 0.15)
				)
			)
		)
		(property "Author" "Antmicro"
			(at -40.5 103.5 0)
			(layer "B.Fab")
			(hide yes)
			(effects
				(font
					(size 1 1)
					(thickness 0.15)
				)
				(justify mirror)
			)
		)
		(property "Dielectric" "X5R"
			(at -40.5 103.5 0)
			(layer "B.Fab")
			(hide yes)
			(effects
				(font
					(size 1 1)
					(thickness 0.15)
				)
				(justify mirror)
			)
		)
		(property "License" "Apache-2.0"
			(at -40.5 103.5 0)
			(layer "B.Fab")
			(hide yes)
			(effects
				(font
					(size 1 1)
					(thickness 0.15)
				)
				(justify mirror)
			)
		)
		(property "MPN" "C3216X5R1C476M160AB"
			(at -40.5 103.5 0)
			(layer "B.Fab")
			(hide yes)
			(effects
				(font
					(size 1 1)
					(thickness 0.15)
				)
				(justify mirror)
			)
		)
		(property "Manufacturer" "TDK"
			(at -40.5 103.5 0)
			(layer "B.Fab")
			(hide yes)
			(effects
				(font
					(size 1 1)
					(thickness 0.15)
				)
				(justify mirror)
			)
		)
		(property "Public" "False"
			(at -40.5 103.5 0)
			(layer "B.Fab")
			(hide yes)
			(effects
				(font
					(size 1 1)
					(thickness 0.15)
				)
				(justify mirror)
			)
		)
		(property "Val" "47u"
			(at -40.5 103.5 0)
			(layer "B.Fab")
			(hide yes)
			(effects
				(font
					(size 1 1)
					(thickness 0.15)
				)
				(justify mirror)
			)
		)
		(property "Voltage" "16V"
			(at -40.5 103.5 0)
			(layer "B.Fab")
			(hide yes)
			(effects
				(font
					(size 1 1)
					(thickness 0.15)
				)
				(justify mirror)
			)
		)
		(sheetname "Ethernet")
		(sheetfile "ethernet.kicad_sch")
		(attr smd)
		(fp_line
			(start -0.8 0.899)
			(end 0.8 0.899)
			(stroke
				(width 0.15)
				(type solid)
			)
			(layer "B.SilkS")
		)
		(fp_line
			(start -0.8 -0.901)
			(end 0.8 -0.901)
			(stroke
				(width 0.15)
				(type solid)
			)
			(layer "B.SilkS")
		)
		(fp_rect
			(start -2.325 1.15)
			(end 2.325 -1.15)
			(stroke
				(width 0.05)
				(type default)
			)
			(fill none)
			(layer "B.CrtYd")
		)
		(fp_rect
			(start -1.6 0.799)
			(end 1.6 -0.801)
			(stroke
				(width 0.15)
				(type solid)
			)
			(fill none)
			(layer "B.Fab")
		)
		(fp_text user "License: Apache-2.0"
			(at -2.8 -6.6 90)
			(layer "B.Fab")
			(hide yes)
			(effects
				(font
					(size 0.7 0.7)
					(thickness 0.15)
				)
				(justify left bottom mirror)
			)
		)
		(fp_text user "Author: Antmicro"
			(at -2.8 -5.6 90)
			(layer "B.Fab")
			(hide yes)
			(effects
				(font
					(size 0.7 0.7)
					(thickness 0.15)
				)
				(justify left bottom mirror)
			)
		)
		(fp_text user "${REFERENCE}"
			(at -2.8 -4.6 90)
			(layer "B.Fab")
			(hide yes)
			(effects
				(font
					(size 0.7 0.7)
					(thickness 0.15)
				)
				(justify left bottom mirror)
			)
		)
		(pad "1" smd roundrect
			(at -1.5 -0.001 270)
			(size 1.15 1.8)
			(layers "B.Cu" "B.Paste" "B.Mask")
			(roundrect_rratio 0.25)
			(net 1 "GND")
			(pintype "passive")
		)
		(pad "2" smd roundrect
			(at 1.5 -0.001 270)
			(size 1.15 1.8)
			(layers "B.Cu" "B.Paste" "B.Mask")
			(roundrect_rratio 0.25)
			(net 500 "POE_OUTPUT")
			(pintype "passive")
		)
	)
	(footprint "antmicro-footprints:Fiducial_1mm_Mask2mm"
		(layer "B.Cu")
		(at 148.45 127.45 180)
		(descr "Circular Fiducial, 1mm bare copper, 3mm soldermask opening")
		(tags "fiducial")
		(property "Reference" "FID8"
			(at 0 1.4 0)
			(layer "B.SilkS")
			(hide yes)
			(effects
				(font
					(size 0.7 0.7)
					(thickness 0.15)
				)
				(justify left bottom mirror)
			)
		)
		(property "Value" "Fiducial_1mm_Mask2mm"
			(at 0 -2.2 0)
			(layer "B.Fab")
			(effects
				(font
					(size 0.7 0.7)
					(thickness 0.15)
				)
				(justify left bottom mirror)
			)
		)
		(property "Footprint" "antmicro-footprints:Fiducial_1mm_Mask2mm"
			(at 0 0 180)
			(layer "F.Fab")
			(hide yes)
			(effects
				(font
					(size 1.27 1.27)
					(thickness 0.15)
				)
			)
		)
		(attr board_only exclude_from_pos_files exclude_from_bom)
		(fp_circle
			(center 0 0)
			(end 1.24 0)
			(stroke
				(width 0.05)
				(type solid)
			)
			(fill none)
			(layer "B.CrtYd")
		)
		(fp_circle
			(center 0 0)
			(end 0.999 0)
			(stroke
				(width 0.15)
				(type solid)
			)
			(fill none)
			(layer "B.Fab")
		)
		(fp_text user "License: Apache-2.0"
			(at -1.25 -7.003 0)
			(layer "B.Fab")
			(hide yes)
			(effects
				(font
					(size 0.7 0.7)
					(thickness 0.15)
				)
				(justify left bottom mirror)
			)
		)
		(fp_text user "Author: Antmicro"
			(at -1.25 -5.803 0)
			(layer "B.Fab")
			(hide yes)
			(effects
				(font
					(size 0.7 0.7)
					(thickness 0.15)
				)
				(justify left bottom mirror)
			)
		)
		(fp_text user "${REFERENCE}"
			(at -1.25 -4.603 0)
			(layer "B.Fab")
			(hide yes)
			(effects
				(font
					(size 0.7 0.7)
					(thickness 0.15)
				)
				(justify left bottom mirror)
			)
		)
		(pad "" smd circle
			(at 0 0 180)
			(size 1 1)
			(layers "B.Cu" "B.Mask")
			(solder_mask_margin 0.5)
			(clearance 0.5)
		)
	)
	(footprint "antmicro-footprints:C_0402_1005Metric"
		(layer "B.Cu")
		(at 60.07 86.31 180)
		(descr "Capacitor SMD 0402")
		(tags "capacitor SMD 0402")
		(property "Reference" "C83"
			(at -1.1 -1.4 0)
			(layer "B.SilkS")
			(effects
				(font
					(size 0.7 0.7)
					(thickness 0.15)
				)
				(justify left bottom mirror)
			)
		)
		(property "Value" "C_10u_0402"
			(at -1.022927 -2.155213 0)
			(layer "B.Fab")
			(effects
				(font
					(size 0.7 0.7)
					(thickness 0.15)
				)
				(justify left bottom mirror)
			)
		)
		(property "Footprint" "antmicro-footprints:C_0402_1005Metric"
			(at 0 0 180)
			(layer "F.Fab")
			(hide yes)
			(effects
				(font
					(size 1.27 1.27)
					(thickness 0.15)
				)
			)
		)
		(property "Datasheet" "https://www.yageo.com/en/Chart/Download/pdf/CC0402MRX5R5BB106"
			(at 0 0 180)
			(layer "F.Fab")
			(hide yes)
			(effects
				(font
					(size 1.27 1.27)
					(thickness 0.15)
				)
			)
		)
		(property "Author" "Antmicro"
			(at 120.14 172.62 0)
			(layer "B.Fab")
			(hide yes)
			(effects
				(font
					(size 1 1)
					(thickness 0.15)
				)
				(justify mirror)
			)
		)
		(property "Dielectric" ""
			(at 120.14 172.62 0)
			(layer "B.Fab")
			(hide yes)
			(effects
				(font
					(size 1 1)
					(thickness 0.15)
				)
				(justify mirror)
			)
		)
		(property "License" "Apache-2.0"
			(at 120.14 172.62 0)
			(layer "B.Fab")
			(hide yes)
			(effects
				(font
					(size 1 1)
					(thickness 0.15)
				)
				(justify mirror)
			)
		)
		(property "MPN" "CC0402MRX5R5BB106"
			(at 120.14 172.62 0)
			(layer "B.Fab")
			(hide yes)
			(effects
				(font
					(size 1 1)
					(thickness 0.15)
				)
				(justify mirror)
			)
		)
		(property "Manufacturer" "YAGEO"
			(at 120.14 172.62 0)
			(layer "B.Fab")
			(hide yes)
			(effects
				(font
					(size 1 1)
					(thickness 0.15)
				)
				(justify mirror)
			)
		)
		(property "Val" "10u"
			(at 120.14 172.62 0)
			(layer "B.Fab")
			(hide yes)
			(effects
				(font
					(size 1 1)
					(thickness 0.15)
				)
				(justify mirror)
			)
		)
		(property "Voltage" ""
			(at 120.14 172.62 0)
			(layer "B.Fab")
			(hide yes)
			(effects
				(font
					(size 1 1)
					(thickness 0.15)
				)
				(justify mirror)
			)
		)
		(sheetname "Supply")
		(sheetfile "supply.kicad_sch")
		(attr smd)
		(fp_rect
			(start -0.925 0.47)
			(end 0.925 -0.47)
			(stroke
				(width 0.05)
				(type default)
			)
			(fill none)
			(layer "B.CrtYd")
		)
		(fp_line
			(start 0.504 0.25)
			(end -0.494 0.25)
			(stroke
				(width 0.15)
				(type solid)
			)
			(layer "B.Fab")
		)
		(fp_line
			(start 0.504 -0.248)
			(end 0.504 0.25)
			(stroke
				(width 0.15)
				(type solid)
			)
			(layer "B.Fab")
		)
		(fp_line
			(start -0.494 0.25)
			(end -0.494 -0.248)
			(stroke
				(width 0.15)
				(type solid)
			)
			(layer "B.Fab")
		)
		(fp_line
			(start -0.494 -0.248)
			(end 0.504 -0.248)
			(stroke
				(width 0.15)
				(type solid)
			)
			(layer "B.Fab")
		)
		(fp_text user "${REFERENCE}"
			(at -0.939 -4.599 0)
			(layer "B.Fab")
			(hide yes)
			(effects
				(font
					(size 0.7 0.7)
					(thickness 0.15)
				)
				(justify left bottom mirror)
			)
		)
		(fp_text user "Author: Antmicro"
			(at -0.939 -3.399 0)
			(layer "B.Fab")
			(hide yes)
			(effects
				(font
					(size 0.7 0.7)
					(thickness 0.15)
				)
				(justify left bottom mirror)
			)
		)
		(fp_text user "License: Apache-2.0"
			(at -0.939 -5.799 0)
			(layer "B.Fab")
			(hide yes)
			(effects
				(font
					(size 0.7 0.7)
					(thickness 0.15)
				)
				(justify left bottom mirror)
			)
		)
		(pad "1" smd roundrect
			(at -0.48 0 180)
			(size 0.59 0.64)
			(layers "B.Cu" "B.Paste" "B.Mask")
			(roundrect_rratio 0.25)
			(net 99 "+5V")
			(pintype "passive")
		)
		(pad "2" smd roundrect
			(at 0.48 0 180)
			(size 0.59 0.64)
			(layers "B.Cu" "B.Paste" "B.Mask")
			(roundrect_rratio 0.25)
			(net 1 "GND")
			(pintype "passive")
		)
	)
	(footprint "antmicro-footprints:R_0402_1005Metric"
		(layer "B.Cu")
		(at 73.9 101)
		(descr "Resistor SMD 0402")
		(tags "resistor SMD 0402")
		(property "Reference" "R68"
			(at 0.93 -1.54 180)
			(layer "B.SilkS")
			(effects
				(font
					(size 0.7 0.7)
					(thickness 0.15)
				)
				(justify left bottom mirror)
			)
		)
		(property "Value" "R_200R_0402"
			(at 0 -1.4 180)
			(layer "B.Fab")
			(effects
				(font
					(size 0.7 0.7)
					(thickness 0.15)
				)
				(justify left bottom mirror)
			)
		)
		(property "Footprint" "antmicro-footprints:R_0402_1005Metric"
			(at 0 0 0)
			(layer "F.Fab")
			(hide yes)
			(effects
				(font
					(size 1.27 1.27)
					(thickness 0.15)
				)
			)
		)
		(property "Datasheet" "https://www.bourns.com/docs/product-datasheets/cr.pdf"
			(at 0 0 0)
			(layer "F.Fab")
			(hide yes)
			(effects
				(font
					(size 1.27 1.27)
					(thickness 0.15)
				)
			)
		)
		(property "Author" "Antmicro"
			(at 0 0 0)
			(layer "B.Fab")
			(hide yes)
			(effects
				(font
					(size 1 1)
					(thickness 0.15)
				)
				(justify mirror)
			)
		)
		(property "License" "Apache-2.0"
			(at 0 0 0)
			(layer "B.Fab")
			(hide yes)
			(effects
				(font
					(size 1 1)
					(thickness 0.15)
				)
				(justify mirror)
			)
		)
		(property "MPN" "CR0402-FX-2000GLF"
			(at 0 0 0)
			(layer "B.Fab")
			(hide yes)
			(effects
				(font
					(size 1 1)
					(thickness 0.15)
				)
				(justify mirror)
			)
		)
		(property "Manufacturer" "Bourns"
			(at 0 0 0)
			(layer "B.Fab")
			(hide yes)
			(effects
				(font
					(size 1 1)
					(thickness 0.15)
				)
				(justify mirror)
			)
		)
		(property "Tolerance" "1%"
			(at 0 0 0)
			(layer "B.Fab")
			(hide yes)
			(effects
				(font
					(size 1 1)
					(thickness 0.15)
				)
				(justify mirror)
			)
		)
		(property "Val" "200R"
			(at 0 0 0)
			(layer "B.Fab")
			(hide yes)
			(effects
				(font
					(size 1 1)
					(thickness 0.15)
				)
				(justify mirror)
			)
		)
		(sheetname "USB Debug, DP")
		(sheetfile "usb.kicad_sch")
		(attr smd)
		(fp_rect
			(start -0.925 0.47)
			(end 0.925 -0.47)
			(stroke
				(width 0.05)
				(type default)
			)
			(fill none)
			(layer "B.CrtYd")
		)
		(fp_rect
			(start -0.5 0.25)
			(end 0.5 -0.25)
			(stroke
				(width 0.15)
				(type solid)
			)
			(fill none)
			(layer "B.Fab")
		)
		(fp_text user "Author: Antmicro"
			(at -0.95 -4.169 180)
			(layer "B.Fab")
			(hide yes)
			(effects
				(font
					(size 0.7 0.7)
					(thickness 0.15)
				)
				(justify left bottom mirror)
			)
		)
		(fp_text user "License: Apache-2.0"
			(at -0.95 -5.169 180)
			(layer "B.Fab")
			(hide yes)
			(effects
				(font
					(size 0.7 0.7)
					(thickness 0.15)
				)
				(justify left bottom mirror)
			)
		)
		(fp_text user "${REFERENCE}"
			(at -0.95 -3.168 180)
			(layer "B.Fab")
			(hide yes)
			(effects
				(font
					(size 0.7 0.7)
					(thickness 0.15)
				)
				(justify left bottom mirror)
			)
		)
		(pad "1" smd roundrect
			(at -0.48 0)
			(size 0.59 0.64)
			(layers "B.Cu" "B.Paste" "B.Mask")
			(roundrect_rratio 0.25)
			(net 300 "/USB Debug, DP/PDC_GPIO14")
			(pintype "passive")
		)
		(pad "2" smd roundrect
			(at 0.48 0)
			(size 0.59 0.64)
			(layers "B.Cu" "B.Paste" "B.Mask")
			(roundrect_rratio 0.25)
			(net 144 "Net-(D4-A)")
			(pintype "passive")
		)
	)
	(footprint "antmicro-footprints:C_0402_1005Metric"
		(layer "B.Cu")
		(at 74.35 114.25 180)
		(descr "Capacitor SMD 0402")
		(tags "capacitor SMD 0402")
		(property "Reference" "C149"
			(at 0.86 -0.32 0)
			(layer "B.SilkS")
			(effects
				(font
					(size 0.7 0.7)
					(thickness 0.15)
				)
				(justify left bottom mirror)
			)
		)
		(property "Value" "C_1u_25V_0402"
			(at 0 -1.4 0)
			(layer "B.Fab")
			(effects
				(font
					(size 0.7 0.7)
					(thickness 0.15)
				)
				(justify left bottom mirror)
			)
		)
		(property "Footprint" "antmicro-footprints:C_0402_1005Metric"
			(at 0 0 180)
			(layer "F.Fab")
			(hide yes)
			(effects
				(font
					(size 1.27 1.27)
					(thickness 0.15)
				)
			)
		)
		(property "Datasheet" "https://www.murata.com/products/productdetail?partno=GRM155R61E105KE11%23"
			(at 0 0 180)
			(layer "F.Fab")
			(hide yes)
			(effects
				(font
					(size 1.27 1.27)
					(thickness 0.15)
				)
			)
		)
		(property "Author" "Antmicro"
			(at 148.7 228.5 0)
			(layer "B.Fab")
			(hide yes)
			(effects
				(font
					(size 1 1)
					(thickness 0.15)
				)
				(justify mirror)
			)
		)
		(property "Dielectric" "X5R"
			(at 148.7 228.5 0)
			(layer "B.Fab")
			(hide yes)
			(effects
				(font
					(size 1 1)
					(thickness 0.15)
				)
				(justify mirror)
			)
		)
		(property "License" "Apache-2.0"
			(at 148.7 228.5 0)
			(layer "B.Fab")
			(hide yes)
			(effects
				(font
					(size 1 1)
					(thickness 0.15)
				)
				(justify mirror)
			)
		)
		(property "MPN" "GRM155R61E105KE11J"
			(at 148.7 228.5 0)
			(layer "B.Fab")
			(hide yes)
			(effects
				(font
					(size 1 1)
					(thickness 0.15)
				)
				(justify mirror)
			)
		)
		(property "Manufacturer" "Murata"
			(at 148.7 228.5 0)
			(layer "B.Fab")
			(hide yes)
			(effects
				(font
					(size 1 1)
					(thickness 0.15)
				)
				(justify mirror)
			)
		)
		(property "Val" "1u"
			(at 148.7 228.5 0)
			(layer "B.Fab")
			(hide yes)
			(effects
				(font
					(size 1 1)
					(thickness 0.15)
				)
				(justify mirror)
			)
		)
		(property "Voltage" "25V"
			(at 148.7 228.5 0)
			(layer "B.Fab")
			(hide yes)
			(effects
				(font
					(size 1 1)
					(thickness 0.15)
				)
				(justify mirror)
			)
		)
		(sheetname "USB Debug, DP")
		(sheetfile "usb.kicad_sch")
		(attr smd)
		(fp_rect
			(start -0.925 0.47)
			(end 0.925 -0.47)
			(stroke
				(width 0.05)
				(type default)
			)
			(fill none)
			(layer "B.CrtYd")
		)
		(fp_line
			(start 0.504 0.25)
			(end -0.494 0.25)
			(stroke
				(width 0.15)
				(type solid)
			)
			(layer "B.Fab")
		)
		(fp_line
			(start 0.504 -0.248)
			(end 0.504 0.25)
			(stroke
				(width 0.15)
				(type solid)
			)
			(layer "B.Fab")
		)
		(fp_line
			(start -0.494 0.25)
			(end -0.494 -0.248)
			(stroke
				(width 0.15)
				(type solid)
			)
			(layer "B.Fab")
		)
		(fp_line
			(start -0.494 -0.248)
			(end 0.504 -0.248)
			(stroke
				(width 0.15)
				(type solid)
			)
			(layer "B.Fab")
		)
		(fp_text user "License: Apache-2.0"
			(at -0.932 -5.17 0)
			(layer "B.Fab")
			(hide yes)
			(effects
				(font
					(size 0.7 0.7)
					(thickness 0.15)
				)
				(justify left bottom mirror)
			)
		)
		(fp_text user "Author: Antmicro"
			(at -0.932 -4.17 0)
			(layer "B.Fab")
			(hide yes)
			(effects
				(font
					(size 0.7 0.7)
					(thickness 0.15)
				)
				(justify left bottom mirror)
			)
		)
		(fp_text user "${REFERENCE}"
			(at -0.932 -3.168 0)
			(layer "B.Fab")
			(hide yes)
			(effects
				(font
					(size 0.7 0.7)
					(thickness 0.15)
				)
				(justify left bottom mirror)
			)
		)
		(pad "1" smd roundrect
			(at -0.48 0 180)
			(size 0.59 0.64)
			(layers "B.Cu" "B.Paste" "B.Mask")
			(roundrect_rratio 0.25)
			(net 1 "GND")
			(pintype "passive")
		)
		(pad "2" smd roundrect
			(at 0.48 0 180)
			(size 0.59 0.64)
			(layers "B.Cu" "B.Paste" "B.Mask")
			(roundrect_rratio 0.25)
			(net 261 "/USB Debug, DP/USBC0_VBUS")
			(pintype "passive")
		)
	)
	(footprint "antmicro-footprints:C_0402_1005Metric"
		(layer "B.Cu")
		(at 138 104.5 -90)
		(descr "Capacitor SMD 0402")
		(tags "capacitor SMD 0402")
		(property "Reference" "C94"
			(at -1.1 -1.3 90)
			(layer "B.SilkS")
			(effects
				(font
					(size 0.7 0.7)
					(thickness 0.15)
				)
				(justify left bottom mirror)
			)
		)
		(property "Value" "C_1u_0402"
			(at 0 -1.4 90)
			(layer "B.Fab")
			(effects
				(font
					(size 0.7 0.7)
					(thickness 0.15)
				)
				(justify left bottom mirror)
			)
		)
		(property "Footprint" "antmicro-footprints:C_0402_1005Metric"
			(at 0 0 -90)
			(layer "F.Fab")
			(hide yes)
			(effects
				(font
					(size 1.27 1.27)
					(thickness 0.15)
				)
			)
		)
		(property "Datasheet" "https://product.tdk.com/en/search/capacitor/ceramic/mlcc/info?part_no=C1005X6S1A105K050BC"
			(at 0 0 -90)
			(layer "F.Fab")
			(hide yes)
			(effects
				(font
					(size 1.27 1.27)
					(thickness 0.15)
				)
			)
		)
		(property "Author" "Antmicro"
			(at 33.5 242.5 0)
			(layer "B.Fab")
			(hide yes)
			(effects
				(font
					(size 1 1)
					(thickness 0.15)
				)
				(justify mirror)
			)
		)
		(property "Dielectric" ""
			(at 33.5 242.5 0)
			(layer "B.Fab")
			(hide yes)
			(effects
				(font
					(size 1 1)
					(thickness 0.15)
				)
				(justify mirror)
			)
		)
		(property "License" "Apache-2.0"
			(at 33.5 242.5 0)
			(layer "B.Fab")
			(hide yes)
			(effects
				(font
					(size 1 1)
					(thickness 0.15)
				)
				(justify mirror)
			)
		)
		(property "MPN" "C1005X6S1A105K050BC"
			(at 33.5 242.5 0)
			(layer "B.Fab")
			(hide yes)
			(effects
				(font
					(size 1 1)
					(thickness 0.15)
				)
				(justify mirror)
			)
		)
		(property "Manufacturer" "TDK"
			(at 33.5 242.5 0)
			(layer "B.Fab")
			(hide yes)
			(effects
				(font
					(size 1 1)
					(thickness 0.15)
				)
				(justify mirror)
			)
		)
		(property "Val" "1u"
			(at 33.5 242.5 0)
			(layer "B.Fab")
			(hide yes)
			(effects
				(font
					(size 1 1)
					(thickness 0.15)
				)
				(justify mirror)
			)
		)
		(property "Voltage" ""
			(at 33.5 242.5 0)
			(layer "B.Fab")
			(hide yes)
			(effects
				(font
					(size 1 1)
					(thickness 0.15)
				)
				(justify mirror)
			)
		)
		(sheetname "CSI")
		(sheetfile "csi.kicad_sch")
		(attr smd)
		(fp_rect
			(start -0.925 0.47)
			(end 0.925 -0.47)
			(stroke
				(width 0.05)
				(type default)
			)
			(fill none)
			(layer "B.CrtYd")
		)
		(fp_line
			(start -0.494 0.25)
			(end -0.494 -0.248)
			(stroke
				(width 0.15)
				(type solid)
			)
			(layer "B.Fab")
		)
		(fp_line
			(start 0.504 0.25)
			(end -0.494 0.25)
			(stroke
				(width 0.15)
				(type solid)
			)
			(layer "B.Fab")
		)
		(fp_line
			(start -0.494 -0.248)
			(end 0.504 -0.248)
			(stroke
				(width 0.15)
				(type solid)
			)
			(layer "B.Fab")
		)
		(fp_line
			(start 0.504 -0.248)
			(end 0.504 0.25)
			(stroke
				(width 0.15)
				(type solid)
			)
			(layer "B.Fab")
		)
		(fp_text user "${REFERENCE}"
			(at -0.932 -3.168 90)
			(layer "B.Fab")
			(hide yes)
			(effects
				(font
					(size 0.7 0.7)
					(thickness 0.15)
				)
				(justify left bottom mirror)
			)
		)
		(fp_text user "Author: Antmicro"
			(at -0.932 -4.17 90)
			(layer "B.Fab")
			(hide yes)
			(effects
				(font
					(size 0.7 0.7)
					(thickness 0.15)
				)
				(justify left bottom mirror)
			)
		)
		(fp_text user "License: Apache-2.0"
			(at -0.932 -5.17 90)
			(layer "B.Fab")
			(hide yes)
			(effects
				(font
					(size 0.7 0.7)
					(thickness 0.15)
				)
				(justify left bottom mirror)
			)
		)
		(pad "1" smd roundrect
			(at -0.48 0 270)
			(size 0.59 0.64)
			(layers "B.Cu" "B.Paste" "B.Mask")
			(roundrect_rratio 0.25)
			(net 1 "GND")
			(pintype "passive")
		)
		(pad "2" smd roundrect
			(at 0.48 0 270)
			(size 0.59 0.64)
			(layers "B.Cu" "B.Paste" "B.Mask")
			(roundrect_rratio 0.25)
			(net 108 "/CSI/CSIA_3V3")
			(pintype "passive")
		)
	)
	(footprint "antmicro-footprints:R_0402_1005Metric"
		(layer "B.Cu")
		(at 77.6 107.4 180)
		(descr "Resistor SMD 0402")
		(tags "resistor SMD 0402")
		(property "Reference" "R90"
			(at -3.14 -2.38 0)
			(layer "B.SilkS")
			(effects
				(font
					(size 0.7 0.7)
					(thickness 0.15)
				)
				(justify left bottom mirror)
			)
		)
		(property "Value" "R_1k_0402"
			(at 0 -1.4 0)
			(layer "B.Fab")
			(effects
				(font
					(size 0.7 0.7)
					(thickness 0.15)
				)
				(justify left bottom mirror)
			)
		)
		(property "Footprint" "antmicro-footprints:R_0402_1005Metric"
			(at 0 0 180)
			(layer "F.Fab")
			(hide yes)
			(effects
				(font
					(size 1.27 1.27)
					(thickness 0.15)
				)
			)
		)
		(property "Datasheet" "https://www.bourns.com/docs/product-datasheets/cr.pdf"
			(at 0 0 180)
			(layer "F.Fab")
			(hide yes)
			(effects
				(font
					(size 1.27 1.27)
					(thickness 0.15)
				)
			)
		)
		(property "Author" "Antmicro"
			(at 155.2 214.8 0)
			(layer "B.Fab")
			(hide yes)
			(effects
				(font
					(size 1 1)
					(thickness 0.15)
				)
				(justify mirror)
			)
		)
		(property "License" "Apache-2.0"
			(at 155.2 214.8 0)
			(layer "B.Fab")
			(hide yes)
			(effects
				(font
					(size 1 1)
					(thickness 0.15)
				)
				(justify mirror)
			)
		)
		(property "MPN" "CR0402-FX-1001GLF"
			(at 155.2 214.8 0)
			(layer "B.Fab")
			(hide yes)
			(effects
				(font
					(size 1 1)
					(thickness 0.15)
				)
				(justify mirror)
			)
		)
		(property "Manufacturer" "Bourns"
			(at 155.2 214.8 0)
			(layer "B.Fab")
			(hide yes)
			(effects
				(font
					(size 1 1)
					(thickness 0.15)
				)
				(justify mirror)
			)
		)
		(property "Tolerance" "1%"
			(at 155.2 214.8 0)
			(layer "B.Fab")
			(hide yes)
			(effects
				(font
					(size 1 1)
					(thickness 0.15)
				)
				(justify mirror)
			)
		)
		(property "Val" "1k"
			(at 155.2 214.8 0)
			(layer "B.Fab")
			(hide yes)
			(effects
				(font
					(size 1 1)
					(thickness 0.15)
				)
				(justify mirror)
			)
		)
		(sheetname "USB Debug, DP")
		(sheetfile "usb.kicad_sch")
		(attr smd)
		(fp_rect
			(start -0.925 0.47)
			(end 0.925 -0.47)
			(stroke
				(width 0.05)
				(type default)
			)
			(fill none)
			(layer "B.CrtYd")
		)
		(fp_rect
			(start -0.5 0.25)
			(end 0.5 -0.25)
			(stroke
				(width 0.15)
				(type solid)
			)
			(fill none)
			(layer "B.Fab")
		)
		(fp_text user "License: Apache-2.0"
			(at -0.95 -5.169 0)
			(layer "B.Fab")
			(hide yes)
			(effects
				(font
					(size 0.7 0.7)
					(thickness 0.15)
				)
				(justify left bottom mirror)
			)
		)
		(fp_text user "Author: Antmicro"
			(at -0.95 -4.169 0)
			(layer "B.Fab")
			(hide yes)
			(effects
				(font
					(size 0.7 0.7)
					(thickness 0.15)
				)
				(justify left bottom mirror)
			)
		)
		(fp_text user "${REFERENCE}"
			(at -0.95 -3.168 0)
			(layer "B.Fab")
			(hide yes)
			(effects
				(font
					(size 0.7 0.7)
					(thickness 0.15)
				)
				(justify left bottom mirror)
			)
		)
		(pad "1" smd roundrect
			(at -0.48 0 180)
			(size 0.59 0.64)
			(layers "B.Cu" "B.Paste" "B.Mask")
			(roundrect_rratio 0.25)
			(net 306 "/USB Debug, DP/USBC0_SSEQ1")
			(pintype "passive")
		)
		(pad "2" smd roundrect
			(at 0.48 0 180)
			(size 0.59 0.64)
			(layers "B.Cu" "B.Paste" "B.Mask")
			(roundrect_rratio 0.25)
			(net 1 "GND")
			(pintype "passive")
		)
	)
	(footprint "antmicro-footprints:C_0402_1005Metric"
		(layer "B.Cu")
		(at 97.45 90.2)
		(descr "Capacitor SMD 0402")
		(tags "capacitor SMD 0402")
		(property "Reference" "C86"
			(at 3.12 0.06 180)
			(layer "B.SilkS")
			(effects
				(font
					(size 0.7 0.7)
					(thickness 0.15)
				)
				(justify left bottom mirror)
			)
		)
		(property "Value" "C_100n_0402"
			(at 0 -1.4 180)
			(layer "B.Fab")
			(effects
				(font
					(size 0.7 0.7)
					(thickness 0.15)
				)
				(justify left bottom mirror)
			)
		)
		(property "Footprint" "antmicro-footprints:C_0402_1005Metric"
			(at 0 0 0)
			(layer "F.Fab")
			(hide yes)
			(effects
				(font
					(size 1.27 1.27)
					(thickness 0.15)
				)
			)
		)
		(property "Datasheet" "https://www.murata.com/products/productdetail?partno=GRM155R61H104KE14%23"
			(at 0 0 0)
			(layer "F.Fab")
			(hide yes)
			(effects
				(font
					(size 1.27 1.27)
					(thickness 0.15)
				)
			)
		)
		(property "Author" "Antmicro"
			(at 0 0 0)
			(layer "B.Fab")
			(hide yes)
			(effects
				(font
					(size 1 1)
					(thickness 0.15)
				)
				(justify mirror)
			)
		)
		(property "Dielectric" "X5R"
			(at 0 0 0)
			(layer "B.Fab")
			(hide yes)
			(effects
				(font
					(size 1 1)
					(thickness 0.15)
				)
				(justify mirror)
			)
		)
		(property "License" "Apache-2.0"
			(at 0 0 0)
			(layer "B.Fab")
			(hide yes)
			(effects
				(font
					(size 1 1)
					(thickness 0.15)
				)
				(justify mirror)
			)
		)
		(property "MPN" "GRM155R61H104KE14D"
			(at 0 0 0)
			(layer "B.Fab")
			(hide yes)
			(effects
				(font
					(size 1 1)
					(thickness 0.15)
				)
				(justify mirror)
			)
		)
		(property "Manufacturer" "Murata"
			(at 0 0 0)
			(layer "B.Fab")
			(hide yes)
			(effects
				(font
					(size 1 1)
					(thickness 0.15)
				)
				(justify mirror)
			)
		)
		(property "Val" "100n"
			(at 0 0 0)
			(layer "B.Fab")
			(hide yes)
			(effects
				(font
					(size 1 1)
					(thickness 0.15)
				)
				(justify mirror)
			)
		)
		(property "Voltage" "50V"
			(at 0 0 0)
			(layer "B.Fab")
			(hide yes)
			(effects
				(font
					(size 1 1)
					(thickness 0.15)
				)
				(justify mirror)
			)
		)
		(sheetname "HDMI")
		(sheetfile "hdmi.kicad_sch")
		(attr smd)
		(fp_rect
			(start -0.925 0.47)
			(end 0.925 -0.47)
			(stroke
				(width 0.05)
				(type default)
			)
			(fill none)
			(layer "B.CrtYd")
		)
		(fp_line
			(start -0.494 -0.248)
			(end 0.504 -0.248)
			(stroke
				(width 0.15)
				(type solid)
			)
			(layer "B.Fab")
		)
		(fp_line
			(start -0.494 0.25)
			(end -0.494 -0.248)
			(stroke
				(width 0.15)
				(type solid)
			)
			(layer "B.Fab")
		)
		(fp_line
			(start 0.504 -0.248)
			(end 0.504 0.25)
			(stroke
				(width 0.15)
				(type solid)
			)
			(layer "B.Fab")
		)
		(fp_line
			(start 0.504 0.25)
			(end -0.494 0.25)
			(stroke
				(width 0.15)
				(type solid)
			)
			(layer "B.Fab")
		)
		(fp_text user "License: Apache-2.0"
			(at -0.932 -5.17 180)
			(layer "B.Fab")
			(hide yes)
			(effects
				(font
					(size 0.7 0.7)
					(thickness 0.15)
				)
				(justify left bottom mirror)
			)
		)
		(fp_text user "Author: Antmicro"
			(at -0.932 -4.17 180)
			(layer "B.Fab")
			(hide yes)
			(effects
				(font
					(size 0.7 0.7)
					(thickness 0.15)
				)
				(justify left bottom mirror)
			)
		)
		(fp_text user "${REFERENCE}"
			(at -0.932 -3.168 180)
			(layer "B.Fab")
			(hide yes)
			(effects
				(font
					(size 0.7 0.7)
					(thickness 0.15)
				)
				(justify left bottom mirror)
			)
		)
		(pad "1" smd roundrect
			(at -0.48 0)
			(size 0.59 0.64)
			(layers "B.Cu" "B.Paste" "B.Mask")
			(roundrect_rratio 0.25)
			(net 556 "/HDMI/DP_MUX_D0-")
			(pintype "passive")
		)
		(pad "2" smd roundrect
			(at 0.48 0)
			(size 0.59 0.64)
			(layers "B.Cu" "B.Paste" "B.Mask")
			(roundrect_rratio 0.25)
			(net 420 "DP1_TXD3_HDMI_TXC_N")
			(pintype "passive")
		)
	)
	(footprint "antmicro-footprints:XDFN-2_1x0.60mm"
		(layer "B.Cu")
		(at 130.25 94.78)
		(property "Reference" "D22"
			(at -1.05 1.42 180)
			(layer "B.SilkS")
			(effects
				(font
					(size 0.7 0.7)
					(thickness 0.15)
				)
				(justify right bottom mirror)
			)
		)
		(property "Value" "TPD1E0B04_XDFN-2"
			(at 0 -1.5 180)
			(layer "B.Fab")
			(effects
				(font
					(size 0.7 0.7)
					(thickness 0.15)
				)
				(justify left bottom mirror)
			)
		)
		(property "Footprint" "antmicro-footprints:XDFN-2_1x0.60mm"
			(at 0 0 0)
			(layer "F.Fab")
			(hide yes)
			(effects
				(font
					(size 1.27 1.27)
					(thickness 0.15)
				)
			)
		)
		(property "Datasheet" "https://www.ti.com/general/docs/suppproductinfo.tsp?distId=26&gotoUrl=https://www.ti.com/lit/gpn/tpd1e0b04"
			(at 0 0 0)
			(layer "F.Fab")
			(hide yes)
			(effects
				(font
					(size 1.27 1.27)
					(thickness 0.15)
				)
			)
		)
		(property "MPN" "TPD1E0B04DPYR"
			(at 0 0 0)
			(layer "B.Fab")
			(hide yes)
			(effects
				(font
					(size 1 1)
					(thickness 0.15)
				)
				(justify mirror)
			)
		)
		(property "Manufacturer" "Texas Instruments"
			(at 0 0 0)
			(layer "B.Fab")
			(hide yes)
			(effects
				(font
					(size 1 1)
					(thickness 0.15)
				)
				(justify mirror)
			)
		)
		(property "Author" "Antmicro"
			(at 0 0 0)
			(layer "B.Fab")
			(hide yes)
			(effects
				(font
					(size 1 1)
					(thickness 0.15)
				)
				(justify mirror)
			)
		)
		(property "License" "Apache-2.0"
			(at 0 0 0)
			(layer "B.Fab")
			(hide yes)
			(effects
				(font
					(size 1 1)
					(thickness 0.15)
				)
				(justify mirror)
			)
		)
		(sheetname "Peripherals")
		(sheetfile "peripherals.kicad_sch")
		(attr smd)
		(fp_rect
			(start -0.725 0.475)
			(end 0.725 -0.475)
			(stroke
				(width 0.05)
				(type solid)
			)
			(fill none)
			(layer "B.CrtYd")
		)
		(fp_rect
			(start -0.55 0.35)
			(end 0.55 -0.35)
			(stroke
				(width 0.15)
				(type solid)
			)
			(fill none)
			(layer "B.Fab")
		)
		(fp_text user "${REFERENCE}"
			(at -0.8 -3.2 180)
			(layer "B.Fab")
			(hide yes)
			(effects
				(font
					(size 0.7 0.7)
					(thickness 0.15)
				)
				(justify left bottom mirror)
			)
		)
		(fp_text user "License: Apache-2.0"
			(at -0.8 -5.6 180)
			(layer "B.Fab")
			(hide yes)
			(effects
				(font
					(size 0.7 0.7)
					(thickness 0.15)
				)
				(justify left bottom mirror)
			)
		)
		(fp_text user "Author: Antmicro"
			(at -0.8 -4.4 180)
			(layer "B.Fab")
			(hide yes)
			(effects
				(font
					(size 0.7 0.7)
					(thickness 0.15)
				)
				(justify left bottom mirror)
			)
		)
		(pad "1" smd roundrect
			(at -0.351 0)
			(size 0.3 0.5)
			(layers "B.Cu" "B.Paste" "B.Mask")
			(roundrect_rratio 0.25)
			(net 434 "USB1_D_N")
			(pinfunction "C")
			(pintype "passive")
		)
		(pad "2" smd roundrect
			(at 0.349 0)
			(size 0.3 0.5)
			(layers "B.Cu" "B.Paste" "B.Mask")
			(roundrect_rratio 0.25)
			(net 1 "GND")
			(pinfunction "A")
			(pintype "passive")
		)
	)
	(footprint "antmicro-footprints:R_0402_1005Metric"
		(layer "B.Cu")
		(at 106 93.02)
		(descr "Resistor SMD 0402")
		(tags "resistor SMD 0402")
		(property "Reference" "R38"
			(at -0.8 0.43 180)
			(layer "B.SilkS")
			(effects
				(font
					(size 0.7 0.7)
					(thickness 0.15)
				)
				(justify left bottom mirror)
			)
		)
		(property "Value" "R_47k_0402"
			(at 0 -1.4 180)
			(layer "B.Fab")
			(effects
				(font
					(size 0.7 0.7)
					(thickness 0.15)
				)
				(justify left bottom mirror)
			)
		)
		(property "Footprint" "antmicro-footprints:R_0402_1005Metric"
			(at 0 0 0)
			(layer "F.Fab")
			(hide yes)
			(effects
				(font
					(size 1.27 1.27)
					(thickness 0.15)
				)
			)
		)
		(property "Datasheet" "https://www.bourns.com/docs/product-datasheets/cr.pdf"
			(at 0 0 0)
			(layer "F.Fab")
			(hide yes)
			(effects
				(font
					(size 1.27 1.27)
					(thickness 0.15)
				)
			)
		)
		(property "Author" "Antmicro"
			(at 0 0 0)
			(layer "B.Fab")
			(hide yes)
			(effects
				(font
					(size 1 1)
					(thickness 0.15)
				)
				(justify mirror)
			)
		)
		(property "License" "Apache-2.0"
			(at 0 0 0)
			(layer "B.Fab")
			(hide yes)
			(effects
				(font
					(size 1 1)
					(thickness 0.15)
				)
				(justify mirror)
			)
		)
		(property "MPN" "CR0402-FX-4702GLF"
			(at 0 0 0)
			(layer "B.Fab")
			(hide yes)
			(effects
				(font
					(size 1 1)
					(thickness 0.15)
				)
				(justify mirror)
			)
		)
		(property "Manufacturer" "Bourns"
			(at 0 0 0)
			(layer "B.Fab")
			(hide yes)
			(effects
				(font
					(size 1 1)
					(thickness 0.15)
				)
				(justify mirror)
			)
		)
		(property "Tolerance" "1%"
			(at 0 0 0)
			(layer "B.Fab")
			(hide yes)
			(effects
				(font
					(size 1 1)
					(thickness 0.15)
				)
				(justify mirror)
			)
		)
		(property "Val" "47k"
			(at 0 0 0)
			(layer "B.Fab")
			(hide yes)
			(effects
				(font
					(size 1 1)
					(thickness 0.15)
				)
				(justify mirror)
			)
		)
		(sheetname "M.2")
		(sheetfile "m-2.kicad_sch")
		(attr smd exclude_from_pos_files exclude_from_bom dnp)
		(fp_rect
			(start -0.925 0.47)
			(end 0.925 -0.47)
			(stroke
				(width 0.05)
				(type default)
			)
			(fill none)
			(layer "B.CrtYd")
		)
		(fp_rect
			(start -0.5 0.25)
			(end 0.5 -0.25)
			(stroke
				(width 0.15)
				(type solid)
			)
			(fill none)
			(layer "B.Fab")
		)
		(fp_text user "License: Apache-2.0"
			(at -0.95 -5.169 180)
			(layer "B.Fab")
			(hide yes)
			(effects
				(font
					(size 0.7 0.7)
					(thickness 0.15)
				)
				(justify left bottom mirror)
			)
		)
		(fp_text user "Author: Antmicro"
			(at -0.95 -4.169 180)
			(layer "B.Fab")
			(hide yes)
			(effects
				(font
					(size 0.7 0.7)
					(thickness 0.15)
				)
				(justify left bottom mirror)
			)
		)
		(fp_text user "${REFERENCE}"
			(at -0.95 -3.168 180)
			(layer "B.Fab")
			(hide yes)
			(effects
				(font
					(size 0.7 0.7)
					(thickness 0.15)
				)
				(justify left bottom mirror)
			)
		)
		(pad "1" smd roundrect
			(at -0.48 0)
			(size 0.59 0.64)
			(layers "B.Cu" "B.Paste" "B.Mask")
			(roundrect_rratio 0.25)
			(net 87 "+3V3")
			(pintype "passive")
		)
		(pad "2" smd roundrect
			(at 0.48 0)
			(size 0.59 0.64)
			(layers "B.Cu" "B.Paste" "B.Mask")
			(roundrect_rratio 0.25)
			(net 248 "/M.2/~{M2_M_CLKREQ0}")
			(pintype "passive")
		)
	)
	(footprint "antmicro-footprints:R_0402_1005Metric"
		(layer "B.Cu")
		(at 129.9 104.25)
		(descr "Resistor SMD 0402")
		(tags "resistor SMD 0402")
		(property "Reference" "R15"
			(at 1.14 -0.4 180)
			(layer "B.SilkS")
			(effects
				(font
					(size 0.7 0.7)
					(thickness 0.15)
				)
				(justify left bottom mirror)
			)
		)
		(property "Value" "R_0R_0402"
			(at 0 -1.4 180)
			(layer "B.Fab")
			(effects
				(font
					(size 0.7 0.7)
					(thickness 0.15)
				)
				(justify left bottom mirror)
			)
		)
		(property "Footprint" "antmicro-footprints:R_0402_1005Metric"
			(at 0 0 0)
			(layer "F.Fab")
			(hide yes)
			(effects
				(font
					(size 1.27 1.27)
					(thickness 0.15)
				)
			)
		)
		(property "Datasheet" "https://industrial.panasonic.com/cdbs/www-data/pdf/RDA0000/AOA0000C301.pdf"
			(at 0 0 0)
			(layer "F.Fab")
			(hide yes)
			(effects
				(font
					(size 1.27 1.27)
					(thickness 0.15)
				)
			)
		)
		(property "Author" "Antmicro"
			(at 0 0 0)
			(layer "B.Fab")
			(hide yes)
			(effects
				(font
					(size 1 1)
					(thickness 0.15)
				)
				(justify mirror)
			)
		)
		(property "Current" "1A"
			(at 0 0 0)
			(layer "B.Fab")
			(hide yes)
			(effects
				(font
					(size 1 1)
					(thickness 0.15)
				)
				(justify mirror)
			)
		)
		(property "License" "Apache-2.0"
			(at 0 0 0)
			(layer "B.Fab")
			(hide yes)
			(effects
				(font
					(size 1 1)
					(thickness 0.15)
				)
				(justify mirror)
			)
		)
		(property "MPN" "ERJ2GE0R00X"
			(at 0 0 0)
			(layer "B.Fab")
			(hide yes)
			(effects
				(font
					(size 1 1)
					(thickness 0.15)
				)
				(justify mirror)
			)
		)
		(property "Manufacturer" "Panasonic"
			(at 0 0 0)
			(layer "B.Fab")
			(hide yes)
			(effects
				(font
					(size 1 1)
					(thickness 0.15)
				)
				(justify mirror)
			)
		)
		(property "Tolerance" ""
			(at 0 0 0)
			(layer "B.Fab")
			(hide yes)
			(effects
				(font
					(size 1 1)
					(thickness 0.15)
				)
				(justify mirror)
			)
		)
		(property "Val" "0R"
			(at 0 0 0)
			(layer "B.Fab")
			(hide yes)
			(effects
				(font
					(size 1 1)
					(thickness 0.15)
				)
				(justify mirror)
			)
		)
		(sheetname "M.2")
		(sheetfile "m-2.kicad_sch")
		(attr smd)
		(fp_rect
			(start -0.925 0.47)
			(end 0.925 -0.47)
			(stroke
				(width 0.05)
				(type default)
			)
			(fill none)
			(layer "B.CrtYd")
		)
		(fp_rect
			(start -0.5 0.25)
			(end 0.5 -0.25)
			(stroke
				(width 0.15)
				(type solid)
			)
			(fill none)
			(layer "B.Fab")
		)
		(fp_text user "Author: Antmicro"
			(at -0.95 -4.169 180)
			(layer "B.Fab")
			(hide yes)
			(effects
				(font
					(size 0.7 0.7)
					(thickness 0.15)
				)
				(justify left bottom mirror)
			)
		)
		(fp_text user "License: Apache-2.0"
			(at -0.95 -5.169 180)
			(layer "B.Fab")
			(hide yes)
			(effects
				(font
					(size 0.7 0.7)
					(thickness 0.15)
				)
				(justify left bottom mirror)
			)
		)
		(fp_text user "${REFERENCE}"
			(at -0.95 -3.168 180)
			(layer "B.Fab")
			(hide yes)
			(effects
				(font
					(size 0.7 0.7)
					(thickness 0.15)
				)
				(justify left bottom mirror)
			)
		)
		(pad "1" smd roundrect
			(at -0.48 0)
			(size 0.59 0.64)
			(layers "B.Cu" "B.Paste" "B.Mask")
			(roundrect_rratio 0.25)
			(net 453 "PCIE_WAKE*")
			(pintype "passive")
		)
		(pad "2" smd roundrect
			(at 0.48 0)
			(size 0.59 0.64)
			(layers "B.Cu" "B.Paste" "B.Mask")
			(roundrect_rratio 0.25)
			(net 427 "PCIE_WAKE_SEL_EXT")
			(pintype "passive")
		)
	)
	(footprint "antmicro-footprints:R_0402_1005Metric"
		(layer "B.Cu")
		(at 74.75 121.1)
		(descr "Resistor SMD 0402")
		(tags "resistor SMD 0402")
		(property "Reference" "R110"
			(at 3.6 0.4 180)
			(layer "B.SilkS")
			(effects
				(font
					(size 0.7 0.7)
					(thickness 0.15)
				)
				(justify left bottom mirror)
			)
		)
		(property "Value" "R_2M_0402"
			(at 0 -1.4 180)
			(layer "B.Fab")
			(effects
				(font
					(size 0.7 0.7)
					(thickness 0.15)
				)
				(justify left bottom mirror)
			)
		)
		(property "Footprint" "antmicro-footprints:R_0402_1005Metric"
			(at 0 0 0)
			(layer "F.Fab")
			(hide yes)
			(effects
				(font
					(size 1.27 1.27)
					(thickness 0.15)
				)
			)
		)
		(property "Datasheet" "https://www.mouser.com/datasheet/2/447/YAGEO_PYu_RC_Group_51_RoHS_L_12-3313492.pdf"
			(at 0 0 0)
			(layer "F.Fab")
			(hide yes)
			(effects
				(font
					(size 1.27 1.27)
					(thickness 0.15)
				)
			)
		)
		(property "Description" "SMD Chip Resistor, 2 Mohm, ± 1%, 62.5 mW, 0402 [1005 Metric], Thick Film, General Purpose"
			(at 0 0 0)
			(layer "F.Fab")
			(hide yes)
			(effects
				(font
					(size 1.27 1.27)
					(thickness 0.15)
				)
			)
		)
		(property "Author" "Antmicro"
			(at 0 0 0)
			(layer "B.Fab")
			(hide yes)
			(effects
				(font
					(size 1 1)
					(thickness 0.15)
				)
				(justify mirror)
			)
		)
		(property "License" "Apache-2.0"
			(at 0 0 0)
			(layer "B.Fab")
			(hide yes)
			(effects
				(font
					(size 1 1)
					(thickness 0.15)
				)
				(justify mirror)
			)
		)
		(property "MPN" "RC0402FR-072ML"
			(at 0 0 0)
			(layer "B.Fab")
			(hide yes)
			(effects
				(font
					(size 1 1)
					(thickness 0.15)
				)
				(justify mirror)
			)
		)
		(property "Manufacturer" "YAGEO"
			(at 0 0 0)
			(layer "B.Fab")
			(hide yes)
			(effects
				(font
					(size 1 1)
					(thickness 0.15)
				)
				(justify mirror)
			)
		)
		(property "Tolerance" "1%"
			(at 0 0 0)
			(layer "B.Fab")
			(hide yes)
			(effects
				(font
					(size 1 1)
					(thickness 0.15)
				)
				(justify mirror)
			)
		)
		(property "Val" "2M"
			(at 0 0 0)
			(layer "B.Fab")
			(hide yes)
			(effects
				(font
					(size 1 1)
					(thickness 0.15)
				)
				(justify mirror)
			)
		)
		(sheetname "USB Debug, DP")
		(sheetfile "usb.kicad_sch")
		(attr smd)
		(fp_rect
			(start -0.925 0.47)
			(end 0.925 -0.47)
			(stroke
				(width 0.05)
				(type default)
			)
			(fill none)
			(layer "B.CrtYd")
		)
		(fp_rect
			(start -0.5 0.25)
			(end 0.5 -0.25)
			(stroke
				(width 0.15)
				(type solid)
			)
			(fill none)
			(layer "B.Fab")
		)
		(fp_text user "${REFERENCE}"
			(at -0.95 -3.168 180)
			(layer "B.Fab")
			(hide yes)
			(effects
				(font
					(size 0.7 0.7)
					(thickness 0.15)
				)
				(justify left bottom mirror)
			)
		)
		(fp_text user "License: Apache-2.0"
			(at -0.95 -5.169 180)
			(layer "B.Fab")
			(hide yes)
			(effects
				(font
					(size 0.7 0.7)
					(thickness 0.15)
				)
				(justify left bottom mirror)
			)
		)
		(fp_text user "Author: Antmicro"
			(at -0.95 -4.169 180)
			(layer "B.Fab")
			(hide yes)
			(effects
				(font
					(size 0.7 0.7)
					(thickness 0.15)
				)
				(justify left bottom mirror)
			)
		)
		(pad "1" smd roundrect
			(at -0.48 0)
			(size 0.59 0.64)
			(layers "B.Cu" "B.Paste" "B.Mask")
			(roundrect_rratio 0.25)
			(net 614 "/USB Debug, DP/USBC0_SBU_P")
			(pintype "passive")
		)
		(pad "2" smd roundrect
			(at 0.48 0)
			(size 0.59 0.64)
			(layers "B.Cu" "B.Paste" "B.Mask")
			(roundrect_rratio 0.25)
			(net 1 "GND")
			(pintype "passive")
		)
	)
	(footprint "antmicro-footprints:C_0402_1005Metric"
		(layer "B.Cu")
		(at 126.735 86.75)
		(descr "Capacitor SMD 0402")
		(tags "capacitor SMD 0402")
		(property "Reference" "C14"
			(at 2.965 0.4 180)
			(layer "B.SilkS")
			(effects
				(font
					(size 0.7 0.7)
					(thickness 0.15)
				)
				(justify left bottom mirror)
			)
		)
		(property "Value" "C_220n_0402"
			(at 0 -1.4 180)
			(layer "B.Fab")
			(effects
				(font
					(size 0.7 0.7)
					(thickness 0.15)
				)
				(justify left bottom mirror)
			)
		)
		(property "Footprint" "antmicro-footprints:C_0402_1005Metric"
			(at 0 0 0)
			(layer "F.Fab")
			(hide yes)
			(effects
				(font
					(size 1.27 1.27)
					(thickness 0.15)
				)
			)
		)
		(property "Datasheet" "https://www.yageo.com/en/Chart/Download/pdf/CC0402KRX5R6BB224"
			(at 0 0 0)
			(layer "F.Fab")
			(hide yes)
			(effects
				(font
					(size 1.27 1.27)
					(thickness 0.15)
				)
			)
		)
		(property "Author" "Antmicro"
			(at 0 0 0)
			(layer "B.Fab")
			(hide yes)
			(effects
				(font
					(size 1 1)
					(thickness 0.15)
				)
				(justify mirror)
			)
		)
		(property "Dielectric" ""
			(at 0 0 0)
			(layer "B.Fab")
			(hide yes)
			(effects
				(font
					(size 1 1)
					(thickness 0.15)
				)
				(justify mirror)
			)
		)
		(property "License" "Apache-2.0"
			(at 0 0 0)
			(layer "B.Fab")
			(hide yes)
			(effects
				(font
					(size 1 1)
					(thickness 0.15)
				)
				(justify mirror)
			)
		)
		(property "MPN" "CC0402KRX5R6BB224"
			(at 0 0 0)
			(layer "B.Fab")
			(hide yes)
			(effects
				(font
					(size 1 1)
					(thickness 0.15)
				)
				(justify mirror)
			)
		)
		(property "Manufacturer" "YAGEO"
			(at 0 0 0)
			(layer "B.Fab")
			(hide yes)
			(effects
				(font
					(size 1 1)
					(thickness 0.15)
				)
				(justify mirror)
			)
		)
		(property "Val" "220n"
			(at 0 0 0)
			(layer "B.Fab")
			(hide yes)
			(effects
				(font
					(size 1 1)
					(thickness 0.15)
				)
				(justify mirror)
			)
		)
		(property "Voltage" ""
			(at 0 0 0)
			(layer "B.Fab")
			(hide yes)
			(effects
				(font
					(size 1 1)
					(thickness 0.15)
				)
				(justify mirror)
			)
		)
		(sheetname "M.2")
		(sheetfile "m-2.kicad_sch")
		(attr smd)
		(fp_rect
			(start -0.925 0.47)
			(end 0.925 -0.47)
			(stroke
				(width 0.05)
				(type default)
			)
			(fill none)
			(layer "B.CrtYd")
		)
		(fp_line
			(start -0.494 -0.248)
			(end 0.504 -0.248)
			(stroke
				(width 0.15)
				(type solid)
			)
			(layer "B.Fab")
		)
		(fp_line
			(start -0.494 0.25)
			(end -0.494 -0.248)
			(stroke
				(width 0.15)
				(type solid)
			)
			(layer "B.Fab")
		)
		(fp_line
			(start 0.504 -0.248)
			(end 0.504 0.25)
			(stroke
				(width 0.15)
				(type solid)
			)
			(layer "B.Fab")
		)
		(fp_line
			(start 0.504 0.25)
			(end -0.494 0.25)
			(stroke
				(width 0.15)
				(type solid)
			)
			(layer "B.Fab")
		)
		(fp_text user "Author: Antmicro"
			(at -0.932 -4.17 180)
			(layer "B.Fab")
			(hide yes)
			(effects
				(font
					(size 0.7 0.7)
					(thickness 0.15)
				)
				(justify left bottom mirror)
			)
		)
		(fp_text user "License: Apache-2.0"
			(at -0.932 -5.17 180)
			(layer "B.Fab")
			(hide yes)
			(effects
				(font
					(size 0.7 0.7)
					(thickness 0.15)
				)
				(justify left bottom mirror)
			)
		)
		(fp_text user "${REFERENCE}"
			(at -0.932 -3.168 180)
			(layer "B.Fab")
			(hide yes)
			(effects
				(font
					(size 0.7 0.7)
					(thickness 0.15)
				)
				(justify left bottom mirror)
			)
		)
		(pad "1" smd roundrect
			(at -0.48 0)
			(size 0.59 0.64)
			(layers "B.Cu" "B.Paste" "B.Mask")
			(roundrect_rratio 0.25)
			(net 90 "/M.2/C_PCIE0_TX1_P")
			(pintype "passive")
		)
		(pad "2" smd roundrect
			(at 0.48 0)
			(size 0.59 0.64)
			(layers "B.Cu" "B.Paste" "B.Mask")
			(roundrect_rratio 0.25)
			(net 444 "PCIE0_TX1_P")
			(pintype "passive")
		)
	)
	(footprint "antmicro-footprints:R_0402_1005Metric"
		(layer "B.Cu")
		(at 77.6 108.4 180)
		(descr "Resistor SMD 0402")
		(tags "resistor SMD 0402")
		(property "Reference" "R94"
			(at -3.14 -2.38 0)
			(layer "B.SilkS")
			(effects
				(font
					(size 0.7 0.7)
					(thickness 0.15)
				)
				(justify left bottom mirror)
			)
		)
		(property "Value" "R_1k_0402"
			(at 0 -1.4 0)
			(layer "B.Fab")
			(effects
				(font
					(size 0.7 0.7)
					(thickness 0.15)
				)
				(justify left bottom mirror)
			)
		)
		(property "Footprint" "antmicro-footprints:R_0402_1005Metric"
			(at 0 0 180)
			(layer "F.Fab")
			(hide yes)
			(effects
				(font
					(size 1.27 1.27)
					(thickness 0.15)
				)
			)
		)
		(property "Datasheet" "https://www.bourns.com/docs/product-datasheets/cr.pdf"
			(at 0 0 180)
			(layer "F.Fab")
			(hide yes)
			(effects
				(font
					(size 1.27 1.27)
					(thickness 0.15)
				)
			)
		)
		(property "Author" "Antmicro"
			(at 155.2 216.8 0)
			(layer "B.Fab")
			(hide yes)
			(effects
				(font
					(size 1 1)
					(thickness 0.15)
				)
				(justify mirror)
			)
		)
		(property "License" "Apache-2.0"
			(at 155.2 216.8 0)
			(layer "B.Fab")
			(hide yes)
			(effects
				(font
					(size 1 1)
					(thickness 0.15)
				)
				(justify mirror)
			)
		)
		(property "MPN" "CR0402-FX-1001GLF"
			(at 155.2 216.8 0)
			(layer "B.Fab")
			(hide yes)
			(effects
				(font
					(size 1 1)
					(thickness 0.15)
				)
				(justify mirror)
			)
		)
		(property "Manufacturer" "Bourns"
			(at 155.2 216.8 0)
			(layer "B.Fab")
			(hide yes)
			(effects
				(font
					(size 1 1)
					(thickness 0.15)
				)
				(justify mirror)
			)
		)
		(property "Tolerance" "1%"
			(at 155.2 216.8 0)
			(layer "B.Fab")
			(hide yes)
			(effects
				(font
					(size 1 1)
					(thickness 0.15)
				)
				(justify mirror)
			)
		)
		(property "Val" "1k"
			(at 155.2 216.8 0)
			(layer "B.Fab")
			(hide yes)
			(effects
				(font
					(size 1 1)
					(thickness 0.15)
				)
				(justify mirror)
			)
		)
		(sheetname "USB Debug, DP")
		(sheetfile "usb.kicad_sch")
		(attr smd)
		(fp_rect
			(start -0.925 0.47)
			(end 0.925 -0.47)
			(stroke
				(width 0.05)
				(type default)
			)
			(fill none)
			(layer "B.CrtYd")
		)
		(fp_rect
			(start -0.5 0.25)
			(end 0.5 -0.25)
			(stroke
				(width 0.15)
				(type solid)
			)
			(fill none)
			(layer "B.Fab")
		)
		(fp_text user "${REFERENCE}"
			(at -0.95 -3.168 0)
			(layer "B.Fab")
			(hide yes)
			(effects
				(font
					(size 0.7 0.7)
					(thickness 0.15)
				)
				(justify left bottom mirror)
			)
		)
		(fp_text user "Author: Antmicro"
			(at -0.95 -4.169 0)
			(layer "B.Fab")
			(hide yes)
			(effects
				(font
					(size 0.7 0.7)
					(thickness 0.15)
				)
				(justify left bottom mirror)
			)
		)
		(fp_text user "License: Apache-2.0"
			(at -0.95 -5.169 0)
			(layer "B.Fab")
			(hide yes)
			(effects
				(font
					(size 0.7 0.7)
					(thickness 0.15)
				)
				(justify left bottom mirror)
			)
		)
		(pad "1" smd roundrect
			(at -0.48 0 180)
			(size 0.59 0.64)
			(layers "B.Cu" "B.Paste" "B.Mask")
			(roundrect_rratio 0.25)
			(net 308 "/USB Debug, DP/USBC0_DPEQ1")
			(pintype "passive")
		)
		(pad "2" smd roundrect
			(at 0.48 0 180)
			(size 0.59 0.64)
			(layers "B.Cu" "B.Paste" "B.Mask")
			(roundrect_rratio 0.25)
			(net 1 "GND")
			(pintype "passive")
		)
	)
	(footprint "antmicro-footprints:R_0402_1005Metric"
		(layer "B.Cu")
		(at 43.77 125.35 90)
		(descr "Resistor SMD 0402")
		(tags "resistor SMD 0402")
		(property "Reference" "R73"
			(at -1.2 -1.77 -90)
			(layer "B.SilkS")
			(effects
				(font
					(size 0.7 0.7)
					(thickness 0.15)
				)
				(justify left bottom mirror)
			)
		)
		(property "Value" "R_200R_0402"
			(at 0 -1.4 -90)
			(layer "B.Fab")
			(effects
				(font
					(size 0.7 0.7)
					(thickness 0.15)
				)
				(justify left bottom mirror)
			)
		)
		(property "Footprint" "antmicro-footprints:R_0402_1005Metric"
			(at 0 0 90)
			(layer "F.Fab")
			(hide yes)
			(effects
				(font
					(size 1.27 1.27)
					(thickness 0.15)
				)
			)
		)
		(property "Datasheet" "https://www.bourns.com/docs/product-datasheets/cr.pdf"
			(at 0 0 90)
			(layer "F.Fab")
			(hide yes)
			(effects
				(font
					(size 1.27 1.27)
					(thickness 0.15)
				)
			)
		)
		(property "Author" "Antmicro"
			(at 169.12 81.58 0)
			(layer "B.Fab")
			(hide yes)
			(effects
				(font
					(size 1 1)
					(thickness 0.15)
				)
				(justify mirror)
			)
		)
		(property "License" "Apache-2.0"
			(at 169.12 81.58 0)
			(layer "B.Fab")
			(hide yes)
			(effects
				(font
					(size 1 1)
					(thickness 0.15)
				)
				(justify mirror)
			)
		)
		(property "MPN" "CR0402-FX-2000GLF"
			(at 169.12 81.58 0)
			(layer "B.Fab")
			(hide yes)
			(effects
				(font
					(size 1 1)
					(thickness 0.15)
				)
				(justify mirror)
			)
		)
		(property "Manufacturer" "Bourns"
			(at 169.12 81.58 0)
			(layer "B.Fab")
			(hide yes)
			(effects
				(font
					(size 1 1)
					(thickness 0.15)
				)
				(justify mirror)
			)
		)
		(property "Tolerance" "1%"
			(at 169.12 81.58 0)
			(layer "B.Fab")
			(hide yes)
			(effects
				(font
					(size 1 1)
					(thickness 0.15)
				)
				(justify mirror)
			)
		)
		(property "Val" "200R"
			(at 169.12 81.58 0)
			(layer "B.Fab")
			(hide yes)
			(effects
				(font
					(size 1 1)
					(thickness 0.15)
				)
				(justify mirror)
			)
		)
		(sheetname "USB Debug, DP")
		(sheetfile "usb.kicad_sch")
		(attr smd)
		(fp_rect
			(start -0.925 0.47)
			(end 0.925 -0.47)
			(stroke
				(width 0.05)
				(type default)
			)
			(fill none)
			(layer "B.CrtYd")
		)
		(fp_rect
			(start -0.5 0.25)
			(end 0.5 -0.25)
			(stroke
				(width 0.15)
				(type solid)
			)
			(fill none)
			(layer "B.Fab")
		)
		(fp_text user "${REFERENCE}"
			(at -0.95 -3.168 -90)
			(layer "B.Fab")
			(hide yes)
			(effects
				(font
					(size 0.7 0.7)
					(thickness 0.15)
				)
				(justify left bottom mirror)
			)
		)
		(fp_text user "License: Apache-2.0"
			(at -0.95 -5.169 -90)
			(layer "B.Fab")
			(hide yes)
			(effects
				(font
					(size 0.7 0.7)
					(thickness 0.15)
				)
				(justify left bottom mirror)
			)
		)
		(fp_text user "Author: Antmicro"
			(at -0.95 -4.169 -90)
			(layer "B.Fab")
			(hide yes)
			(effects
				(font
					(size 0.7 0.7)
					(thickness 0.15)
				)
				(justify left bottom mirror)
			)
		)
		(pad "1" smd roundrect
			(at -0.48 0 90)
			(size 0.59 0.64)
			(layers "B.Cu" "B.Paste" "B.Mask")
			(roundrect_rratio 0.25)
			(net 143 "Net-(D3-A)")
			(pintype "passive")
		)
		(pad "2" smd roundrect
			(at 0.48 0 90)
			(size 0.59 0.64)
			(layers "B.Cu" "B.Paste" "B.Mask")
			(roundrect_rratio 0.25)
			(net 185 "/USB Debug, DP/FTDI_3V3")
			(pintype "passive")
		)
	)
	(footprint "antmicro-footprints:R_0402_1005Metric"
		(layer "B.Cu")
		(at 79.5 108.4)
		(descr "Resistor SMD 0402")
		(tags "resistor SMD 0402")
		(property "Reference" "R93"
			(at 3.3 2.34 180)
			(layer "B.SilkS")
			(effects
				(font
					(size 0.7 0.7)
					(thickness 0.15)
				)
				(justify left bottom mirror)
			)
		)
		(property "Value" "R_1k_0402"
			(at 0 -1.4 180)
			(layer "B.Fab")
			(effects
				(font
					(size 0.7 0.7)
					(thickness 0.15)
				)
				(justify left bottom mirror)
			)
		)
		(property "Footprint" "antmicro-footprints:R_0402_1005Metric"
			(at 0 0 0)
			(layer "F.Fab")
			(hide yes)
			(effects
				(font
					(size 1.27 1.27)
					(thickness 0.15)
				)
			)
		)
		(property "Datasheet" "https://www.bourns.com/docs/product-datasheets/cr.pdf"
			(at 0 0 0)
			(layer "F.Fab")
			(hide yes)
			(effects
				(font
					(size 1.27 1.27)
					(thickness 0.15)
				)
			)
		)
		(property "Author" "Antmicro"
			(at 0 0 0)
			(layer "B.Fab")
			(hide yes)
			(effects
				(font
					(size 1 1)
					(thickness 0.15)
				)
				(justify mirror)
			)
		)
		(property "License" "Apache-2.0"
			(at 0 0 0)
			(layer "B.Fab")
			(hide yes)
			(effects
				(font
					(size 1 1)
					(thickness 0.15)
				)
				(justify mirror)
			)
		)
		(property "MPN" "CR0402-FX-1001GLF"
			(at 0 0 0)
			(layer "B.Fab")
			(hide yes)
			(effects
				(font
					(size 1 1)
					(thickness 0.15)
				)
				(justify mirror)
			)
		)
		(property "Manufacturer" "Bourns"
			(at 0 0 0)
			(layer "B.Fab")
			(hide yes)
			(effects
				(font
					(size 1 1)
					(thickness 0.15)
				)
				(justify mirror)
			)
		)
		(property "Tolerance" "1%"
			(at 0 0 0)
			(layer "B.Fab")
			(hide yes)
			(effects
				(font
					(size 1 1)
					(thickness 0.15)
				)
				(justify mirror)
			)
		)
		(property "Val" "1k"
			(at 0 0 0)
			(layer "B.Fab")
			(hide yes)
			(effects
				(font
					(size 1 1)
					(thickness 0.15)
				)
				(justify mirror)
			)
		)
		(sheetname "USB Debug, DP")
		(sheetfile "usb.kicad_sch")
		(attr smd exclude_from_pos_files exclude_from_bom dnp)
		(fp_rect
			(start -0.925 0.47)
			(end 0.925 -0.47)
			(stroke
				(width 0.05)
				(type default)
			)
			(fill none)
			(layer "B.CrtYd")
		)
		(fp_rect
			(start -0.5 0.25)
			(end 0.5 -0.25)
			(stroke
				(width 0.15)
				(type solid)
			)
			(fill none)
			(layer "B.Fab")
		)
		(fp_text user "License: Apache-2.0"
			(at -0.95 -5.169 180)
			(layer "B.Fab")
			(hide yes)
			(effects
				(font
					(size 0.7 0.7)
					(thickness 0.15)
				)
				(justify left bottom mirror)
			)
		)
		(fp_text user "Author: Antmicro"
			(at -0.95 -4.169 180)
			(layer "B.Fab")
			(hide yes)
			(effects
				(font
					(size 0.7 0.7)
					(thickness 0.15)
				)
				(justify left bottom mirror)
			)
		)
		(fp_text user "${REFERENCE}"
			(at -0.95 -3.168 180)
			(layer "B.Fab")
			(hide yes)
			(effects
				(font
					(size 0.7 0.7)
					(thickness 0.15)
				)
				(justify left bottom mirror)
			)
		)
		(pad "1" smd roundrect
			(at -0.48 0)
			(size 0.59 0.64)
			(layers "B.Cu" "B.Paste" "B.Mask")
			(roundrect_rratio 0.25)
			(net 308 "/USB Debug, DP/USBC0_DPEQ1")
			(pintype "passive")
		)
		(pad "2" smd roundrect
			(at 0.48 0)
			(size 0.59 0.64)
			(layers "B.Cu" "B.Paste" "B.Mask")
			(roundrect_rratio 0.25)
			(net 87 "+3V3")
			(pintype "passive")
		)
	)
	(footprint "antmicro-footprints:C_0402_1005Metric"
		(layer "B.Cu")
		(at 126.735 83.75)
		(descr "Capacitor SMD 0402")
		(tags "capacitor SMD 0402")
		(property "Reference" "C13"
			(at 2.965 0.45 180)
			(layer "B.SilkS")
			(effects
				(font
					(size 0.7 0.7)
					(thickness 0.15)
				)
				(justify left bottom mirror)
			)
		)
		(property "Value" "C_220n_0402"
			(at 0 -1.4 180)
			(layer "B.Fab")
			(effects
				(font
					(size 0.7 0.7)
					(thickness 0.15)
				)
				(justify left bottom mirror)
			)
		)
		(property "Footprint" "antmicro-footprints:C_0402_1005Metric"
			(at 0 0 0)
			(layer "F.Fab")
			(hide yes)
			(effects
				(font
					(size 1.27 1.27)
					(thickness 0.15)
				)
			)
		)
		(property "Datasheet" "https://www.yageo.com/en/Chart/Download/pdf/CC0402KRX5R6BB224"
			(at 0 0 0)
			(layer "F.Fab")
			(hide yes)
			(effects
				(font
					(size 1.27 1.27)
					(thickness 0.15)
				)
			)
		)
		(property "Author" "Antmicro"
			(at 0 0 0)
			(layer "B.Fab")
			(hide yes)
			(effects
				(font
					(size 1 1)
					(thickness 0.15)
				)
				(justify mirror)
			)
		)
		(property "Dielectric" ""
			(at 0 0 0)
			(layer "B.Fab")
			(hide yes)
			(effects
				(font
					(size 1 1)
					(thickness 0.15)
				)
				(justify mirror)
			)
		)
		(property "License" "Apache-2.0"
			(at 0 0 0)
			(layer "B.Fab")
			(hide yes)
			(effects
				(font
					(size 1 1)
					(thickness 0.15)
				)
				(justify mirror)
			)
		)
		(property "MPN" "CC0402KRX5R6BB224"
			(at 0 0 0)
			(layer "B.Fab")
			(hide yes)
			(effects
				(font
					(size 1 1)
					(thickness 0.15)
				)
				(justify mirror)
			)
		)
		(property "Manufacturer" "YAGEO"
			(at 0 0 0)
			(layer "B.Fab")
			(hide yes)
			(effects
				(font
					(size 1 1)
					(thickness 0.15)
				)
				(justify mirror)
			)
		)
		(property "Val" "220n"
			(at 0 0 0)
			(layer "B.Fab")
			(hide yes)
			(effects
				(font
					(size 1 1)
					(thickness 0.15)
				)
				(justify mirror)
			)
		)
		(property "Voltage" ""
			(at 0 0 0)
			(layer "B.Fab")
			(hide yes)
			(effects
				(font
					(size 1 1)
					(thickness 0.15)
				)
				(justify mirror)
			)
		)
		(sheetname "M.2")
		(sheetfile "m-2.kicad_sch")
		(attr smd)
		(fp_rect
			(start -0.925 0.47)
			(end 0.925 -0.47)
			(stroke
				(width 0.05)
				(type default)
			)
			(fill none)
			(layer "B.CrtYd")
		)
		(fp_line
			(start -0.494 -0.248)
			(end 0.504 -0.248)
			(stroke
				(width 0.15)
				(type solid)
			)
			(layer "B.Fab")
		)
		(fp_line
			(start -0.494 0.25)
			(end -0.494 -0.248)
			(stroke
				(width 0.15)
				(type solid)
			)
			(layer "B.Fab")
		)
		(fp_line
			(start 0.504 -0.248)
			(end 0.504 0.25)
			(stroke
				(width 0.15)
				(type solid)
			)
			(layer "B.Fab")
		)
		(fp_line
			(start 0.504 0.25)
			(end -0.494 0.25)
			(stroke
				(width 0.15)
				(type solid)
			)
			(layer "B.Fab")
		)
		(fp_text user "Author: Antmicro"
			(at -0.932 -4.17 180)
			(layer "B.Fab")
			(hide yes)
			(effects
				(font
					(size 0.7 0.7)
					(thickness 0.15)
				)
				(justify left bottom mirror)
			)
		)
		(fp_text user "${REFERENCE}"
			(at -0.932 -3.168 180)
			(layer "B.Fab")
			(hide yes)
			(effects
				(font
					(size 0.7 0.7)
					(thickness 0.15)
				)
				(justify left bottom mirror)
			)
		)
		(fp_text user "License: Apache-2.0"
			(at -0.932 -5.17 180)
			(layer "B.Fab")
			(hide yes)
			(effects
				(font
					(size 0.7 0.7)
					(thickness 0.15)
				)
				(justify left bottom mirror)
			)
		)
		(pad "1" smd roundrect
			(at -0.48 0)
			(size 0.59 0.64)
			(layers "B.Cu" "B.Paste" "B.Mask")
			(roundrect_rratio 0.25)
			(net 88 "/M.2/C_PCIE0_TX0_P")
			(pintype "passive")
		)
		(pad "2" smd roundrect
			(at 0.48 0)
			(size 0.59 0.64)
			(layers "B.Cu" "B.Paste" "B.Mask")
			(roundrect_rratio 0.25)
			(net 442 "PCIE0_TX0_P")
			(pintype "passive")
		)
	)
	(footprint "antmicro-footprints:R_0402_1005Metric"
		(layer "B.Cu")
		(at 106.4 89.82 -90)
		(descr "Resistor SMD 0402")
		(tags "resistor SMD 0402")
		(property "Reference" "R18"
			(at -1.12 0.45 90)
			(layer "B.SilkS")
			(effects
				(font
					(size 0.7 0.7)
					(thickness 0.15)
				)
				(justify left bottom mirror)
			)
		)
		(property "Value" "R_0R_0402"
			(at 0 -1.4 90)
			(layer "B.Fab")
			(effects
				(font
					(size 0.7 0.7)
					(thickness 0.15)
				)
				(justify left bottom mirror)
			)
		)
		(property "Footprint" "antmicro-footprints:R_0402_1005Metric"
			(at 0 0 -90)
			(layer "F.Fab")
			(hide yes)
			(effects
				(font
					(size 1.27 1.27)
					(thickness 0.15)
				)
			)
		)
		(property "Datasheet" "https://industrial.panasonic.com/cdbs/www-data/pdf/RDA0000/AOA0000C301.pdf"
			(at 0 0 -90)
			(layer "F.Fab")
			(hide yes)
			(effects
				(font
					(size 1.27 1.27)
					(thickness 0.15)
				)
			)
		)
		(property "Author" "Antmicro"
			(at 16.58 196.22 0)
			(layer "B.Fab")
			(hide yes)
			(effects
				(font
					(size 1 1)
					(thickness 0.15)
				)
				(justify mirror)
			)
		)
		(property "Current" "1A"
			(at 16.58 196.22 0)
			(layer "B.Fab")
			(hide yes)
			(effects
				(font
					(size 1 1)
					(thickness 0.15)
				)
				(justify mirror)
			)
		)
		(property "License" "Apache-2.0"
			(at 16.58 196.22 0)
			(layer "B.Fab")
			(hide yes)
			(effects
				(font
					(size 1 1)
					(thickness 0.15)
				)
				(justify mirror)
			)
		)
		(property "MPN" "ERJ2GE0R00X"
			(at 16.58 196.22 0)
			(layer "B.Fab")
			(hide yes)
			(effects
				(font
					(size 1 1)
					(thickness 0.15)
				)
				(justify mirror)
			)
		)
		(property "Manufacturer" "Panasonic"
			(at 16.58 196.22 0)
			(layer "B.Fab")
			(hide yes)
			(effects
				(font
					(size 1 1)
					(thickness 0.15)
				)
				(justify mirror)
			)
		)
		(property "Tolerance" ""
			(at 16.58 196.22 0)
			(layer "B.Fab")
			(hide yes)
			(effects
				(font
					(size 1 1)
					(thickness 0.15)
				)
				(justify mirror)
			)
		)
		(property "Val" "0R"
			(at 16.58 196.22 0)
			(layer "B.Fab")
			(hide yes)
			(effects
				(font
					(size 1 1)
					(thickness 0.15)
				)
				(justify mirror)
			)
		)
		(sheetname "M.2")
		(sheetfile "m-2.kicad_sch")
		(attr smd)
		(fp_rect
			(start -0.925 0.47)
			(end 0.925 -0.47)
			(stroke
				(width 0.05)
				(type default)
			)
			(fill none)
			(layer "B.CrtYd")
		)
		(fp_rect
			(start -0.5 0.25)
			(end 0.5 -0.25)
			(stroke
				(width 0.15)
				(type solid)
			)
			(fill none)
			(layer "B.Fab")
		)
		(fp_text user "Author: Antmicro"
			(at -0.95 -4.169 90)
			(layer "B.Fab")
			(hide yes)
			(effects
				(font
					(size 0.7 0.7)
					(thickness 0.15)
				)
				(justify left bottom mirror)
			)
		)
		(fp_text user "${REFERENCE}"
			(at -0.95 -3.168 90)
			(layer "B.Fab")
			(hide yes)
			(effects
				(font
					(size 0.7 0.7)
					(thickness 0.15)
				)
				(justify left bottom mirror)
			)
		)
		(fp_text user "License: Apache-2.0"
			(at -0.95 -5.169 90)
			(layer "B.Fab")
			(hide yes)
			(effects
				(font
					(size 0.7 0.7)
					(thickness 0.15)
				)
				(justify left bottom mirror)
			)
		)
		(pad "1" smd roundrect
			(at -0.48 0 270)
			(size 0.59 0.64)
			(layers "B.Cu" "B.Paste" "B.Mask")
			(roundrect_rratio 0.25)
			(net 455 "PCIE0_RST*")
			(pintype "passive")
		)
		(pad "2" smd roundrect
			(at 0.48 0 270)
			(size 0.59 0.64)
			(layers "B.Cu" "B.Paste" "B.Mask")
			(roundrect_rratio 0.25)
			(net 247 "/M.2/~{M2_M_PERST}")
			(pintype "passive")
		)
	)
	(footprint "antmicro-footprints:R_0402_1005Metric"
		(layer "B.Cu")
		(at 55.075 84.25)
		(descr "Resistor SMD 0402")
		(tags "resistor SMD 0402")
		(property "Reference" "R283"
			(at -1.075 0.65 0)
			(layer "B.SilkS")
			(effects
				(font
					(size 0.7 0.7)
					(thickness 0.15)
				)
				(justify right top mirror)
			)
		)
		(property "Value" "R_560R_0402"
			(at -1.011843 -1.772046 0)
			(layer "B.Fab")
			(effects
				(font
					(size 0.7 0.7)
					(thickness 0.15)
				)
				(justify right top mirror)
			)
		)
		(property "Footprint" "antmicro-footprints:R_0402_1005Metric"
			(at 0 0 0)
			(layer "B.Fab")
			(hide yes)
			(effects
				(font
					(size 1.27 1.27)
					(thickness 0.15)
				)
				(justify mirror)
			)
		)
		(property "Datasheet" "https://www.bourns.com/docs/product-datasheets/cr.pdf"
			(at 0 0 0)
			(layer "B.Fab")
			(hide yes)
			(effects
				(font
					(size 1.27 1.27)
					(thickness 0.15)
				)
				(justify mirror)
			)
		)
		(property "Description" "SMD Chip Resistor, 560 ohm, ± 1%, 100 mW, 0402 [1005 Metric], Thick Film, Precision"
			(at 0 0 0)
			(layer "B.Fab")
			(hide yes)
			(effects
				(font
					(size 1.27 1.27)
					(thickness 0.15)
				)
				(justify mirror)
			)
		)
		(property "MPN" "CR0402-FX-5600GLF"
			(at 0 0 180)
			(unlocked yes)
			(layer "B.Fab")
			(hide yes)
			(effects
				(font
					(size 1 1)
					(thickness 0.15)
				)
				(justify mirror)
			)
		)
		(property "Manufacturer" "Bourns"
			(at 0 0 180)
			(unlocked yes)
			(layer "B.Fab")
			(hide yes)
			(effects
				(font
					(size 1 1)
					(thickness 0.15)
				)
				(justify mirror)
			)
		)
		(property "License" "Apache-2.0"
			(at 0 0 180)
			(unlocked yes)
			(layer "B.Fab")
			(hide yes)
			(effects
				(font
					(size 1 1)
					(thickness 0.15)
				)
				(justify mirror)
			)
		)
		(property "Author" "Antmicro"
			(at 0 0 180)
			(unlocked yes)
			(layer "B.Fab")
			(hide yes)
			(effects
				(font
					(size 1 1)
					(thickness 0.15)
				)
				(justify mirror)
			)
		)
		(property "Val" "560R"
			(at 0 0 180)
			(unlocked yes)
			(layer "B.Fab")
			(hide yes)
			(effects
				(font
					(size 1 1)
					(thickness 0.15)
				)
				(justify mirror)
			)
		)
		(property "Tolerance" "1%"
			(at 0 0 180)
			(unlocked yes)
			(layer "B.Fab")
			(hide yes)
			(effects
				(font
					(size 1 1)
					(thickness 0.15)
				)
				(justify mirror)
			)
		)
		(sheetname "Supply")
		(sheetfile "supply.kicad_sch")
		(attr smd)
		(fp_poly
			(pts
				(xy -0.925 0.47) (xy 0.925 0.47) (xy 0.925 -0.47) (xy -0.925 -0.47)
			)
			(stroke
				(width 0.05)
				(type default)
			)
			(fill none)
			(layer "B.CrtYd")
		)
		(fp_poly
			(pts
				(xy -0.5 0.25) (xy 0.5 0.25) (xy 0.5 -0.25) (xy -0.5 -0.25)
			)
			(stroke
				(width 0.15)
				(type solid)
			)
			(fill none)
			(layer "B.Fab")
		)
		(fp_text user "${REFERENCE}"
			(at -0.95 -3.168 0)
			(layer "B.Fab")
			(hide yes)
			(effects
				(font
					(size 0.7 0.7)
					(thickness 0.15)
				)
				(justify right top mirror)
			)
		)
		(fp_text user "Author: Antmicro"
			(at -0.95 -4.169 0)
			(layer "B.Fab")
			(hide yes)
			(effects
				(font
					(size 0.7 0.7)
					(thickness 0.15)
				)
				(justify right top mirror)
			)
		)
		(fp_text user "License: Apache-2.0"
			(at -0.949999 -5.169 0)
			(layer "B.Fab")
			(hide yes)
			(effects
				(font
					(size 0.7 0.7)
					(thickness 0.15)
				)
				(justify right top mirror)
			)
		)
		(pad "1" smd roundrect
			(at -0.48 0)
			(size 0.59 0.64)
			(layers "B.Cu" "B.Paste" "B.Mask")
			(roundrect_rratio 0.25)
			(net 1 "GND")
			(pintype "passive")
		)
		(pad "2" smd roundrect
			(at 0.48 0)
			(size 0.59 0.64)
			(layers "B.Cu" "B.Paste" "B.Mask")
			(roundrect_rratio 0.25)
			(net 790 "Net-(U29-ILIM)")
			(pintype "passive")
		)
	)
	(footprint "antmicro-footprints:R_0402_1005Metric"
		(layer "B.Cu")
		(at 131.6 93.2 90)
		(descr "Resistor SMD 0402")
		(tags "resistor SMD 0402")
		(property "Reference" "R141"
			(at 3.67 0.45 -90)
			(layer "B.SilkS")
			(effects
				(font
					(size 0.7 0.7)
					(thickness 0.15)
				)
				(justify left bottom mirror)
			)
		)
		(property "Value" "R_0R_0402"
			(at 0 -1.4 -90)
			(layer "B.Fab")
			(effects
				(font
					(size 0.7 0.7)
					(thickness 0.15)
				)
				(justify left bottom mirror)
			)
		)
		(property "Footprint" "antmicro-footprints:R_0402_1005Metric"
			(at 0 0 90)
			(layer "F.Fab")
			(hide yes)
			(effects
				(font
					(size 1.27 1.27)
					(thickness 0.15)
				)
			)
		)
		(property "Datasheet" "https://industrial.panasonic.com/cdbs/www-data/pdf/RDA0000/AOA0000C301.pdf"
			(at 0 0 90)
			(layer "F.Fab")
			(hide yes)
			(effects
				(font
					(size 1.27 1.27)
					(thickness 0.15)
				)
			)
		)
		(property "Author" "Antmicro"
			(at 224.8 -38.4 0)
			(layer "B.Fab")
			(hide yes)
			(effects
				(font
					(size 1 1)
					(thickness 0.15)
				)
				(justify mirror)
			)
		)
		(property "Current" "1A"
			(at 224.8 -38.4 0)
			(layer "B.Fab")
			(hide yes)
			(effects
				(font
					(size 1 1)
					(thickness 0.15)
				)
				(justify mirror)
			)
		)
		(property "License" "Apache-2.0"
			(at 224.8 -38.4 0)
			(layer "B.Fab")
			(hide yes)
			(effects
				(font
					(size 1 1)
					(thickness 0.15)
				)
				(justify mirror)
			)
		)
		(property "MPN" "ERJ2GE0R00X"
			(at 224.8 -38.4 0)
			(layer "B.Fab")
			(hide yes)
			(effects
				(font
					(size 1 1)
					(thickness 0.15)
				)
				(justify mirror)
			)
		)
		(property "Manufacturer" "Panasonic"
			(at 224.8 -38.4 0)
			(layer "B.Fab")
			(hide yes)
			(effects
				(font
					(size 1 1)
					(thickness 0.15)
				)
				(justify mirror)
			)
		)
		(property "Tolerance" ""
			(at 224.8 -38.4 0)
			(layer "B.Fab")
			(hide yes)
			(effects
				(font
					(size 1 1)
					(thickness 0.15)
				)
				(justify mirror)
			)
		)
		(property "Val" "0R"
			(at 224.8 -38.4 0)
			(layer "B.Fab")
			(hide yes)
			(effects
				(font
					(size 1 1)
					(thickness 0.15)
				)
				(justify mirror)
			)
		)
		(sheetname "Peripherals")
		(sheetfile "peripherals.kicad_sch")
		(attr smd exclude_from_pos_files exclude_from_bom dnp)
		(fp_rect
			(start -0.925 0.47)
			(end 0.925 -0.47)
			(stroke
				(width 0.05)
				(type default)
			)
			(fill none)
			(layer "B.CrtYd")
		)
		(fp_rect
			(start -0.5 0.25)
			(end 0.5 -0.25)
			(stroke
				(width 0.15)
				(type solid)
			)
			(fill none)
			(layer "B.Fab")
		)
		(fp_text user "Author: Antmicro"
			(at -0.95 -4.169 -90)
			(layer "B.Fab")
			(hide yes)
			(effects
				(font
					(size 0.7 0.7)
					(thickness 0.15)
				)
				(justify left bottom mirror)
			)
		)
		(fp_text user "License: Apache-2.0"
			(at -0.95 -5.169 -90)
			(layer "B.Fab")
			(hide yes)
			(effects
				(font
					(size 0.7 0.7)
					(thickness 0.15)
				)
				(justify left bottom mirror)
			)
		)
		(fp_text user "${REFERENCE}"
			(at -0.95 -3.168 -90)
			(layer "B.Fab")
			(hide yes)
			(effects
				(font
					(size 0.7 0.7)
					(thickness 0.15)
				)
				(justify left bottom mirror)
			)
		)
		(pad "1" smd roundrect
			(at -0.48 0 90)
			(size 0.59 0.64)
			(layers "B.Cu" "B.Paste" "B.Mask")
			(roundrect_rratio 0.25)
			(net 619 "/Peripherals/USB_CONN_P")
			(pintype "passive")
		)
		(pad "2" smd roundrect
			(at 0.48 0 90)
			(size 0.59 0.64)
			(layers "B.Cu" "B.Paste" "B.Mask")
			(roundrect_rratio 0.25)
			(net 436 "USB1_D_P")
			(pintype "passive")
		)
	)
	(footprint "antmicro-footprints:TP_SMD_0.75mm"
		(layer "B.Cu")
		(at 103.3008 101.55 -90)
		(property "Reference" "TP36"
			(at 0 0.6 90)
			(layer "B.SilkS")
			(hide yes)
			(effects
				(font
					(size 0.7 0.7)
					(thickness 0.15)
				)
				(justify left bottom mirror)
			)
		)
		(property "Value" "TP_0.75mm_SMD"
			(at 0 -1.2 90)
			(layer "B.Fab")
			(effects
				(font
					(size 0.7 0.7)
					(thickness 0.15)
				)
				(justify left bottom mirror)
			)
		)
		(property "Footprint" "antmicro-footprints:TP_SMD_0.75mm"
			(at 0 0 -90)
			(layer "F.Fab")
			(hide yes)
			(effects
				(font
					(size 1.27 1.27)
					(thickness 0.15)
				)
			)
		)
		(property "Author" "Antmicro"
			(at 1.7508 204.8508 0)
			(layer "B.Fab")
			(hide yes)
			(effects
				(font
					(size 1 1)
					(thickness 0.15)
				)
				(justify mirror)
			)
		)
		(property "License" "Apache-2.0"
			(at 1.7508 204.8508 0)
			(layer "B.Fab")
			(hide yes)
			(effects
				(font
					(size 1 1)
					(thickness 0.15)
				)
				(justify mirror)
			)
		)
		(property "MPN" ""
			(at 1.7508 204.8508 0)
			(layer "B.Fab")
			(hide yes)
			(effects
				(font
					(size 1 1)
					(thickness 0.15)
				)
				(justify mirror)
			)
		)
		(property "Manufacturer" ""
			(at 1.7508 204.8508 0)
			(layer "B.Fab")
			(hide yes)
			(effects
				(font
					(size 1 1)
					(thickness 0.15)
				)
				(justify mirror)
			)
		)
		(sheetname "CSI")
		(sheetfile "csi.kicad_sch")
		(attr exclude_from_pos_files exclude_from_bom)
		(fp_circle
			(center 0 0)
			(end 0.475 0)
			(stroke
				(width 0.05)
				(type default)
			)
			(fill none)
			(layer "B.CrtYd")
		)
		(fp_text user "License: Apache-2.0"
			(at -0.4 -5.101 90)
			(layer "B.Fab")
			(hide yes)
			(effects
				(font
					(size 0.7 0.7)
					(thickness 0.15)
				)
				(justify left bottom mirror)
			)
		)
		(fp_text user "${REFERENCE}"
			(at -0.4 -2.7 90)
			(layer "B.Fab")
			(hide yes)
			(effects
				(font
					(size 0.7 0.7)
					(thickness 0.15)
				)
				(justify left bottom mirror)
			)
		)
		(fp_text user "Author: Antmicro"
			(at -0.4 -3.901 90)
			(layer "B.Fab")
			(hide yes)
			(effects
				(font
					(size 0.7 0.7)
					(thickness 0.15)
				)
				(justify left bottom mirror)
			)
		)
		(pad "1" smd circle
			(at 0 0 270)
			(size 0.75 0.75)
			(layers "B.Cu" "B.Mask")
			(net 535 "/CSI/MUX_I2C_4_SDA")
			(pinfunction "1")
			(pintype "passive")
		)
	)
	(footprint "antmicro-footprints:R_Array_4x0201_Panasonic_EXB18V"
		(layer "B.Cu")
		(at 119.53 74.35 -90)
		(property "Reference" "R107"
			(at 0.87 -1.53 90)
			(layer "B.SilkS")
			(effects
				(font
					(size 0.7 0.7)
					(thickness 0.15)
				)
				(justify right bottom mirror)
			)
		)
		(property "Value" "R_4x0R_0201_array"
			(at -1.1 -1.8 90)
			(layer "B.Fab")
			(effects
				(font
					(size 0.7 0.7)
					(thickness 0.15)
				)
				(justify left bottom mirror)
			)
		)
		(property "Footprint" "antmicro-footprints:R_Array_4x0201_Panasonic_EXB18V"
			(at 0 0 -90)
			(layer "F.Fab")
			(hide yes)
			(effects
				(font
					(size 1.27 1.27)
					(thickness 0.15)
				)
			)
		)
		(property "Datasheet" "http://industrial.panasonic.com/cdbs/www-data/pdf/AOC0000/AOC0000C14.pdf"
			(at 0 0 -90)
			(layer "F.Fab")
			(hide yes)
			(effects
				(font
					(size 1.27 1.27)
					(thickness 0.15)
				)
			)
		)
		(property "Author" "Antmicro"
			(at 45.18 193.88 0)
			(layer "B.Fab")
			(hide yes)
			(effects
				(font
					(size 1 1)
					(thickness 0.15)
				)
				(justify mirror)
			)
		)
		(property "License" "Apache-2.0"
			(at 45.18 193.88 0)
			(layer "B.Fab")
			(hide yes)
			(effects
				(font
					(size 1 1)
					(thickness 0.15)
				)
				(justify mirror)
			)
		)
		(property "MPN" "EXB-18VR000X"
			(at 45.18 193.88 0)
			(layer "B.Fab")
			(hide yes)
			(effects
				(font
					(size 1 1)
					(thickness 0.15)
				)
				(justify mirror)
			)
		)
		(property "Manufacturer" "Panasonic"
			(at 45.18 193.88 0)
			(layer "B.Fab")
			(hide yes)
			(effects
				(font
					(size 1 1)
					(thickness 0.15)
				)
				(justify mirror)
			)
		)
		(property "Val" "4x0R_0201"
			(at 45.18 193.88 0)
			(layer "B.Fab")
			(hide yes)
			(effects
				(font
					(size 1 1)
					(thickness 0.15)
				)
				(justify mirror)
			)
		)
		(sheetname "CSI")
		(sheetfile "csi.kicad_sch")
		(attr smd)
		(fp_line
			(start -0.8 -0.45)
			(end -0.8 0.45)
			(stroke
				(width 0.12)
				(type solid)
			)
			(layer "B.SilkS")
		)
		(fp_line
			(start 0.8 -0.45)
			(end 0.8 0.45)
			(stroke
				(width 0.12)
				(type solid)
			)
			(layer "B.SilkS")
		)
		(fp_rect
			(start -0.898 0.66)
			(end 0.898 -0.65)
			(stroke
				(width 0.05)
				(type solid)
			)
			(fill none)
			(layer "B.CrtYd")
		)
		(fp_text user "${REFERENCE}"
			(at -1.051 -3.2 90)
			(layer "B.Fab")
			(hide yes)
			(effects
				(font
					(size 0.7 0.7)
					(thickness 0.15)
				)
				(justify left bottom mirror)
			)
		)
		(fp_text user "Author: Antmicro"
			(at -1.051 -4.599 90)
			(layer "B.Fab")
			(hide yes)
			(effects
				(font
					(size 0.7 0.7)
					(thickness 0.15)
				)
				(justify left bottom mirror)
			)
		)
		(fp_text user "License: Apache-2.0"
			(at -1.051 -6 90)
			(layer "B.Fab")
			(hide yes)
			(effects
				(font
					(size 0.7 0.7)
					(thickness 0.15)
				)
				(justify left bottom mirror)
			)
		)
		(pad "1" smd roundrect
			(at -0.6 -0.298 270)
			(size 0.2 0.4)
			(layers "B.Cu" "B.Paste" "B.Mask")
			(roundrect_rratio 0.25)
			(net 10 "CSI1_D1_N")
			(pinfunction "R1.1")
			(pintype "passive")
		)
		(pad "2" smd roundrect
			(at -0.202 -0.298 270)
			(size 0.2 0.4)
			(layers "B.Cu" "B.Paste" "B.Mask")
			(roundrect_rratio 0.25)
			(net 12 "CSI1_D1_P")
			(pinfunction "R2.1")
			(pintype "passive")
		)
		(pad "3" smd roundrect
			(at 0.2 -0.298 270)
			(size 0.2 0.4)
			(layers "B.Cu" "B.Paste" "B.Mask")
			(roundrect_rratio 0.25)
			(net 2 "CSI1_D0_N")
			(pinfunction "R3.1")
			(pintype "passive")
		)
		(pad "4" smd roundrect
			(at 0.598 -0.298 270)
			(size 0.2 0.4)
			(layers "B.Cu" "B.Paste" "B.Mask")
			(roundrect_rratio 0.25)
			(net 4 "CSI1_D0_P")
			(pinfunction "R4.1")
			(pintype "passive")
		)
		(pad "5" smd roundrect
			(at 0.598 0.3 270)
			(size 0.2 0.4)
			(layers "B.Cu" "B.Paste" "B.Mask")
			(roundrect_rratio 0.25)
			(net 235 "/CSI/CSI1_1_D0_P")
			(pinfunction "R4.2")
			(pintype "passive")
		)
		(pad "6" smd roundrect
			(at 0.2 0.3 270)
			(size 0.2 0.4)
			(layers "B.Cu" "B.Paste" "B.Mask")
			(roundrect_rratio 0.25)
			(net 234 "/CSI/CSI1_1_D0_N")
			(pinfunction "R3.2")
			(pintype "passive")
		)
		(pad "7" smd roundrect
			(at -0.202 0.3 270)
			(size 0.2 0.4)
			(layers "B.Cu" "B.Paste" "B.Mask")
			(roundrect_rratio 0.25)
			(net 237 "/CSI/CSI1_1_D1_P")
			(pinfunction "R2.2")
			(pintype "passive")
		)
		(pad "8" smd roundrect
			(at -0.6 0.3 270)
			(size 0.2 0.4)
			(layers "B.Cu" "B.Paste" "B.Mask")
			(roundrect_rratio 0.25)
			(net 236 "/CSI/CSI1_1_D1_N")
			(pinfunction "R1.2")
			(pintype "passive")
		)
	)
	(footprint "antmicro-footprints:C_0402_1005Metric"
		(layer "B.Cu")
		(at 61.4 109.2 -90)
		(descr "Capacitor SMD 0402")
		(tags "capacitor SMD 0402")
		(property "Reference" "C53"
			(at 1.05 -0.29 90)
			(layer "B.SilkS")
			(effects
				(font
					(size 0.7 0.7)
					(thickness 0.15)
				)
				(justify left bottom mirror)
			)
		)
		(property "Value" "C_100n_0402"
			(at 0 -1.4 90)
			(layer "B.Fab")
			(effects
				(font
					(size 0.7 0.7)
					(thickness 0.15)
				)
				(justify left bottom mirror)
			)
		)
		(property "Footprint" "antmicro-footprints:C_0402_1005Metric"
			(at 0 0 -90)
			(layer "F.Fab")
			(hide yes)
			(effects
				(font
					(size 1.27 1.27)
					(thickness 0.15)
				)
			)
		)
		(property "Datasheet" "https://www.murata.com/products/productdetail?partno=GRM155R61H104KE14%23"
			(at 0 0 -90)
			(layer "F.Fab")
			(hide yes)
			(effects
				(font
					(size 1.27 1.27)
					(thickness 0.15)
				)
			)
		)
		(property "Author" "Antmicro"
			(at -47.8 170.6 0)
			(layer "B.Fab")
			(hide yes)
			(effects
				(font
					(size 1 1)
					(thickness 0.15)
				)
				(justify mirror)
			)
		)
		(property "Dielectric" "X5R"
			(at -47.8 170.6 0)
			(layer "B.Fab")
			(hide yes)
			(effects
				(font
					(size 1 1)
					(thickness 0.15)
				)
				(justify mirror)
			)
		)
		(property "License" "Apache-2.0"
			(at -47.8 170.6 0)
			(layer "B.Fab")
			(hide yes)
			(effects
				(font
					(size 1 1)
					(thickness 0.15)
				)
				(justify mirror)
			)
		)
		(property "MPN" "GRM155R61H104KE14D"
			(at -47.8 170.6 0)
			(layer "B.Fab")
			(hide yes)
			(effects
				(font
					(size 1 1)
					(thickness 0.15)
				)
				(justify mirror)
			)
		)
		(property "Manufacturer" "Murata"
			(at -47.8 170.6 0)
			(layer "B.Fab")
			(hide yes)
			(effects
				(font
					(size 1 1)
					(thickness 0.15)
				)
				(justify mirror)
			)
		)
		(property "Val" "100n"
			(at -47.8 170.6 0)
			(layer "B.Fab")
			(hide yes)
			(effects
				(font
					(size 1 1)
					(thickness 0.15)
				)
				(justify mirror)
			)
		)
		(property "Voltage" "50V"
			(at -47.8 170.6 0)
			(layer "B.Fab")
			(hide yes)
			(effects
				(font
					(size 1 1)
					(thickness 0.15)
				)
				(justify mirror)
			)
		)
		(sheetname "USB Debug, DP")
		(sheetfile "usb.kicad_sch")
		(attr smd)
		(fp_rect
			(start -0.925 0.47)
			(end 0.925 -0.47)
			(stroke
				(width 0.05)
				(type default)
			)
			(fill none)
			(layer "B.CrtYd")
		)
		(fp_line
			(start -0.494 0.25)
			(end -0.494 -0.248)
			(stroke
				(width 0.15)
				(type solid)
			)
			(layer "B.Fab")
		)
		(fp_line
			(start 0.504 0.25)
			(end -0.494 0.25)
			(stroke
				(width 0.15)
				(type solid)
			)
			(layer "B.Fab")
		)
		(fp_line
			(start -0.494 -0.248)
			(end 0.504 -0.248)
			(stroke
				(width 0.15)
				(type solid)
			)
			(layer "B.Fab")
		)
		(fp_line
			(start 0.504 -0.248)
			(end 0.504 0.25)
			(stroke
				(width 0.15)
				(type solid)
			)
			(layer "B.Fab")
		)
		(fp_text user "${REFERENCE}"
			(at -0.932 -3.168 90)
			(layer "B.Fab")
			(hide yes)
			(effects
				(font
					(size 0.7 0.7)
					(thickness 0.15)
				)
				(justify left bottom mirror)
			)
		)
		(fp_text user "Author: Antmicro"
			(at -0.932 -4.17 90)
			(layer "B.Fab")
			(hide yes)
			(effects
				(font
					(size 0.7 0.7)
					(thickness 0.15)
				)
				(justify left bottom mirror)
			)
		)
		(fp_text user "License: Apache-2.0"
			(at -0.932 -5.17 90)
			(layer "B.Fab")
			(hide yes)
			(effects
				(font
					(size 0.7 0.7)
					(thickness 0.15)
				)
				(justify left bottom mirror)
			)
		)
		(pad "1" smd roundrect
			(at -0.48 0 270)
			(size 0.59 0.64)
			(layers "B.Cu" "B.Paste" "B.Mask")
			(roundrect_rratio 0.25)
			(net 480 "USBPD1_HV")
			(pintype "passive")
		)
		(pad "2" smd roundrect
			(at 0.48 0 270)
			(size 0.59 0.64)
			(layers "B.Cu" "B.Paste" "B.Mask")
			(roundrect_rratio 0.25)
			(net 1 "GND")
			(pintype "passive")
		)
	)
	(footprint "antmicro-footprints:R_0402_1005Metric"
		(layer "B.Cu")
		(at 98.4 84.25 180)
		(descr "Resistor SMD 0402")
		(tags "resistor SMD 0402")
		(property "Reference" "R9"
			(at -0.87 -1.33 0)
			(layer "B.SilkS")
			(effects
				(font
					(size 0.7 0.7)
					(thickness 0.15)
				)
				(justify left bottom mirror)
			)
		)
		(property "Value" "R_4k7_0402"
			(at 0 -1.4 0)
			(layer "B.Fab")
			(effects
				(font
					(size 0.7 0.7)
					(thickness 0.15)
				)
				(justify left bottom mirror)
			)
		)
		(property "Footprint" "antmicro-footprints:R_0402_1005Metric"
			(at 0 0 180)
			(layer "F.Fab")
			(hide yes)
			(effects
				(font
					(size 1.27 1.27)
					(thickness 0.15)
				)
			)
		)
		(property "Datasheet" "https://www.bourns.com/docs/product-datasheets/cr.pdf"
			(at 0 0 180)
			(layer "F.Fab")
			(hide yes)
			(effects
				(font
					(size 1.27 1.27)
					(thickness 0.15)
				)
			)
		)
		(property "Author" "Antmicro"
			(at 196.8 168.5 0)
			(layer "B.Fab")
			(hide yes)
			(effects
				(font
					(size 1 1)
					(thickness 0.15)
				)
				(justify mirror)
			)
		)
		(property "License" "Apache-2.0"
			(at 196.8 168.5 0)
			(layer "B.Fab")
			(hide yes)
			(effects
				(font
					(size 1 1)
					(thickness 0.15)
				)
				(justify mirror)
			)
		)
		(property "MPN" "CR0402-FX-4701GLF"
			(at 196.8 168.5 0)
			(layer "B.Fab")
			(hide yes)
			(effects
				(font
					(size 1 1)
					(thickness 0.15)
				)
				(justify mirror)
			)
		)
		(property "Manufacturer" "Bourns"
			(at 196.8 168.5 0)
			(layer "B.Fab")
			(hide yes)
			(effects
				(font
					(size 1 1)
					(thickness 0.15)
				)
				(justify mirror)
			)
		)
		(property "Tolerance" "1%"
			(at 196.8 168.5 0)
			(layer "B.Fab")
			(hide yes)
			(effects
				(font
					(size 1 1)
					(thickness 0.15)
				)
				(justify mirror)
			)
		)
		(property "Val" "4k7"
			(at 196.8 168.5 0)
			(layer "B.Fab")
			(hide yes)
			(effects
				(font
					(size 1 1)
					(thickness 0.15)
				)
				(justify mirror)
			)
		)
		(sheetname "CSI")
		(sheetfile "csi.kicad_sch")
		(attr smd)
		(fp_rect
			(start -0.925 0.47)
			(end 0.925 -0.47)
			(stroke
				(width 0.05)
				(type default)
			)
			(fill none)
			(layer "B.CrtYd")
		)
		(fp_rect
			(start -0.5 0.25)
			(end 0.5 -0.25)
			(stroke
				(width 0.15)
				(type solid)
			)
			(fill none)
			(layer "B.Fab")
		)
		(fp_text user "License: Apache-2.0"
			(at -0.95 -5.169 0)
			(layer "B.Fab")
			(hide yes)
			(effects
				(font
					(size 0.7 0.7)
					(thickness 0.15)
				)
				(justify left bottom mirror)
			)
		)
		(fp_text user "${REFERENCE}"
			(at -0.95 -3.168 0)
			(layer "B.Fab")
			(hide yes)
			(effects
				(font
					(size 0.7 0.7)
					(thickness 0.15)
				)
				(justify left bottom mirror)
			)
		)
		(fp_text user "Author: Antmicro"
			(at -0.95 -4.169 0)
			(layer "B.Fab")
			(hide yes)
			(effects
				(font
					(size 0.7 0.7)
					(thickness 0.15)
				)
				(justify left bottom mirror)
			)
		)
		(pad "1" smd roundrect
			(at -0.48 0 180)
			(size 0.59 0.64)
			(layers "B.Cu" "B.Paste" "B.Mask")
			(roundrect_rratio 0.25)
			(net 1 "GND")
			(pintype "passive")
		)
		(pad "2" smd roundrect
			(at 0.48 0 180)
			(size 0.59 0.64)
			(layers "B.Cu" "B.Paste" "B.Mask")
			(roundrect_rratio 0.25)
			(net 343 "/CSI/CSIB_5V_ISET")
			(pintype "passive")
		)
	)
	(footprint "antmicro-footprints:TP_SMD_0.75mm"
		(layer "B.Cu")
		(at 130.085 88.869999)
		(property "Reference" "TP12"
			(at 0.395 0.365001 0)
			(layer "B.SilkS")
			(effects
				(font
					(size 0.7 0.7)
					(thickness 0.15)
				)
				(justify right bottom mirror)
			)
		)
		(property "Value" "TP_0.75mm_SMD"
			(at 0 -1.2 0)
			(layer "B.Fab")
			(effects
				(font
					(size 0.7 0.7)
					(thickness 0.15)
				)
				(justify right bottom mirror)
			)
		)
		(property "Footprint" "antmicro-footprints:TP_SMD_0.75mm"
			(at 0 0 0)
			(layer "F.Fab")
			(hide yes)
			(effects
				(font
					(size 1.27 1.27)
					(thickness 0.15)
				)
			)
		)
		(property "Author" "Antmicro"
			(at 0 0 0)
			(layer "B.Fab")
			(hide yes)
			(effects
				(font
					(size 1 1)
					(thickness 0.15)
				)
				(justify mirror)
			)
		)
		(property "License" "Apache-2.0"
			(at 0 0 0)
			(layer "B.Fab")
			(hide yes)
			(effects
				(font
					(size 1 1)
					(thickness 0.15)
				)
				(justify mirror)
			)
		)
		(property "MPN" ""
			(at 0 0 0)
			(layer "B.Fab")
			(hide yes)
			(effects
				(font
					(size 1 1)
					(thickness 0.15)
				)
				(justify mirror)
			)
		)
		(property "Manufacturer" ""
			(at 0 0 0)
			(layer "B.Fab")
			(hide yes)
			(effects
				(font
					(size 1 1)
					(thickness 0.15)
				)
				(justify mirror)
			)
		)
		(sheetname "M.2")
		(sheetfile "m-2.kicad_sch")
		(attr exclude_from_pos_files exclude_from_bom)
		(fp_circle
			(center 0 0)
			(end 0.475 0)
			(stroke
				(width 0.05)
				(type default)
			)
			(fill none)
			(layer "B.CrtYd")
		)
		(fp_text user "License: Apache-2.0"
			(at -0.4 -5.101 0)
			(layer "B.Fab")
			(hide yes)
			(effects
				(font
					(size 0.7 0.7)
					(thickness 0.15)
				)
				(justify right bottom mirror)
			)
		)
		(fp_text user "${REFERENCE}"
			(at -0.4 -2.7 0)
			(layer "B.Fab")
			(hide yes)
			(effects
				(font
					(size 0.7 0.7)
					(thickness 0.15)
				)
				(justify right bottom mirror)
			)
		)
		(fp_text user "Author: Antmicro"
			(at -0.4 -3.901 0)
			(layer "B.Fab")
			(hide yes)
			(effects
				(font
					(size 0.7 0.7)
					(thickness 0.15)
				)
				(justify right bottom mirror)
			)
		)
		(pad "1" smd circle
			(at 0 0)
			(size 0.75 0.75)
			(layers "B.Cu" "B.Mask")
			(net 244 "/M.2/M2_M_SMB_CLK")
			(pinfunction "1")
			(pintype "passive")
		)
	)
	(footprint "antmicro-footprints:C_0402_1005Metric"
		(layer "B.Cu")
		(at 97.45 93.45)
		(descr "Capacitor SMD 0402")
		(tags "capacitor SMD 0402")
		(property "Reference" "C88"
			(at 3.26 0.32 180)
			(layer "B.SilkS")
			(effects
				(font
					(size 0.7 0.7)
					(thickness 0.15)
				)
				(justify left bottom mirror)
			)
		)
		(property "Value" "C_100n_0402"
			(at 0 -1.4 180)
			(layer "B.Fab")
			(effects
				(font
					(size 0.7 0.7)
					(thickness 0.15)
				)
				(justify left bottom mirror)
			)
		)
		(property "Footprint" "antmicro-footprints:C_0402_1005Metric"
			(at 0 0 0)
			(layer "F.Fab")
			(hide yes)
			(effects
				(font
					(size 1.27 1.27)
					(thickness 0.15)
				)
			)
		)
		(property "Datasheet" "https://www.murata.com/products/productdetail?partno=GRM155R61H104KE14%23"
			(at 0 0 0)
			(layer "F.Fab")
			(hide yes)
			(effects
				(font
					(size 1.27 1.27)
					(thickness 0.15)
				)
			)
		)
		(property "Author" "Antmicro"
			(at 0 0 0)
			(layer "B.Fab")
			(hide yes)
			(effects
				(font
					(size 1 1)
					(thickness 0.15)
				)
				(justify mirror)
			)
		)
		(property "Dielectric" "X5R"
			(at 0 0 0)
			(layer "B.Fab")
			(hide yes)
			(effects
				(font
					(size 1 1)
					(thickness 0.15)
				)
				(justify mirror)
			)
		)
		(property "License" "Apache-2.0"
			(at 0 0 0)
			(layer "B.Fab")
			(hide yes)
			(effects
				(font
					(size 1 1)
					(thickness 0.15)
				)
				(justify mirror)
			)
		)
		(property "MPN" "GRM155R61H104KE14D"
			(at 0 0 0)
			(layer "B.Fab")
			(hide yes)
			(effects
				(font
					(size 1 1)
					(thickness 0.15)
				)
				(justify mirror)
			)
		)
		(property "Manufacturer" "Murata"
			(at 0 0 0)
			(layer "B.Fab")
			(hide yes)
			(effects
				(font
					(size 1 1)
					(thickness 0.15)
				)
				(justify mirror)
			)
		)
		(property "Val" "100n"
			(at 0 0 0)
			(layer "B.Fab")
			(hide yes)
			(effects
				(font
					(size 1 1)
					(thickness 0.15)
				)
				(justify mirror)
			)
		)
		(property "Voltage" "50V"
			(at 0 0 0)
			(layer "B.Fab")
			(hide yes)
			(effects
				(font
					(size 1 1)
					(thickness 0.15)
				)
				(justify mirror)
			)
		)
		(sheetname "HDMI")
		(sheetfile "hdmi.kicad_sch")
		(attr smd)
		(fp_rect
			(start -0.925 0.47)
			(end 0.925 -0.47)
			(stroke
				(width 0.05)
				(type default)
			)
			(fill none)
			(layer "B.CrtYd")
		)
		(fp_line
			(start -0.494 -0.248)
			(end 0.504 -0.248)
			(stroke
				(width 0.15)
				(type solid)
			)
			(layer "B.Fab")
		)
		(fp_line
			(start -0.494 0.25)
			(end -0.494 -0.248)
			(stroke
				(width 0.15)
				(type solid)
			)
			(layer "B.Fab")
		)
		(fp_line
			(start 0.504 -0.248)
			(end 0.504 0.25)
			(stroke
				(width 0.15)
				(type solid)
			)
			(layer "B.Fab")
		)
		(fp_line
			(start 0.504 0.25)
			(end -0.494 0.25)
			(stroke
				(width 0.15)
				(type solid)
			)
			(layer "B.Fab")
		)
		(fp_text user "${REFERENCE}"
			(at -0.932 -3.168 180)
			(layer "B.Fab")
			(hide yes)
			(effects
				(font
					(size 0.7 0.7)
					(thickness 0.15)
				)
				(justify left bottom mirror)
			)
		)
		(fp_text user "License: Apache-2.0"
			(at -0.932 -5.17 180)
			(layer "B.Fab")
			(hide yes)
			(effects
				(font
					(size 0.7 0.7)
					(thickness 0.15)
				)
				(justify left bottom mirror)
			)
		)
		(fp_text user "Author: Antmicro"
			(at -0.932 -4.17 180)
			(layer "B.Fab")
			(hide yes)
			(effects
				(font
					(size 0.7 0.7)
					(thickness 0.15)
				)
				(justify left bottom mirror)
			)
		)
		(pad "1" smd roundrect
			(at -0.48 0)
			(size 0.59 0.64)
			(layers "B.Cu" "B.Paste" "B.Mask")
			(roundrect_rratio 0.25)
			(net 664 "/HDMI/DP_MUX_D2-")
			(pintype "passive")
		)
		(pad "2" smd roundrect
			(at 0.48 0)
			(size 0.59 0.64)
			(layers "B.Cu" "B.Paste" "B.Mask")
			(roundrect_rratio 0.25)
			(net 375 "DP1_TXD1_HDMI_TX1_N")
			(pintype "passive")
		)
	)
	(footprint "antmicro-footprints:R_0402_1005Metric"
		(layer "B.Cu")
		(at 68.1 83.3 180)
		(descr "Resistor SMD 0402")
		(tags "resistor SMD 0402")
		(property "Reference" "R80"
			(at -1.06 -1.3 0)
			(layer "B.SilkS")
			(effects
				(font
					(size 0.7 0.7)
					(thickness 0.15)
				)
				(justify left bottom mirror)
			)
		)
		(property "Value" "R_4k7_0402"
			(at 0 -1.4 0)
			(layer "B.Fab")
			(effects
				(font
					(size 0.7 0.7)
					(thickness 0.15)
				)
				(justify left bottom mirror)
			)
		)
		(property "Footprint" "antmicro-footprints:R_0402_1005Metric"
			(at 0 0 180)
			(layer "F.Fab")
			(hide yes)
			(effects
				(font
					(size 1.27 1.27)
					(thickness 0.15)
				)
			)
		)
		(property "Datasheet" "https://www.bourns.com/docs/product-datasheets/cr.pdf"
			(at 0 0 180)
			(layer "F.Fab")
			(hide yes)
			(effects
				(font
					(size 1.27 1.27)
					(thickness 0.15)
				)
			)
		)
		(property "Author" "Antmicro"
			(at 136.2 166.6 0)
			(layer "B.Fab")
			(hide yes)
			(effects
				(font
					(size 1 1)
					(thickness 0.15)
				)
				(justify mirror)
			)
		)
		(property "License" "Apache-2.0"
			(at 136.2 166.6 0)
			(layer "B.Fab")
			(hide yes)
			(effects
				(font
					(size 1 1)
					(thickness 0.15)
				)
				(justify mirror)
			)
		)
		(property "MPN" "CR0402-FX-4701GLF"
			(at 136.2 166.6 0)
			(layer "B.Fab")
			(hide yes)
			(effects
				(font
					(size 1 1)
					(thickness 0.15)
				)
				(justify mirror)
			)
		)
		(property "Manufacturer" "Bourns"
			(at 136.2 166.6 0)
			(layer "B.Fab")
			(hide yes)
			(effects
				(font
					(size 1 1)
					(thickness 0.15)
				)
				(justify mirror)
			)
		)
		(property "Tolerance" "1%"
			(at 136.2 166.6 0)
			(layer "B.Fab")
			(hide yes)
			(effects
				(font
					(size 1 1)
					(thickness 0.15)
				)
				(justify mirror)
			)
		)
		(property "Val" "4k7"
			(at 136.2 166.6 0)
			(layer "B.Fab")
			(hide yes)
			(effects
				(font
					(size 1 1)
					(thickness 0.15)
				)
				(justify mirror)
			)
		)
		(sheetname "SoM")
		(sheetfile "som.kicad_sch")
		(attr smd)
		(fp_rect
			(start -0.925 0.47)
			(end 0.925 -0.47)
			(stroke
				(width 0.05)
				(type default)
			)
			(fill none)
			(layer "B.CrtYd")
		)
		(fp_rect
			(start -0.5 0.25)
			(end 0.5 -0.25)
			(stroke
				(width 0.15)
				(type solid)
			)
			(fill none)
			(layer "B.Fab")
		)
		(fp_text user "Author: Antmicro"
			(at -0.95 -4.169 0)
			(layer "B.Fab")
			(hide yes)
			(effects
				(font
					(size 0.7 0.7)
					(thickness 0.15)
				)
				(justify left bottom mirror)
			)
		)
		(fp_text user "${REFERENCE}"
			(at -0.95 -3.168 0)
			(layer "B.Fab")
			(hide yes)
			(effects
				(font
					(size 0.7 0.7)
					(thickness 0.15)
				)
				(justify left bottom mirror)
			)
		)
		(fp_text user "License: Apache-2.0"
			(at -0.95 -5.169 0)
			(layer "B.Fab")
			(hide yes)
			(effects
				(font
					(size 0.7 0.7)
					(thickness 0.15)
				)
				(justify left bottom mirror)
			)
		)
		(pad "1" smd roundrect
			(at -0.48 0 180)
			(size 0.59 0.64)
			(layers "B.Cu" "B.Paste" "B.Mask")
			(roundrect_rratio 0.25)
			(net 714 "GPIO010")
			(pintype "passive")
		)
		(pad "2" smd roundrect
			(at 0.48 0 180)
			(size 0.59 0.64)
			(layers "B.Cu" "B.Paste" "B.Mask")
			(roundrect_rratio 0.25)
			(net 112 "+1V8")
			(pintype "passive")
		)
	)
	(footprint "antmicro-footprints:TP_SMD_0.75mm"
		(layer "B.Cu")
		(at 68.165 121.57 180)
		(property "Reference" "TP53"
			(at 1.49 -1.53 0)
			(layer "B.SilkS")
			(hide yes)
			(effects
				(font
					(size 0.7 0.7)
					(thickness 0.15)
				)
				(justify left bottom mirror)
			)
		)
		(property "Value" "TP_0.75mm_SMD"
			(at 0 -1.2 0)
			(layer "B.Fab")
			(effects
				(font
					(size 0.7 0.7)
					(thickness 0.15)
				)
				(justify left bottom mirror)
			)
		)
		(property "Footprint" "antmicro-footprints:TP_SMD_0.75mm"
			(at 0 0 180)
			(layer "F.Fab")
			(hide yes)
			(effects
				(font
					(size 1.27 1.27)
					(thickness 0.15)
				)
			)
		)
		(property "Author" "Antmicro"
			(at 136.33 243.14 0)
			(layer "B.Fab")
			(hide yes)
			(effects
				(font
					(size 1 1)
					(thickness 0.15)
				)
				(justify mirror)
			)
		)
		(property "License" "Apache-2.0"
			(at 136.33 243.14 0)
			(layer "B.Fab")
			(hide yes)
			(effects
				(font
					(size 1 1)
					(thickness 0.15)
				)
				(justify mirror)
			)
		)
		(property "MPN" ""
			(at 136.33 243.14 0)
			(layer "B.Fab")
			(hide yes)
			(effects
				(font
					(size 1 1)
					(thickness 0.15)
				)
				(justify mirror)
			)
		)
		(property "Manufacturer" ""
			(at 136.33 243.14 0)
			(layer "B.Fab")
			(hide yes)
			(effects
				(font
					(size 1 1)
					(thickness 0.15)
				)
				(justify mirror)
			)
		)
		(sheetname "Supply")
		(sheetfile "supply.kicad_sch")
		(attr exclude_from_pos_files exclude_from_bom)
		(fp_circle
			(center 0 0)
			(end 0.475 0)
			(stroke
				(width 0.05)
				(type default)
			)
			(fill none)
			(layer "B.CrtYd")
		)
		(fp_text user "${REFERENCE}"
			(at -0.4 -2.7 0)
			(layer "B.Fab")
			(hide yes)
			(effects
				(font
					(size 0.7 0.7)
					(thickness 0.15)
				)
				(justify left bottom mirror)
			)
		)
		(fp_text user "Author: Antmicro"
			(at -0.4 -3.901 0)
			(layer "B.Fab")
			(hide yes)
			(effects
				(font
					(size 0.7 0.7)
					(thickness 0.15)
				)
				(justify left bottom mirror)
			)
		)
		(fp_text user "License: Apache-2.0"
			(at -0.4 -5.101 0)
			(layer "B.Fab")
			(hide yes)
			(effects
				(font
					(size 0.7 0.7)
					(thickness 0.15)
				)
				(justify left bottom mirror)
			)
		)
		(pad "1" smd circle
			(at 0 0 180)
			(size 0.75 0.75)
			(layers "B.Cu" "B.Mask")
			(net 99 "+5V")
			(pinfunction "1")
			(pintype "passive")
		)
	)
	(footprint "antmicro-footprints:Tag-Connect_TC2050-IDC-NL_2x5_P1.27mm"
		(layer "B.Cu")
		(at 83.909 125.2545 180)
		(property "Reference" "J9"
			(at 1.909 2.2245 0)
			(layer "B.SilkS")
			(effects
				(font
					(size 0.7 0.7)
					(thickness 0.15)
				)
				(justify left bottom mirror)
			)
		)
		(property "Value" "Tag-Connect_TC2050-IDC-NL_2x5_P1.27mm"
			(at 0 -4.4 0)
			(layer "B.Fab")
			(effects
				(font
					(size 0.7 0.7)
					(thickness 0.15)
				)
				(justify left bottom mirror)
			)
		)
		(property "Footprint" "antmicro-footprints:Tag-Connect_TC2050-IDC-NL_2x5_P1.27mm"
			(at 0 0 180)
			(layer "F.Fab")
			(hide yes)
			(effects
				(font
					(size 1.27 1.27)
					(thickness 0.15)
				)
			)
		)
		(property "Datasheet" "https://www.tag-connect.com/wp-content/uploads/bsk-pdf-manager/TC2050-IDC-NL_Datasheet_8.pdf"
			(at 0 0 180)
			(layer "F.Fab")
			(hide yes)
			(effects
				(font
					(size 1.27 1.27)
					(thickness 0.15)
				)
			)
		)
		(property "Author" "Antmicro"
			(at 167.818 250.509 0)
			(layer "B.Fab")
			(hide yes)
			(effects
				(font
					(size 1 1)
					(thickness 0.15)
				)
				(justify mirror)
			)
		)
		(property "License" "Apache-2.0"
			(at 167.818 250.509 0)
			(layer "B.Fab")
			(hide yes)
			(effects
				(font
					(size 1 1)
					(thickness 0.15)
				)
				(justify mirror)
			)
		)
		(property "MPN" "TC2050-IDC-NL"
			(at 167.818 250.509 0)
			(layer "B.Fab")
			(hide yes)
			(effects
				(font
					(size 1 1)
					(thickness 0.15)
				)
				(justify mirror)
			)
		)
		(property "Manufacturer" "Tag Connect"
			(at 167.818 250.509 0)
			(layer "B.Fab")
			(hide yes)
			(effects
				(font
					(size 1 1)
					(thickness 0.15)
				)
				(justify mirror)
			)
		)
		(sheetname "Peripherals")
		(sheetfile "peripherals.kicad_sch")
		(attr exclude_from_pos_files exclude_from_bom dnp)
		(fp_line
			(start 5.1 1.7)
			(end 4.7 2.05)
			(stroke
				(width 0.15)
				(type solid)
			)
			(layer "B.SilkS")
		)
		(fp_line
			(start 5.1 -1.7)
			(end 5.1 1.7)
			(stroke
				(width 0.15)
				(type solid)
			)
			(layer "B.SilkS")
		)
		(fp_line
			(start 5.1 -1.7)
			(end 4.7 -2.049)
			(stroke
				(width 0.15)
				(type solid)
			)
			(layer "B.SilkS")
		)
		(fp_line
			(start 4.7 2.05)
			(end -2.2 2.05)
			(stroke
				(width 0.15)
				(type solid)
			)
			(layer "B.SilkS")
		)
		(fp_line
			(start -2.2 2.05)
			(end -5.08 0.9)
			(stroke
				(width 0.15)
				(type solid)
			)
			(layer "B.SilkS")
		)
		(fp_line
			(start -2.3 -2.049)
			(end 4.7 -2.049)
			(stroke
				(width 0.15)
				(type solid)
			)
			(layer "B.SilkS")
		)
		(fp_line
			(start -3.101 -0.4)
			(end -3.101 -1.269)
			(stroke
				(width 0.15)
				(type solid)
			)
			(layer "B.SilkS")
		)
		(fp_line
			(start -5.08 0.9)
			(end -5.08 -0.8)
			(stroke
				(width 0.15)
				(type solid)
			)
			(layer "B.SilkS")
		)
		(fp_line
			(start -5.08 -0.8)
			(end -2.3 -2.049)
			(stroke
				(width 0.15)
				(type solid)
			)
			(layer "B.SilkS")
		)
		(fp_line
			(start 5.32 1.8)
			(end 4.8 2.3)
			(stroke
				(width 0.05)
				(type solid)
			)
			(layer "B.CrtYd")
		)
		(fp_line
			(start 5.32 -1.8)
			(end 5.32 1.8)
			(stroke
				(width 0.05)
				(type solid)
			)
			(layer "B.CrtYd")
		)
		(fp_line
			(start 5.32 -1.8)
			(end 4.8 -2.29)
			(stroke
				(width 0.05)
				(type solid)
			)
			(layer "B.CrtYd")
		)
		(fp_line
			(start 4.8 2.3)
			(end -2.3 2.3)
			(stroke
				(width 0.05)
				(type solid)
			)
			(layer "B.CrtYd")
		)
		(fp_line
			(start -2.3 2.3)
			(end -5.33 1.1)
			(stroke
				(width 0.05)
				(type solid)
			)
			(layer "B.CrtYd")
		)
		(fp_line
			(start -2.4 -2.29)
			(end 4.8 -2.29)
			(stroke
				(width 0.05)
				(type solid)
			)
			(layer "B.CrtYd")
		)
		(fp_line
			(start -5.33 1.1)
			(end -5.33 -1)
			(stroke
				(width 0.05)
				(type solid)
			)
			(layer "B.CrtYd")
		)
		(fp_line
			(start -5.33 -1)
			(end -2.4 -2.29)
			(stroke
				(width 0.05)
				(type solid)
			)
			(layer "B.CrtYd")
		)
		(fp_text user "License: Apache-2.0"
			(at -6.223 -8.449 0)
			(layer "B.Fab")
			(hide yes)
			(effects
				(font
					(size 0.7 0.7)
					(thickness 0.15)
				)
				(justify left bottom mirror)
			)
		)
		(fp_text user "${REFERENCE}"
			(at -6.223 -6.049 0)
			(layer "B.Fab")
			(hide yes)
			(effects
				(font
					(size 0.7 0.7)
					(thickness 0.15)
				)
				(justify left bottom mirror)
			)
		)
		(fp_text user "Author: Antmicro"
			(at -6.223 -7.249 0)
			(layer "B.Fab")
			(hide yes)
			(effects
				(font
					(size 0.7 0.7)
					(thickness 0.15)
				)
				(justify left bottom mirror)
			)
		)
		(pad "" np_thru_hole circle
			(at -3.81 0 180)
			(size 0.9906 0.9906)
			(drill 0.9906)
			(layers "*.Cu" "*.Mask")
		)
		(pad "" np_thru_hole circle
			(at 3.809 -1.015 180)
			(size 0.9906 0.9906)
			(drill 0.9906)
			(layers "*.Cu" "*.Mask")
		)
		(pad "" np_thru_hole circle
			(at 3.809 1.016 180)
			(size 0.9906 0.9906)
			(drill 0.9906)
			(layers "*.Cu" "*.Mask")
		)
		(pad "1" connect circle
			(at -2.54 -0.634 180)
			(size 0.7874 0.7874)
			(layers "B.Cu" "B.Mask")
			(net 98 "EEPROM_PWR")
			(pinfunction "3V3")
			(pintype "passive")
		)
		(pad "2" connect circle
			(at -1.27 -0.634 180)
			(size 0.7874 0.7874)
			(layers "B.Cu" "B.Mask")
			(net 772 "/Peripherals/~{CS}")
			(pinfunction "SPI_CS")
			(pintype "passive")
		)
		(pad "3" connect circle
			(at 0 -0.634 180)
			(size 0.7874 0.7874)
			(layers "B.Cu" "B.Mask")
			(net 1 "GND")
			(pinfunction "GND")
			(pintype "passive")
		)
		(pad "4" connect circle
			(at 1.269 -0.634 180)
			(size 0.7874 0.7874)
			(layers "B.Cu" "B.Mask")
			(net 671 "/Peripherals/SCK")
			(pinfunction "SPI_SCK")
			(pintype "passive")
		)
		(pad "5" connect circle
			(at 2.539 -0.634 180)
			(size 0.7874 0.7874)
			(layers "B.Cu" "B.Mask")
			(net 1 "GND")
			(pinfunction "GND")
			(pintype "passive")
		)
		(pad "6" connect circle
			(at 2.539 0.635 180)
			(size 0.7874 0.7874)
			(layers "B.Cu" "B.Mask")
			(net 773 "/Peripherals/MISO")
			(pinfunction "SPI_MISO")
			(pintype "passive")
		)
		(pad "7" connect circle
			(at 1.269 0.635 180)
			(size 0.7874 0.7874)
			(layers "B.Cu" "B.Mask")
			(net 775 "unconnected-(J9-Pad7)")
			(pinfunction "NC")
			(pintype "passive+no_connect")
		)
		(pad "8" connect circle
			(at 0 0.635 180)
			(size 0.7874 0.7874)
			(layers "B.Cu" "B.Mask")
			(net 774 "/Peripherals/MOSI")
			(pinfunction "SPI_MOSI")
			(pintype "passive")
		)
		(pad "9" connect circle
			(at -1.27 0.635 180)
			(size 0.7874 0.7874)
			(layers "B.Cu" "B.Mask")
			(net 1 "GND")
			(pinfunction "GND")
			(pintype "passive")
		)
		(pad "10" connect circle
			(at -2.54 0.635 180)
			(size 0.7874 0.7874)
			(layers "B.Cu" "B.Mask")
			(net 776 "unconnected-(J9-Pad10)")
			(pinfunction "SPI_NC")
			(pintype "passive+no_connect")
		)
	)
	(footprint "antmicro-footprints:SOD-923"
		(layer "B.Cu")
		(at 69.8 81 -90)
		(property "Reference" "D30"
			(at -0.83 0.56 90)
			(unlocked yes)
			(layer "B.SilkS")
			(effects
				(font
					(size 0.7 0.7)
					(thickness 0.15)
				)
				(justify left bottom mirror)
			)
		)
		(property "Value" "ESD9X5.0ST5G"
			(at 0 -1.3 90)
			(unlocked yes)
			(layer "B.Fab")
			(effects
				(font
					(size 0.7 0.7)
					(thickness 0.15)
				)
				(justify left bottom mirror)
			)
		)
		(property "Footprint" "antmicro-footprints:SOD-923"
			(at 0 0 -90)
			(layer "F.Fab")
			(hide yes)
			(effects
				(font
					(size 1.27 1.27)
					(thickness 0.15)
				)
			)
		)
		(property "Datasheet" "https://www.onsemi.com/pdf/datasheet/esd9x3.3st5g-d.pdf"
			(at 0 0 -90)
			(layer "F.Fab")
			(hide yes)
			(effects
				(font
					(size 1.27 1.27)
					(thickness 0.15)
				)
			)
		)
		(property "Author" "Antmicro"
			(at -11.2 150.8 0)
			(layer "B.Fab")
			(hide yes)
			(effects
				(font
					(size 1 1)
					(thickness 0.15)
				)
				(justify mirror)
			)
		)
		(property "License" "Apache-2.0"
			(at -11.2 150.8 0)
			(layer "B.Fab")
			(hide yes)
			(effects
				(font
					(size 1 1)
					(thickness 0.15)
				)
				(justify mirror)
			)
		)
		(property "MPN" "ESD9X5.0ST5G"
			(at -11.2 150.8 0)
			(layer "B.Fab")
			(hide yes)
			(effects
				(font
					(size 1 1)
					(thickness 0.15)
				)
				(justify mirror)
			)
		)
		(property "Manufacturer" "ON Semiconductor"
			(at -11.2 150.8 0)
			(layer "B.Fab")
			(hide yes)
			(effects
				(font
					(size 1 1)
					(thickness 0.15)
				)
				(justify mirror)
			)
		)
		(sheetname "Supply")
		(sheetfile "supply.kicad_sch")
		(attr smd)
		(fp_line
			(start -0.5 0.4)
			(end -0.5 0.3)
			(stroke
				(width 0.15)
				(type solid)
			)
			(layer "B.SilkS")
		)
		(fp_line
			(start 0.5 0.4)
			(end -0.5 0.4)
			(stroke
				(width 0.15)
				(type solid)
			)
			(layer "B.SilkS")
		)
		(fp_line
			(start 0.5 0.3)
			(end 0.5 0.4)
			(stroke
				(width 0.15)
				(type solid)
			)
			(layer "B.SilkS")
		)
		(fp_line
			(start -0.5 -0.3)
			(end -0.5 -0.4)
			(stroke
				(width 0.15)
				(type solid)
			)
			(layer "B.SilkS")
		)
		(fp_line
			(start 0.5 -0.3)
			(end 0.5 -0.4)
			(stroke
				(width 0.15)
				(type solid)
			)
			(layer "B.SilkS")
		)
		(fp_line
			(start -0.16 -0.4)
			(end -0.16 0.4)
			(stroke
				(width 0.15)
				(type solid)
			)
			(layer "B.SilkS")
		)
		(fp_line
			(start 0.5 -0.4)
			(end -0.5 -0.4)
			(stroke
				(width 0.15)
				(type solid)
			)
			(layer "B.SilkS")
		)
		(fp_rect
			(start -0.68 0.41)
			(end 0.68 -0.41)
			(stroke
				(width 0.05)
				(type solid)
			)
			(fill none)
			(layer "B.CrtYd")
		)
		(fp_line
			(start -0.202 -0.298)
			(end -0.202 0.3)
			(stroke
				(width 0.15)
				(type solid)
			)
			(layer "B.Fab")
		)
		(fp_rect
			(start -0.402 0.3)
			(end 0.4 -0.298)
			(stroke
				(width 0.15)
				(type solid)
			)
			(fill none)
			(layer "B.Fab")
		)
		(fp_text user "${REFERENCE}"
			(at -0.68 -3.3 90)
			(unlocked yes)
			(layer "B.Fab")
			(hide yes)
			(effects
				(font
					(size 0.7 0.7)
					(thickness 0.15)
				)
				(justify left bottom mirror)
			)
		)
		(fp_text user "License: Apache-2.0"
			(at -0.68 -4.5 90)
			(layer "B.Fab")
			(hide yes)
			(effects
				(font
					(size 0.7 0.7)
					(thickness 0.15)
				)
				(justify left bottom mirror)
			)
		)
		(fp_text user "Author: Antmicro"
			(at -0.68 -5.7 90)
			(layer "B.Fab")
			(hide yes)
			(effects
				(font
					(size 0.7 0.7)
					(thickness 0.15)
				)
				(justify left bottom mirror)
			)
		)
		(pad "1" smd roundrect
			(at -0.438 0 270)
			(size 0.4 0.325)
			(layers "B.Cu" "B.Paste" "B.Mask")
			(roundrect_rratio 0.25)
			(net 117 "3V3_STDB")
			(pinfunction "C")
			(pintype "passive")
		)
		(pad "2" smd roundrect
			(at 0.436 0 270)
			(size 0.4 0.325)
			(layers "B.Cu" "B.Paste" "B.Mask")
			(roundrect_rratio 0.25)
			(net 1 "GND")
			(pinfunction "A")
			(pintype "passive")
		)
	)
	(footprint "antmicro-footprints:R_0402_1005Metric"
		(layer "B.Cu")
		(at 63.84 98.6)
		(descr "Resistor SMD 0402")
		(tags "resistor SMD 0402")
		(property "Reference" "R65"
			(at 3.95 -1.72 180)
			(layer "B.SilkS")
			(effects
				(font
					(size 0.7 0.7)
					(thickness 0.15)
				)
				(justify left bottom mirror)
			)
		)
		(property "Value" "R_0R_0402"
			(at 0 -1.4 180)
			(layer "B.Fab")
			(effects
				(font
					(size 0.7 0.7)
					(thickness 0.15)
				)
				(justify left bottom mirror)
			)
		)
		(property "Footprint" "antmicro-footprints:R_0402_1005Metric"
			(at 0 0 0)
			(layer "F.Fab")
			(hide yes)
			(effects
				(font
					(size 1.27 1.27)
					(thickness 0.15)
				)
			)
		)
		(property "Datasheet" "https://industrial.panasonic.com/cdbs/www-data/pdf/RDA0000/AOA0000C301.pdf"
			(at 0 0 0)
			(layer "F.Fab")
			(hide yes)
			(effects
				(font
					(size 1.27 1.27)
					(thickness 0.15)
				)
			)
		)
		(property "Author" "Antmicro"
			(at 0 0 0)
			(layer "B.Fab")
			(hide yes)
			(effects
				(font
					(size 1 1)
					(thickness 0.15)
				)
				(justify mirror)
			)
		)
		(property "Current" "1A"
			(at 0 0 0)
			(layer "B.Fab")
			(hide yes)
			(effects
				(font
					(size 1 1)
					(thickness 0.15)
				)
				(justify mirror)
			)
		)
		(property "License" "Apache-2.0"
			(at 0 0 0)
			(layer "B.Fab")
			(hide yes)
			(effects
				(font
					(size 1 1)
					(thickness 0.15)
				)
				(justify mirror)
			)
		)
		(property "MPN" "ERJ2GE0R00X"
			(at 0 0 0)
			(layer "B.Fab")
			(hide yes)
			(effects
				(font
					(size 1 1)
					(thickness 0.15)
				)
				(justify mirror)
			)
		)
		(property "Manufacturer" "Panasonic"
			(at 0 0 0)
			(layer "B.Fab")
			(hide yes)
			(effects
				(font
					(size 1 1)
					(thickness 0.15)
				)
				(justify mirror)
			)
		)
		(property "Tolerance" ""
			(at 0 0 0)
			(layer "B.Fab")
			(hide yes)
			(effects
				(font
					(size 1 1)
					(thickness 0.15)
				)
				(justify mirror)
			)
		)
		(property "Val" "0R"
			(at 0 0 0)
			(layer "B.Fab")
			(hide yes)
			(effects
				(font
					(size 1 1)
					(thickness 0.15)
				)
				(justify mirror)
			)
		)
		(sheetname "USB Debug, DP")
		(sheetfile "usb.kicad_sch")
		(attr smd)
		(fp_rect
			(start -0.925 0.47)
			(end 0.925 -0.47)
			(stroke
				(width 0.05)
				(type default)
			)
			(fill none)
			(layer "B.CrtYd")
		)
		(fp_rect
			(start -0.5 0.25)
			(end 0.5 -0.25)
			(stroke
				(width 0.15)
				(type solid)
			)
			(fill none)
			(layer "B.Fab")
		)
		(fp_text user "${REFERENCE}"
			(at -0.95 -3.168 180)
			(layer "B.Fab")
			(hide yes)
			(effects
				(font
					(size 0.7 0.7)
					(thickness 0.15)
				)
				(justify left bottom mirror)
			)
		)
		(fp_text user "License: Apache-2.0"
			(at -0.95 -5.169 180)
			(layer "B.Fab")
			(hide yes)
			(effects
				(font
					(size 0.7 0.7)
					(thickness 0.15)
				)
				(justify left bottom mirror)
			)
		)
		(fp_text user "Author: Antmicro"
			(at -0.95 -4.169 180)
			(layer "B.Fab")
			(hide yes)
			(effects
				(font
					(size 0.7 0.7)
					(thickness 0.15)
				)
				(justify left bottom mirror)
			)
		)
		(pad "1" smd roundrect
			(at -0.48 0)
			(size 0.59 0.64)
			(layers "B.Cu" "B.Paste" "B.Mask")
			(roundrect_rratio 0.25)
			(net 677 "USBC_HPD")
			(pintype "passive")
		)
		(pad "2" smd roundrect
			(at 0.48 0)
			(size 0.59 0.64)
			(layers "B.Cu" "B.Paste" "B.Mask")
			(roundrect_rratio 0.25)
			(net 670 "/USB Debug, DP/PDC_HPD2")
			(pintype "passive")
		)
	)
	(footprint "antmicro-footprints:Spacer_Drill3.7mm_H6.5mm_9774065151R"
		(locked yes)
		(layer "B.Cu")
		(at 144.75 72.25 180)
		(descr "Spacer M=3 h=6.5mm fi=5.1mm")
		(property "Reference" "H5"
			(at 2.25 -3.05 0)
			(layer "B.SilkS")
			(effects
				(font
					(size 0.7 0.7)
					(thickness 0.15)
				)
				(justify left bottom mirror)
			)
		)
		(property "Value" "Spacer_Drill3.7mm_H6.5mm_9774065151R"
			(at 0 -4 0)
			(layer "B.Fab")
			(effects
				(font
					(size 0.7 0.7)
					(thickness 0.15)
				)
				(justify left bottom mirror)
			)
		)
		(property "Footprint" "antmicro-footprints:Spacer_Drill3.7mm_H6.5mm_9774065151R"
			(at 0 0 180)
			(layer "F.Fab")
			(hide yes)
			(effects
				(font
					(size 1.27 1.27)
					(thickness 0.15)
				)
			)
		)
		(property "Datasheet" "https://www.we-online.com/components/products/datasheet/9774065151R.pdf"
			(at 0 0 180)
			(layer "F.Fab")
			(hide yes)
			(effects
				(font
					(size 1.27 1.27)
					(thickness 0.15)
				)
			)
		)
		(property "Author" "Antmicro"
			(at 289.5 144.5 0)
			(layer "B.Fab")
			(hide yes)
			(effects
				(font
					(size 1 1)
					(thickness 0.15)
				)
				(justify mirror)
			)
		)
		(property "License" "Apache-2.0"
			(at 289.5 144.5 0)
			(layer "B.Fab")
			(hide yes)
			(effects
				(font
					(size 1 1)
					(thickness 0.15)
				)
				(justify mirror)
			)
		)
		(property "MPN" "9774065151R"
			(at 289.5 144.5 0)
			(layer "B.Fab")
			(hide yes)
			(effects
				(font
					(size 1 1)
					(thickness 0.15)
				)
				(justify mirror)
			)
		)
		(property "Manufacturer" "Würth Elektronik"
			(at 289.5 144.5 0)
			(layer "B.Fab")
			(hide yes)
			(effects
				(font
					(size 1 1)
					(thickness 0.15)
				)
				(justify mirror)
			)
		)
		(sheetname "Root")
		(sheetfile "jetson-orin-baseboard.kicad_sch")
		(solder_paste_ratio -1)
		(attr smd)
		(fp_circle
			(center 0 0)
			(end 3.05 0)
			(stroke
				(width 0.05)
				(type solid)
			)
			(fill none)
			(layer "B.CrtYd")
		)
		(fp_circle
			(center 0 0)
			(end 2.6 0)
			(stroke
				(width 0.15)
				(type solid)
			)
			(fill none)
			(layer "B.Fab")
		)
		(fp_text user "${REFERENCE}"
			(at -9.6 -6.5 0)
			(layer "B.Fab")
			(hide yes)
			(effects
				(font
					(size 0.7 0.7)
					(thickness 0.15)
				)
				(justify left bottom mirror)
			)
		)
		(fp_text user "Author: Antmicro"
			(at -9.6 -7.7 0)
			(layer "B.Fab")
			(hide yes)
			(effects
				(font
					(size 0.7 0.7)
					(thickness 0.15)
				)
				(justify left bottom mirror)
			)
		)
		(fp_text user "License: Apache-2.0"
			(at -9.6 -8.9 0)
			(layer "B.Fab")
			(hide yes)
			(effects
				(font
					(size 0.7 0.7)
					(thickness 0.15)
				)
				(justify left bottom mirror)
			)
		)
		(pad "" smd custom
			(at -1.7 -1.7 90)
			(size 0.62 0.62)
			(layers "B.Paste")
			(thermal_bridge_angle 90)
			(options
				(clearance outline)
				(anchor circle)
			)
			(primitives
				(gr_arc
					(start 1.266786 0.24747)
					(mid 0.285453 -0.29439)
					(end -0.250195 -1.279127)
					(width 0.2)
				)
				(gr_arc
					(start 1.259603 0.339191)
					(mid 0.218448 -0.232561)
					(end -0.34334 -1.279127)
					(width 0.2)
				)
				(gr_arc
					(start 1.255279 0.431435)
					(mid 0.152481 -0.169693)
					(end -0.436309 -1.279127)
					(width 0.2)
				)
				(gr_arc
					(start 1.253811 0.524161)
					(mid 0.087542 -0.105784)
					(end -0.529126 -1.279127)
					(width 0.2)
				)
				(gr_arc
					(start 1.275473 0.621136)
					(mid 0.0309 -0.033527)
					(end -0.621807 -1.279127)
					(width 0.2)
				)
				(gr_arc
					(start 1.263664 0.711602)
					(mid -0.037759 0.026651)
					(end -0.71437 -1.279127)
					(width 0.2)
				)
				(gr_arc
					(start 1.253435 0.802342)
					(mid -0.105837 0.087395)
					(end -0.806826 -1.279127)
					(width 0.2)
				)
				(gr_arc
					(start 1.267475 0.897258)
					(mid -0.165236 0.156885)
					(end -0.899187 -1.279127)
					(width 0.2)
				)
				(gr_arc
					(start 1.270645 0.990112)
					(mid -0.228522 0.222449)
					(end -0.991463 -1.279127)
					(width 0.2)
				)
				(gr_arc
					(start 1.266278 1.081674)
					(mid -0.294507 0.285313)
					(end -1.083663 -1.279127)
					(width 0.2)
				)
				(gr_line
					(start 1.279127 1.083663)
					(end 1.279127 0.250195)
					(width 0.2)
				)
				(gr_line
					(start -1.083663 -1.279127)
					(end -0.250195 -1.279127)
					(width 0.2)
				)
			)
		)
		(pad "" smd custom
			(at -1.7 1.7 180)
			(size 0.62 0.62)
			(layers "B.Paste")
			(thermal_bridge_angle 90)
			(options
				(clearance outline)
				(anchor circle)
			)
			(primitives
				(gr_arc
					(start 1.266786 0.24747)
					(mid 0.285453 -0.29439)
					(end -0.250195 -1.279127)
					(width 0.2)
				)
				(gr_arc
					(start 1.259603 0.339191)
					(mid 0.218448 -0.232561)
					(end -0.34334 -1.279127)
					(width 0.2)
				)
				(gr_arc
					(start 1.255279 0.431435)
					(mid 0.152481 -0.169693)
					(end -0.436309 -1.279127)
					(width 0.2)
				)
				(gr_arc
					(start 1.253811 0.524161)
					(mid 0.087542 -0.105784)
					(end -0.529126 -1.279127)
					(width 0.2)
				)
				(gr_arc
					(start 1.275473 0.621136)
					(mid 0.0309 -0.033527)
					(end -0.621807 -1.279127)
					(width 0.2)
				)
				(gr_arc
					(start 1.263664 0.711602)
					(mid -0.037759 0.026651)
					(end -0.71437 -1.279127)
					(width 0.2)
				)
				(gr_arc
					(start 1.253435 0.802342)
					(mid -0.105837 0.087395)
					(end -0.806826 -1.279127)
					(width 0.2)
				)
				(gr_arc
					(start 1.267475 0.897258)
					(mid -0.165236 0.156885)
					(end -0.899187 -1.279127)
					(width 0.2)
				)
				(gr_arc
					(start 1.270645 0.990112)
					(mid -0.228522 0.222449)
					(end -0.991463 -1.279127)
					(width 0.2)
				)
				(gr_arc
					(start 1.266278 1.081674)
					(mid -0.294507 0.285313)
					(end -1.083663 -1.279127)
					(width 0.2)
				)
				(gr_line
					(start 1.279127 1.083663)
					(end 1.279127 0.250195)
					(width 0.2)
				)
				(gr_line
					(start -1.083663 -1.279127)
					(end -0.250195 -1.279127)
					(width 0.2)
				)
			)
		)
		(pad "" smd custom
			(at 1.7 -1.7)
			(size 0.62 0.62)
			(layers "B.Paste")
			(thermal_bridge_angle 90)
			(options
				(clearance outline)
				(anchor circle)
			)
			(primitives
				(gr_arc
					(start 1.266786 0.24747)
					(mid 0.285453 -0.29439)
					(end -0.250195 -1.279127)
					(width 0.2)
				)
				(gr_arc
					(start 1.259603 0.339191)
					(mid 0.218448 -0.232561)
					(end -0.34334 -1.279127)
					(width 0.2)
				)
				(gr_arc
					(start 1.255279 0.431435)
					(mid 0.152481 -0.169693)
					(end -0.436309 -1.279127)
					(width 0.2)
				)
				(gr_arc
					(start 1.253811 0.524161)
					(mid 0.087542 -0.105784)
					(end -0.529126 -1.279127)
					(width 0.2)
				)
				(gr_arc
					(start 1.275473 0.621136)
					(mid 0.0309 -0.033527)
					(end -0.621807 -1.279127)
					(width 0.2)
				)
				(gr_arc
					(start 1.263664 0.711602)
					(mid -0.037759 0.026651)
					(end -0.71437 -1.279127)
					(width 0.2)
				)
				(gr_arc
					(start 1.253435 0.802342)
					(mid -0.105837 0.087395)
					(end -0.806826 -1.279127)
					(width 0.2)
				)
				(gr_arc
					(start 1.267475 0.897258)
					(mid -0.165236 0.156885)
					(end -0.899187 -1.279127)
					(width 0.2)
				)
				(gr_arc
					(start 1.270645 0.990112)
					(mid -0.228522 0.222449)
					(end -0.991463 -1.279127)
					(width 0.2)
				)
				(gr_arc
					(start 1.266278 1.081674)
					(mid -0.294507 0.285313)
					(end -1.083663 -1.279127)
					(width 0.2)
				)
				(gr_line
					(start 1.279127 1.083663)
					(end 1.279127 0.250195)
					(width 0.2)
				)
				(gr_line
					(start -1.083663 -1.279127)
					(end -0.250195 -1.279127)
					(width 0.2)
				)
			)
		)
		(pad "" smd custom
			(at 1.7 1.7 270)
			(size 0.62 0.62)
			(layers "B.Paste")
			(thermal_bridge_angle 90)
			(options
				(clearance outline)
				(anchor circle)
			)
			(primitives
				(gr_arc
					(start 1.266786 0.24747)
					(mid 0.285453 -0.29439)
					(end -0.250195 -1.279127)
					(width 0.2)
				)
				(gr_arc
					(start 1.259603 0.339191)
					(mid 0.218448 -0.232561)
					(end -0.34334 -1.279127)
					(width 0.2)
				)
				(gr_arc
					(start 1.255279 0.431435)
					(mid 0.152481 -0.169693)
					(end -0.436309 -1.279127)
					(width 0.2)
				)
				(gr_arc
					(start 1.253811 0.524161)
					(mid 0.087542 -0.105784)
					(end -0.529126 -1.279127)
					(width 0.2)
				)
				(gr_arc
					(start 1.275473 0.621136)
					(mid 0.0309 -0.033527)
					(end -0.621807 -1.279127)
					(width 0.2)
				)
				(gr_arc
					(start 1.263664 0.711602)
					(mid -0.037759 0.026651)
					(end -0.71437 -1.279127)
					(width 0.2)
				)
				(gr_arc
					(start 1.253435 0.802342)
					(mid -0.105837 0.087395)
					(end -0.806826 -1.279127)
					(width 0.2)
				)
				(gr_arc
					(start 1.267475 0.897258)
					(mid -0.165236 0.156885)
					(end -0.899187 -1.279127)
					(width 0.2)
				)
				(gr_arc
					(start 1.270645 0.990112)
					(mid -0.228522 0.222449)
					(end -0.991463 -1.279127)
					(width 0.2)
				)
				(gr_arc
					(start 1.266278 1.081674)
					(mid -0.294507 0.285313)
					(end -1.083663 -1.279127)
					(width 0.2)
				)
				(gr_line
					(start 1.279127 1.083663)
					(end 1.279127 0.250195)
					(width 0.2)
				)
				(gr_line
					(start -1.083663 -1.279127)
					(end -0.250195 -1.279127)
					(width 0.2)
				)
			)
		)
		(pad "1" thru_hole circle
			(at 0 0 180)
			(size 6 6)
			(drill 3.7)
			(layers "*.Cu" "*.Mask")
			(remove_unused_layers no)
			(net 1 "GND")
			(pintype "passive")
		)
	)
	(footprint "antmicro-footprints:R_0402_1005Metric"
		(layer "B.Cu")
		(at 53.23 78.61 90)
		(descr "Resistor SMD 0402")
		(tags "resistor SMD 0402")
		(property "Reference" "R274"
			(at -7.69 21.07 90)
			(layer "B.SilkS")
			(effects
				(font
					(size 0.7 0.7)
					(thickness 0.15)
				)
				(justify left top mirror)
			)
		)
		(property "Value" "R_100k_0402"
			(at -1.011843 -1.772046 90)
			(layer "B.Fab")
			(effects
				(font
					(size 0.7 0.7)
					(thickness 0.15)
				)
				(justify right top mirror)
			)
		)
		(property "Footprint" "antmicro-footprints:R_0402_1005Metric"
			(at 0 0 90)
			(layer "B.Fab")
			(hide yes)
			(effects
				(font
					(size 1.27 1.27)
					(thickness 0.15)
				)
				(justify mirror)
			)
		)
		(property "Datasheet" "https://www.bourns.com/docs/product-datasheets/cr.pdf"
			(at 0 0 90)
			(layer "B.Fab")
			(hide yes)
			(effects
				(font
					(size 1.27 1.27)
					(thickness 0.15)
				)
				(justify mirror)
			)
		)
		(property "MPN" "CR0402-FX-1003GLF"
			(at 0 0 -90)
			(unlocked yes)
			(layer "B.Fab")
			(hide yes)
			(effects
				(font
					(size 1 1)
					(thickness 0.15)
				)
				(justify mirror)
			)
		)
		(property "Manufacturer" "Bourns"
			(at 0 0 -90)
			(unlocked yes)
			(layer "B.Fab")
			(hide yes)
			(effects
				(font
					(size 1 1)
					(thickness 0.15)
				)
				(justify mirror)
			)
		)
		(property "License" "Apache-2.0"
			(at 0 0 -90)
			(unlocked yes)
			(layer "B.Fab")
			(hide yes)
			(effects
				(font
					(size 1 1)
					(thickness 0.15)
				)
				(justify mirror)
			)
		)
		(property "Author" "Antmicro"
			(at 0 0 -90)
			(unlocked yes)
			(layer "B.Fab")
			(hide yes)
			(effects
				(font
					(size 1 1)
					(thickness 0.15)
				)
				(justify mirror)
			)
		)
		(property "Val" "100k"
			(at 0 0 -90)
			(unlocked yes)
			(layer "B.Fab")
			(hide yes)
			(effects
				(font
					(size 1 1)
					(thickness 0.15)
				)
				(justify mirror)
			)
		)
		(property "Tolerance" "1%"
			(at 0 0 -90)
			(unlocked yes)
			(layer "B.Fab")
			(hide yes)
			(effects
				(font
					(size 1 1)
					(thickness 0.15)
				)
				(justify mirror)
			)
		)
		(sheetname "Supply")
		(sheetfile "supply.kicad_sch")
		(attr smd)
		(fp_poly
			(pts
				(xy -0.925 0.47) (xy -0.925 -0.47) (xy 0.925 -0.47) (xy 0.925 0.47)
			)
			(stroke
				(width 0.05)
				(type default)
			)
			(fill none)
			(layer "B.CrtYd")
		)
		(fp_poly
			(pts
				(xy -0.5 0.25) (xy -0.5 -0.25) (xy 0.5 -0.25) (xy 0.5 0.25)
			)
			(stroke
				(width 0.15)
				(type solid)
			)
			(fill none)
			(layer "B.Fab")
		)
		(fp_text user "Author: Antmicro"
			(at -0.95 -4.169 90)
			(layer "B.Fab")
			(hide yes)
			(effects
				(font
					(size 0.7 0.7)
					(thickness 0.15)
				)
				(justify right top mirror)
			)
		)
		(fp_text user "License: Apache-2.0"
			(at -0.949999 -5.169 90)
			(layer "B.Fab")
			(hide yes)
			(effects
				(font
					(size 0.7 0.7)
					(thickness 0.15)
				)
				(justify right top mirror)
			)
		)
		(fp_text user "${REFERENCE}"
			(at -0.95 -3.168 90)
			(layer "B.Fab")
			(hide yes)
			(effects
				(font
					(size 0.7 0.7)
					(thickness 0.15)
				)
				(justify right top mirror)
			)
		)
		(pad "1" smd roundrect
			(at -0.48 0 90)
			(size 0.59 0.64)
			(layers "B.Cu" "B.Paste" "B.Mask")
			(roundrect_rratio 0.25)
			(net 799 "/Supply/PG_{HP}")
			(pintype "passive")
		)
		(pad "2" smd roundrect
			(at 0.48 0 90)
			(size 0.59 0.64)
			(layers "B.Cu" "B.Paste" "B.Mask")
			(roundrect_rratio 0.25)
			(net 787 "+5V_SoM")
			(pintype "passive")
		)
	)
	(footprint "antmicro-footprints:R_0402_1005Metric"
		(layer "B.Cu")
		(at 42.2 119.3 90)
		(descr "Resistor SMD 0402")
		(tags "resistor SMD 0402")
		(property "Reference" "R151"
			(at 3.68 0.3 -90)
			(layer "B.SilkS")
			(effects
				(font
					(size 0.7 0.7)
					(thickness 0.15)
				)
				(justify left bottom mirror)
			)
		)
		(property "Value" "R_200R_0402"
			(at 0 -1.4 -90)
			(layer "B.Fab")
			(effects
				(font
					(size 0.7 0.7)
					(thickness 0.15)
				)
				(justify left bottom mirror)
			)
		)
		(property "Footprint" "antmicro-footprints:R_0402_1005Metric"
			(at 0 0 90)
			(layer "F.Fab")
			(hide yes)
			(effects
				(font
					(size 1.27 1.27)
					(thickness 0.15)
				)
			)
		)
		(property "Datasheet" "https://www.bourns.com/docs/product-datasheets/cr.pdf"
			(at 0 0 90)
			(layer "F.Fab")
			(hide yes)
			(effects
				(font
					(size 1.27 1.27)
					(thickness 0.15)
				)
			)
		)
		(property "Author" "Antmicro"
			(at 161.5 77.1 0)
			(layer "B.Fab")
			(hide yes)
			(effects
				(font
					(size 1 1)
					(thickness 0.15)
				)
				(justify mirror)
			)
		)
		(property "License" "Apache-2.0"
			(at 161.5 77.1 0)
			(layer "B.Fab")
			(hide yes)
			(effects
				(font
					(size 1 1)
					(thickness 0.15)
				)
				(justify mirror)
			)
		)
		(property "MPN" "CR0402-FX-2000GLF"
			(at 161.5 77.1 0)
			(layer "B.Fab")
			(hide yes)
			(effects
				(font
					(size 1 1)
					(thickness 0.15)
				)
				(justify mirror)
			)
		)
		(property "Manufacturer" "Bourns"
			(at 161.5 77.1 0)
			(layer "B.Fab")
			(hide yes)
			(effects
				(font
					(size 1 1)
					(thickness 0.15)
				)
				(justify mirror)
			)
		)
		(property "Tolerance" "1%"
			(at 161.5 77.1 0)
			(layer "B.Fab")
			(hide yes)
			(effects
				(font
					(size 1 1)
					(thickness 0.15)
				)
				(justify mirror)
			)
		)
		(property "Val" "200R"
			(at 161.5 77.1 0)
			(layer "B.Fab")
			(hide yes)
			(effects
				(font
					(size 1 1)
					(thickness 0.15)
				)
				(justify mirror)
			)
		)
		(sheetname "Ethernet")
		(sheetfile "ethernet.kicad_sch")
		(attr smd)
		(fp_rect
			(start -0.925 0.47)
			(end 0.925 -0.47)
			(stroke
				(width 0.05)
				(type default)
			)
			(fill none)
			(layer "B.CrtYd")
		)
		(fp_rect
			(start -0.5 0.25)
			(end 0.5 -0.25)
			(stroke
				(width 0.15)
				(type solid)
			)
			(fill none)
			(layer "B.Fab")
		)
		(fp_text user "${REFERENCE}"
			(at -0.95 -3.168 -90)
			(layer "B.Fab")
			(hide yes)
			(effects
				(font
					(size 0.7 0.7)
					(thickness 0.15)
				)
				(justify left bottom mirror)
			)
		)
		(fp_text user "License: Apache-2.0"
			(at -0.95 -5.169 -90)
			(layer "B.Fab")
			(hide yes)
			(effects
				(font
					(size 0.7 0.7)
					(thickness 0.15)
				)
				(justify left bottom mirror)
			)
		)
		(fp_text user "Author: Antmicro"
			(at -0.95 -4.169 -90)
			(layer "B.Fab")
			(hide yes)
			(effects
				(font
					(size 0.7 0.7)
					(thickness 0.15)
				)
				(justify left bottom mirror)
			)
		)
		(pad "1" smd roundrect
			(at -0.48 0 90)
			(size 0.59 0.64)
			(layers "B.Cu" "B.Paste" "B.Mask")
			(roundrect_rratio 0.25)
			(net 552 "Net-(J6-LED_YEL-)")
			(pintype "passive")
		)
		(pad "2" smd roundrect
			(at 0.48 0 90)
			(size 0.59 0.64)
			(layers "B.Cu" "B.Paste" "B.Mask")
			(roundrect_rratio 0.25)
			(net 459 "GBE_LED_ACT")
			(pintype "passive")
		)
	)
	(footprint "antmicro-footprints:C_0402_1005Metric"
		(layer "B.Cu")
		(at 95.55 91.925)
		(descr "Capacitor SMD 0402")
		(tags "capacitor SMD 0402")
		(property "Reference" "C87"
			(at 5.01 0.065 180)
			(layer "B.SilkS")
			(effects
				(font
					(size 0.7 0.7)
					(thickness 0.15)
				)
				(justify left bottom mirror)
			)
		)
		(property "Value" "C_100n_0402"
			(at 0 -1.4 180)
			(layer "B.Fab")
			(effects
				(font
					(size 0.7 0.7)
					(thickness 0.15)
				)
				(justify left bottom mirror)
			)
		)
		(property "Footprint" "antmicro-footprints:C_0402_1005Metric"
			(at 0 0 0)
			(layer "F.Fab")
			(hide yes)
			(effects
				(font
					(size 1.27 1.27)
					(thickness 0.15)
				)
			)
		)
		(property "Datasheet" "https://www.murata.com/products/productdetail?partno=GRM155R61H104KE14%23"
			(at 0 0 0)
			(layer "F.Fab")
			(hide yes)
			(effects
				(font
					(size 1.27 1.27)
					(thickness 0.15)
				)
			)
		)
		(property "Author" "Antmicro"
			(at 0 0 0)
			(layer "B.Fab")
			(hide yes)
			(effects
				(font
					(size 1 1)
					(thickness 0.15)
				)
				(justify mirror)
			)
		)
		(property "Dielectric" "X5R"
			(at 0 0 0)
			(layer "B.Fab")
			(hide yes)
			(effects
				(font
					(size 1 1)
					(thickness 0.15)
				)
				(justify mirror)
			)
		)
		(property "License" "Apache-2.0"
			(at 0 0 0)
			(layer "B.Fab")
			(hide yes)
			(effects
				(font
					(size 1 1)
					(thickness 0.15)
				)
				(justify mirror)
			)
		)
		(property "MPN" "GRM155R61H104KE14D"
			(at 0 0 0)
			(layer "B.Fab")
			(hide yes)
			(effects
				(font
					(size 1 1)
					(thickness 0.15)
				)
				(justify mirror)
			)
		)
		(property "Manufacturer" "Murata"
			(at 0 0 0)
			(layer "B.Fab")
			(hide yes)
			(effects
				(font
					(size 1 1)
					(thickness 0.15)
				)
				(justify mirror)
			)
		)
		(property "Val" "100n"
			(at 0 0 0)
			(layer "B.Fab")
			(hide yes)
			(effects
				(font
					(size 1 1)
					(thickness 0.15)
				)
				(justify mirror)
			)
		)
		(property "Voltage" "50V"
			(at 0 0 0)
			(layer "B.Fab")
			(hide yes)
			(effects
				(font
					(size 1 1)
					(thickness 0.15)
				)
				(justify mirror)
			)
		)
		(sheetname "HDMI")
		(sheetfile "hdmi.kicad_sch")
		(attr smd)
		(fp_rect
			(start -0.925 0.47)
			(end 0.925 -0.47)
			(stroke
				(width 0.05)
				(type default)
			)
			(fill none)
			(layer "B.CrtYd")
		)
		(fp_line
			(start -0.494 -0.248)
			(end 0.504 -0.248)
			(stroke
				(width 0.15)
				(type solid)
			)
			(layer "B.Fab")
		)
		(fp_line
			(start -0.494 0.25)
			(end -0.494 -0.248)
			(stroke
				(width 0.15)
				(type solid)
			)
			(layer "B.Fab")
		)
		(fp_line
			(start 0.504 -0.248)
			(end 0.504 0.25)
			(stroke
				(width 0.15)
				(type solid)
			)
			(layer "B.Fab")
		)
		(fp_line
			(start 0.504 0.25)
			(end -0.494 0.25)
			(stroke
				(width 0.15)
				(type solid)
			)
			(layer "B.Fab")
		)
		(fp_text user "Author: Antmicro"
			(at -0.932 -4.17 180)
			(layer "B.Fab")
			(hide yes)
			(effects
				(font
					(size 0.7 0.7)
					(thickness 0.15)
				)
				(justify left bottom mirror)
			)
		)
		(fp_text user "License: Apache-2.0"
			(at -0.932 -5.17 180)
			(layer "B.Fab")
			(hide yes)
			(effects
				(font
					(size 0.7 0.7)
					(thickness 0.15)
				)
				(justify left bottom mirror)
			)
		)
		(fp_text user "${REFERENCE}"
			(at -0.932 -3.168 180)
			(layer "B.Fab")
			(hide yes)
			(effects
				(font
					(size 0.7 0.7)
					(thickness 0.15)
				)
				(justify left bottom mirror)
			)
		)
		(pad "1" smd roundrect
			(at -0.48 0)
			(size 0.59 0.64)
			(layers "B.Cu" "B.Paste" "B.Mask")
			(roundrect_rratio 0.25)
			(net 663 "/HDMI/DP_MUX_D1-")
			(pintype "passive")
		)
		(pad "2" smd roundrect
			(at 0.48 0)
			(size 0.59 0.64)
			(layers "B.Cu" "B.Paste" "B.Mask")
			(roundrect_rratio 0.25)
			(net 418 "DP1_TXD2_HDMI_TX0_N")
			(pintype "passive")
		)
	)
	(footprint "antmicro-footprints:R_0402_1005Metric"
		(layer "B.Cu")
		(at 75 103.4 90)
		(descr "Resistor SMD 0402")
		(tags "resistor SMD 0402")
		(property "Reference" "R91"
			(at 5.16 1.67 -90)
			(layer "B.SilkS")
			(effects
				(font
					(size 0.7 0.7)
					(thickness 0.15)
				)
				(justify left bottom mirror)
			)
		)
		(property "Value" "R_1k_0402"
			(at 0 -1.4 -90)
			(layer "B.Fab")
			(effects
				(font
					(size 0.7 0.7)
					(thickness 0.15)
				)
				(justify left bottom mirror)
			)
		)
		(property "Footprint" "antmicro-footprints:R_0402_1005Metric"
			(at 0 0 90)
			(layer "F.Fab")
			(hide yes)
			(effects
				(font
					(size 1.27 1.27)
					(thickness 0.15)
				)
			)
		)
		(property "Datasheet" "https://www.bourns.com/docs/product-datasheets/cr.pdf"
			(at 0 0 90)
			(layer "F.Fab")
			(hide yes)
			(effects
				(font
					(size 1.27 1.27)
					(thickness 0.15)
				)
			)
		)
		(property "Author" "Antmicro"
			(at 178.4 28.4 0)
			(layer "B.Fab")
			(hide yes)
			(effects
				(font
					(size 1 1)
					(thickness 0.15)
				)
				(justify mirror)
			)
		)
		(property "License" "Apache-2.0"
			(at 178.4 28.4 0)
			(layer "B.Fab")
			(hide yes)
			(effects
				(font
					(size 1 1)
					(thickness 0.15)
				)
				(justify mirror)
			)
		)
		(property "MPN" "CR0402-FX-1001GLF"
			(at 178.4 28.4 0)
			(layer "B.Fab")
			(hide yes)
			(effects
				(font
					(size 1 1)
					(thickness 0.15)
				)
				(justify mirror)
			)
		)
		(property "Manufacturer" "Bourns"
			(at 178.4 28.4 0)
			(layer "B.Fab")
			(hide yes)
			(effects
				(font
					(size 1 1)
					(thickness 0.15)
				)
				(justify mirror)
			)
		)
		(property "Tolerance" "1%"
			(at 178.4 28.4 0)
			(layer "B.Fab")
			(hide yes)
			(effects
				(font
					(size 1 1)
					(thickness 0.15)
				)
				(justify mirror)
			)
		)
		(property "Val" "1k"
			(at 178.4 28.4 0)
			(layer "B.Fab")
			(hide yes)
			(effects
				(font
					(size 1 1)
					(thickness 0.15)
				)
				(justify mirror)
			)
		)
		(sheetname "USB Debug, DP")
		(sheetfile "usb.kicad_sch")
		(attr smd exclude_from_pos_files exclude_from_bom dnp)
		(fp_rect
			(start -0.925 0.47)
			(end 0.925 -0.47)
			(stroke
				(width 0.05)
				(type default)
			)
			(fill none)
			(layer "B.CrtYd")
		)
		(fp_rect
			(start -0.5 0.25)
			(end 0.5 -0.25)
			(stroke
				(width 0.15)
				(type solid)
			)
			(fill none)
			(layer "B.Fab")
		)
		(fp_text user "${REFERENCE}"
			(at -0.95 -3.168 -90)
			(layer "B.Fab")
			(hide yes)
			(effects
				(font
					(size 0.7 0.7)
					(thickness 0.15)
				)
				(justify left bottom mirror)
			)
		)
		(fp_text user "Author: Antmicro"
			(at -0.95 -4.169 -90)
			(layer "B.Fab")
			(hide yes)
			(effects
				(font
					(size 0.7 0.7)
					(thickness 0.15)
				)
				(justify left bottom mirror)
			)
		)
		(fp_text user "License: Apache-2.0"
			(at -0.95 -5.169 -90)
			(layer "B.Fab")
			(hide yes)
			(effects
				(font
					(size 0.7 0.7)
					(thickness 0.15)
				)
				(justify left bottom mirror)
			)
		)
		(pad "1" smd roundrect
			(at -0.48 0 90)
			(size 0.59 0.64)
			(layers "B.Cu" "B.Paste" "B.Mask")
			(roundrect_rratio 0.25)
			(net 307 "/USB Debug, DP/USBC0_DPEQ0")
			(pintype "passive")
		)
		(pad "2" smd roundrect
			(at 0.48 0 90)
			(size 0.59 0.64)
			(layers "B.Cu" "B.Paste" "B.Mask")
			(roundrect_rratio 0.25)
			(net 87 "+3V3")
			(pintype "passive")
		)
	)
	(footprint "antmicro-footprints:R_0402_1005Metric"
		(layer "B.Cu")
		(at 91.3 116.1 -90)
		(descr "Resistor SMD 0402")
		(tags "resistor SMD 0402")
		(property "Reference" "R280"
			(at -2.55 -4.8 90)
			(layer "B.SilkS")
			(effects
				(font
					(size 0.7 0.7)
					(thickness 0.15)
				)
				(justify left bottom mirror)
			)
		)
		(property "Value" "R_2k2_0402"
			(at 0 -1.4 90)
			(layer "B.Fab")
			(effects
				(font
					(size 0.7 0.7)
					(thickness 0.15)
				)
				(justify left bottom mirror)
			)
		)
		(property "Footprint" "antmicro-footprints:R_0402_1005Metric"
			(at 0 0 -90)
			(layer "F.Fab")
			(hide yes)
			(effects
				(font
					(size 1.27 1.27)
					(thickness 0.15)
				)
			)
		)
		(property "Datasheet" "https://www.bourns.com/docs/product-datasheets/cr.pdf"
			(at 0 0 -90)
			(layer "F.Fab")
			(hide yes)
			(effects
				(font
					(size 1.27 1.27)
					(thickness 0.15)
				)
			)
		)
		(property "Author" "Antmicro"
			(at -24.8 207.4 0)
			(layer "B.Fab")
			(hide yes)
			(effects
				(font
					(size 1 1)
					(thickness 0.15)
				)
				(justify mirror)
			)
		)
		(property "License" "Apache-2.0"
			(at -24.8 207.4 0)
			(layer "B.Fab")
			(hide yes)
			(effects
				(font
					(size 1 1)
					(thickness 0.15)
				)
				(justify mirror)
			)
		)
		(property "MPN" "CR0402-FX-2201GLF"
			(at -24.8 207.4 0)
			(layer "B.Fab")
			(hide yes)
			(effects
				(font
					(size 1 1)
					(thickness 0.15)
				)
				(justify mirror)
			)
		)
		(property "Manufacturer" "Bourns"
			(at -24.8 207.4 0)
			(layer "B.Fab")
			(hide yes)
			(effects
				(font
					(size 1 1)
					(thickness 0.15)
				)
				(justify mirror)
			)
		)
		(property "Tolerance" "1%"
			(at -24.8 207.4 0)
			(layer "B.Fab")
			(hide yes)
			(effects
				(font
					(size 1 1)
					(thickness 0.15)
				)
				(justify mirror)
			)
		)
		(property "Val" "2k2"
			(at -24.8 207.4 0)
			(layer "B.Fab")
			(hide yes)
			(effects
				(font
					(size 1 1)
					(thickness 0.15)
				)
				(justify mirror)
			)
		)
		(sheetname "HDMI")
		(sheetfile "hdmi.kicad_sch")
		(attr smd exclude_from_pos_files exclude_from_bom dnp)
		(fp_rect
			(start -0.925 0.47)
			(end 0.925 -0.47)
			(stroke
				(width 0.05)
				(type default)
			)
			(fill none)
			(layer "B.CrtYd")
		)
		(fp_rect
			(start -0.5 0.25)
			(end 0.5 -0.25)
			(stroke
				(width 0.15)
				(type solid)
			)
			(fill none)
			(layer "B.Fab")
		)
		(fp_text user "Author: Antmicro"
			(at -0.95 -4.169 90)
			(layer "B.Fab")
			(hide yes)
			(effects
				(font
					(size 0.7 0.7)
					(thickness 0.15)
				)
				(justify left bottom mirror)
			)
		)
		(fp_text user "License: Apache-2.0"
			(at -0.95 -5.169 90)
			(layer "B.Fab")
			(hide yes)
			(effects
				(font
					(size 0.7 0.7)
					(thickness 0.15)
				)
				(justify left bottom mirror)
			)
		)
		(fp_text user "${REFERENCE}"
			(at -0.95 -3.168 90)
			(layer "B.Fab")
			(hide yes)
			(effects
				(font
					(size 0.7 0.7)
					(thickness 0.15)
				)
				(justify left bottom mirror)
			)
		)
		(pad "1" smd roundrect
			(at -0.48 0 270)
			(size 0.59 0.64)
			(layers "B.Cu" "B.Paste" "B.Mask")
			(roundrect_rratio 0.25)
			(net 555 "/HDMI/HDMI_SCL_3V3")
			(pintype "passive")
		)
		(pad "2" smd roundrect
			(at 0.48 0 270)
			(size 0.59 0.64)
			(layers "B.Cu" "B.Paste" "B.Mask")
			(roundrect_rratio 0.25)
			(net 87 "+3V3")
			(pintype "passive")
		)
	)
	(footprint "antmicro-footprints:R_0402_1005Metric"
		(layer "B.Cu")
		(at 76 108.3 90)
		(descr "Resistor SMD 0402")
		(tags "resistor SMD 0402")
		(property "Reference" "R96"
			(at -0.63 2.37 -90)
			(layer "B.SilkS")
			(effects
				(font
					(size 0.7 0.7)
					(thickness 0.15)
				)
				(justify left bottom mirror)
			)
		)
		(property "Value" "R_1k_0402"
			(at 0 -1.4 -90)
			(layer "B.Fab")
			(effects
				(font
					(size 0.7 0.7)
					(thickness 0.15)
				)
				(justify left bottom mirror)
			)
		)
		(property "Footprint" "antmicro-footprints:R_0402_1005Metric"
			(at 0 0 90)
			(layer "F.Fab")
			(hide yes)
			(effects
				(font
					(size 1.27 1.27)
					(thickness 0.15)
				)
			)
		)
		(property "Datasheet" "https://www.bourns.com/docs/product-datasheets/cr.pdf"
			(at 0 0 90)
			(layer "F.Fab")
			(hide yes)
			(effects
				(font
					(size 1.27 1.27)
					(thickness 0.15)
				)
			)
		)
		(property "Author" "Antmicro"
			(at 184.3 32.3 0)
			(layer "B.Fab")
			(hide yes)
			(effects
				(font
					(size 1 1)
					(thickness 0.15)
				)
				(justify mirror)
			)
		)
		(property "License" "Apache-2.0"
			(at 184.3 32.3 0)
			(layer "B.Fab")
			(hide yes)
			(effects
				(font
					(size 1 1)
					(thickness 0.15)
				)
				(justify mirror)
			)
		)
		(property "MPN" "CR0402-FX-1001GLF"
			(at 184.3 32.3 0)
			(layer "B.Fab")
			(hide yes)
			(effects
				(font
					(size 1 1)
					(thickness 0.15)
				)
				(justify mirror)
			)
		)
		(property "Manufacturer" "Bourns"
			(at 184.3 32.3 0)
			(layer "B.Fab")
			(hide yes)
			(effects
				(font
					(size 1 1)
					(thickness 0.15)
				)
				(justify mirror)
			)
		)
		(property "Tolerance" "1%"
			(at 184.3 32.3 0)
			(layer "B.Fab")
			(hide yes)
			(effects
				(font
					(size 1 1)
					(thickness 0.15)
				)
				(justify mirror)
			)
		)
		(property "Val" "1k"
			(at 184.3 32.3 0)
			(layer "B.Fab")
			(hide yes)
			(effects
				(font
					(size 1 1)
					(thickness 0.15)
				)
				(justify mirror)
			)
		)
		(sheetname "USB Debug, DP")
		(sheetfile "usb.kicad_sch")
		(attr smd exclude_from_pos_files exclude_from_bom dnp)
		(fp_rect
			(start -0.925 0.47)
			(end 0.925 -0.47)
			(stroke
				(width 0.05)
				(type default)
			)
			(fill none)
			(layer "B.CrtYd")
		)
		(fp_rect
			(start -0.5 0.25)
			(end 0.5 -0.25)
			(stroke
				(width 0.15)
				(type solid)
			)
			(fill none)
			(layer "B.Fab")
		)
		(fp_text user "${REFERENCE}"
			(at -0.95 -3.168 -90)
			(layer "B.Fab")
			(hide yes)
			(effects
				(font
					(size 0.7 0.7)
					(thickness 0.15)
				)
				(justify left bottom mirror)
			)
		)
		(fp_text user "Author: Antmicro"
			(at -0.95 -4.169 -90)
			(layer "B.Fab")
			(hide yes)
			(effects
				(font
					(size 0.7 0.7)
					(thickness 0.15)
				)
				(justify left bottom mirror)
			)
		)
		(fp_text user "License: Apache-2.0"
			(at -0.95 -5.169 -90)
			(layer "B.Fab")
			(hide yes)
			(effects
				(font
					(size 0.7 0.7)
					(thickness 0.15)
				)
				(justify left bottom mirror)
			)
		)
		(pad "1" smd roundrect
			(at -0.48 0 90)
			(size 0.59 0.64)
			(layers "B.Cu" "B.Paste" "B.Mask")
			(roundrect_rratio 0.25)
			(net 309 "/USB Debug, DP/USBC0_EQ0")
			(pintype "passive")
		)
		(pad "2" smd roundrect
			(at 0.48 0 90)
			(size 0.59 0.64)
			(layers "B.Cu" "B.Paste" "B.Mask")
			(roundrect_rratio 0.25)
			(net 1 "GND")
			(pintype "passive")
		)
	)
	(footprint "antmicro-footprints:SOD-523"
		(layer "B.Cu")
		(at 58.95 77.35)
		(property "Reference" "D36"
			(at 20.77 9.01 0)
			(layer "B.SilkS")
			(effects
				(font
					(size 0.7 0.7)
					(thickness 0.15)
				)
				(justify right bottom mirror)
			)
		)
		(property "Value" "RB521S30T1G"
			(at 0 -1.499 0)
			(layer "B.Fab")
			(effects
				(font
					(size 0.7 0.7)
					(thickness 0.15)
				)
				(justify right bottom mirror)
			)
		)
		(property "Footprint" "antmicro-footprints:SOD-523"
			(at 0 0 0)
			(layer "F.Fab")
			(hide yes)
			(effects
				(font
					(size 1.27 1.27)
					(thickness 0.15)
				)
			)
		)
		(property "Datasheet" "https://www.onsemi.com/pdf/datasheet/rb521s30t1-d.pdf"
			(at 0 0 0)
			(layer "F.Fab")
			(hide yes)
			(effects
				(font
					(size 1.27 1.27)
					(thickness 0.15)
				)
			)
		)
		(property "Author" "Antmicro"
			(at 0 0 0)
			(layer "B.Fab")
			(hide yes)
			(effects
				(font
					(size 1 1)
					(thickness 0.15)
				)
				(justify mirror)
			)
		)
		(property "License" "Apache-2.0"
			(at 0 0 0)
			(layer "B.Fab")
			(hide yes)
			(effects
				(font
					(size 1 1)
					(thickness 0.15)
				)
				(justify mirror)
			)
		)
		(property "MPN" "RB521S30T1G"
			(at 0 0 0)
			(layer "B.Fab")
			(hide yes)
			(effects
				(font
					(size 1 1)
					(thickness 0.15)
				)
				(justify mirror)
			)
		)
		(property "Manufacturer" "ON Semiconductor"
			(at 0 0 0)
			(layer "B.Fab")
			(hide yes)
			(effects
				(font
					(size 1 1)
					(thickness 0.15)
				)
				(justify mirror)
			)
		)
		(sheetname "Supply")
		(sheetfile "supply.kicad_sch")
		(attr smd)
		(fp_line
			(start -0.35 -0.5)
			(end -0.35 0.5)
			(stroke
				(width 0.15)
				(type solid)
			)
			(layer "B.SilkS")
		)
		(fp_rect
			(start -1 0.6)
			(end 1 -0.6)
			(stroke
				(width 0.05)
				(type solid)
			)
			(fill none)
			(layer "B.CrtYd")
		)
		(fp_line
			(start -0.652 0.425)
			(end -0.652 -0.423)
			(stroke
				(width 0.15)
				(type solid)
			)
			(layer "B.Fab")
		)
		(fp_line
			(start -0.35 -0.4)
			(end -0.35 0.4)
			(stroke
				(width 0.15)
				(type solid)
			)
			(layer "B.Fab")
		)
		(fp_line
			(start 0.65 -0.423)
			(end -0.652 -0.423)
			(stroke
				(width 0.15)
				(type solid)
			)
			(layer "B.Fab")
		)
		(fp_line
			(start 0.65 -0.423)
			(end 0.65 0.425)
			(stroke
				(width 0.15)
				(type solid)
			)
			(layer "B.Fab")
		)
		(fp_line
			(start 0.65 0.425)
			(end -0.652 0.425)
			(stroke
				(width 0.15)
				(type solid)
			)
			(layer "B.Fab")
		)
		(fp_text user "License: Apache-2.0"
			(at -1.276 -5.9 0)
			(layer "B.Fab")
			(hide yes)
			(effects
				(font
					(size 0.7 0.7)
					(thickness 0.15)
				)
				(justify right bottom mirror)
			)
		)
		(fp_text user "${REFERENCE}"
			(at -1.276 -3.499 0)
			(layer "B.Fab")
			(hide yes)
			(effects
				(font
					(size 0.7 0.7)
					(thickness 0.15)
				)
				(justify right bottom mirror)
			)
		)
		(fp_text user "Author: Antmicro"
			(at -1.276 -4.7 0)
			(layer "B.Fab")
			(hide yes)
			(effects
				(font
					(size 0.7 0.7)
					(thickness 0.15)
				)
				(justify right bottom mirror)
			)
		)
		(pad "1" smd roundrect
			(at -0.701 0)
			(size 0.5 0.6)
			(layers "B.Cu" "B.Paste" "B.Mask")
			(roundrect_rratio 0.25)
			(net 174 "Net-(D36-C)")
			(pinfunction "C")
			(pintype "passive")
		)
		(pad "2" smd roundrect
			(at 0.699 0)
			(size 0.5 0.6)
			(layers "B.Cu" "B.Paste" "B.Mask")
			(roundrect_rratio 0.25)
			(net 137 "Net-(D36-A)")
			(pinfunction "A")
			(pintype "passive")
		)
	)
	(footprint "antmicro-footprints:Conn_JST_SH_1x4_SM04B-SRSS-TB-LF-SN"
		(layer "B.Cu")
		(at 131.65 125.651 180)
		(property "Reference" "J14"
			(at 1.9 2.301 0)
			(layer "B.SilkS")
			(effects
				(font
					(size 0.7 0.7)
					(thickness 0.15)
				)
				(justify left bottom mirror)
			)
		)
		(property "Value" "JST_SH_1x4_SM04B-SRSS-TB-LF-SN"
			(at 0 -3.9 0)
			(layer "B.Fab")
			(effects
				(font
					(size 0.7 0.7)
					(thickness 0.15)
				)
				(justify left bottom mirror)
			)
		)
		(property "Footprint" "antmicro-footprints:Conn_JST_SH_1x4_SM04B-SRSS-TB-LF-SN"
			(at 0 0 180)
			(layer "F.Fab")
			(hide yes)
			(effects
				(font
					(size 1.27 1.27)
					(thickness 0.15)
				)
			)
		)
		(property "Datasheet" "https://www.jst-mfg.com/product/pdf/eng/eSH.pdf"
			(at 0 0 180)
			(layer "F.Fab")
			(hide yes)
			(effects
				(font
					(size 1.27 1.27)
					(thickness 0.15)
				)
			)
		)
		(property "Author" "Antmicro"
			(at 263.3 251.302 0)
			(layer "B.Fab")
			(hide yes)
			(effects
				(font
					(size 1 1)
					(thickness 0.15)
				)
				(justify mirror)
			)
		)
		(property "License" "Apache-2.0"
			(at 263.3 251.302 0)
			(layer "B.Fab")
			(hide yes)
			(effects
				(font
					(size 1 1)
					(thickness 0.15)
				)
				(justify mirror)
			)
		)
		(property "MPN" "SM04B-SRSS-TB(LF)(SN)"
			(at 263.3 251.302 0)
			(layer "B.Fab")
			(hide yes)
			(effects
				(font
					(size 1 1)
					(thickness 0.15)
				)
				(justify mirror)
			)
		)
		(property "Manufacturer" "JST Automotive Connectors"
			(at 263.3 251.302 0)
			(layer "B.Fab")
			(hide yes)
			(effects
				(font
					(size 1 1)
					(thickness 0.15)
				)
				(justify mirror)
			)
		)
		(sheetname "Peripherals")
		(sheetfile "peripherals.kicad_sch")
		(attr smd)
		(fp_line
			(start 3.2 2)
			(end 2 2)
			(stroke
				(width 0.15)
				(type solid)
			)
			(layer "B.SilkS")
		)
		(fp_line
			(start 3.2 -0.6)
			(end 3.2 2)
			(stroke
				(width 0.15)
				(type solid)
			)
			(layer "B.SilkS")
		)
		(fp_line
			(start 2 -2.6)
			(end -2 -2.6)
			(stroke
				(width 0.15)
				(type solid)
			)
			(layer "B.SilkS")
		)
		(fp_line
			(start -3.2 2)
			(end -2 2)
			(stroke
				(width 0.15)
				(type solid)
			)
			(layer "B.SilkS")
		)
		(fp_line
			(start -3.2 -0.6)
			(end -3.2 2)
			(stroke
				(width 0.15)
				(type solid)
			)
			(layer "B.SilkS")
		)
		(fp_circle
			(center -2.1 2.5)
			(end -2.05 2.5)
			(stroke
				(width 0.15)
				(type solid)
			)
			(fill solid)
			(layer "B.SilkS")
		)
		(fp_rect
			(start -3.65 3.14)
			(end 3.65 -2.9)
			(stroke
				(width 0.05)
				(type solid)
			)
			(fill none)
			(layer "B.CrtYd")
		)
		(fp_rect
			(start -3 2.475)
			(end 3 -2.475)
			(stroke
				(width 0.15)
				(type solid)
			)
			(fill none)
			(layer "B.Fab")
		)
		(fp_text user "Author: Antmicro"
			(at -4 -6.945 0)
			(layer "B.Fab")
			(hide yes)
			(effects
				(font
					(size 0.7 0.7)
					(thickness 0.15)
				)
				(justify left bottom mirror)
			)
		)
		(fp_text user "${REFERENCE}"
			(at -4 -5.743 0)
			(layer "B.Fab")
			(hide yes)
			(effects
				(font
					(size 0.7 0.7)
					(thickness 0.15)
				)
				(justify left bottom mirror)
			)
		)
		(fp_text user "License: Apache-2.0"
			(at -4 -8.143 0)
			(layer "B.Fab")
			(hide yes)
			(effects
				(font
					(size 0.7 0.7)
					(thickness 0.15)
				)
				(justify left bottom mirror)
			)
		)
		(pad "1" smd roundrect
			(at -1.5 2.12)
			(size 0.6 1.55)
			(layers "B.Cu" "B.Paste" "B.Mask")
			(roundrect_rratio 0.25)
			(net 1 "GND")
			(pintype "passive")
		)
		(pad "2" smd roundrect
			(at -0.5 2.12)
			(size 0.6 1.55)
			(layers "B.Cu" "B.Paste" "B.Mask")
			(roundrect_rratio 0.25)
			(net 662 "/Peripherals/I2C_CONN_3V3")
			(pintype "passive")
		)
		(pad "3" smd roundrect
			(at 0.5 2.12)
			(size 0.6 1.55)
			(layers "B.Cu" "B.Paste" "B.Mask")
			(roundrect_rratio 0.25)
			(net 660 "I2C1_SDA")
			(pintype "passive")
		)
		(pad "4" smd roundrect
			(at 1.5 2.12)
			(size 0.6 1.55)
			(layers "B.Cu" "B.Paste" "B.Mask")
			(roundrect_rratio 0.25)
			(net 659 "I2C1_SCL")
			(pintype "passive")
		)
		(pad "MP" smd roundrect
			(at -2.8 -1.755 180)
			(size 1.2 1.8)
			(layers "B.Cu" "B.Paste" "B.Mask")
			(roundrect_rratio 0.25)
			(net 1 "GND")
			(pintype "passive")
		)
		(pad "MP" smd roundrect
			(at 2.8 -1.755 180)
			(size 1.2 1.8)
			(layers "B.Cu" "B.Paste" "B.Mask")
			(roundrect_rratio 0.25)
			(net 1 "GND")
			(pintype "passive")
		)
	)
	(footprint "antmicro-footprints:SOT-363"
		(layer "B.Cu")
		(at 43.7 74.675)
		(property "Reference" "Q14"
			(at -1.46 1.05 90)
			(layer "B.SilkS")
			(effects
				(font
					(size 0.7 0.7)
					(thickness 0.15)
				)
				(justify right bottom mirror)
			)
		)
		(property "Value" "BCM857BS-7-F"
			(at 0 -2.2 0)
			(layer "B.Fab")
			(effects
				(font
					(size 0.7 0.7)
					(thickness 0.15)
				)
				(justify right bottom mirror)
			)
		)
		(property "Footprint" "antmicro-footprints:SOT-363"
			(at 0 0 0)
			(layer "F.Fab")
			(hide yes)
			(effects
				(font
					(size 1.27 1.27)
					(thickness 0.15)
				)
			)
		)
		(property "Datasheet" "https://www.diodes.com/assets/Datasheets/BCM857BS.pdf"
			(at 0 0 0)
			(layer "F.Fab")
			(hide yes)
			(effects
				(font
					(size 1.27 1.27)
					(thickness 0.15)
				)
			)
		)
		(property "Author" "Antmicro"
			(at 0 0 0)
			(layer "B.Fab")
			(hide yes)
			(effects
				(font
					(size 1 1)
					(thickness 0.15)
				)
				(justify mirror)
			)
		)
		(property "License" "Apache-2.0"
			(at 0 0 0)
			(layer "B.Fab")
			(hide yes)
			(effects
				(font
					(size 1 1)
					(thickness 0.15)
				)
				(justify mirror)
			)
		)
		(property "MPN" "BCM857BS-7-F"
			(at 0 0 0)
			(layer "B.Fab")
			(hide yes)
			(effects
				(font
					(size 1 1)
					(thickness 0.15)
				)
				(justify mirror)
			)
		)
		(property "Manufacturer" "Diodes Incorporated"
			(at 0 0 0)
			(layer "B.Fab")
			(hide yes)
			(effects
				(font
					(size 1 1)
					(thickness 0.15)
				)
				(justify mirror)
			)
		)
		(sheetname "Supply")
		(sheetfile "supply.kicad_sch")
		(attr smd)
		(fp_line
			(start -0.8 -1.223)
			(end -0.8 -1.146)
			(stroke
				(width 0.15)
				(type solid)
			)
			(layer "B.SilkS")
		)
		(fp_line
			(start -0.72 1.228)
			(end -0.72 1.153)
			(stroke
				(width 0.15)
				(type solid)
			)
			(layer "B.SilkS")
		)
		(fp_line
			(start -0.72 1.228)
			(end 0.803 1.228)
			(stroke
				(width 0.15)
				(type solid)
			)
			(layer "B.SilkS")
		)
		(fp_line
			(start 0.803 -1.223)
			(end -0.8 -1.223)
			(stroke
				(width 0.15)
				(type solid)
			)
			(layer "B.SilkS")
		)
		(fp_line
			(start 0.803 -1.223)
			(end 0.803 -1.146)
			(stroke
				(width 0.15)
				(type solid)
			)
			(layer "B.SilkS")
		)
		(fp_line
			(start 0.803 1.228)
			(end 0.803 1.153)
			(stroke
				(width 0.15)
				(type solid)
			)
			(layer "B.SilkS")
		)
		(fp_circle
			(center -0.978102 1.2)
			(end -0.928102 1.2)
			(stroke
				(width 0.15)
				(type solid)
			)
			(fill solid)
			(layer "B.SilkS")
		)
		(fp_rect
			(start 1.3 1.3)
			(end -1.3 -1.3)
			(stroke
				(width 0.05)
				(type solid)
			)
			(fill none)
			(layer "B.CrtYd")
		)
		(fp_line
			(start -0.68 0.52)
			(end -0.1 1.1)
			(stroke
				(width 0.15)
				(type solid)
			)
			(layer "B.Fab")
		)
		(fp_rect
			(start 0.68 -1.1)
			(end -0.68 1.1)
			(stroke
				(width 0.15)
				(type solid)
			)
			(fill none)
			(layer "B.Fab")
		)
		(fp_text user "License: Apache-2.0"
			(at -1.3 -5.2 0)
			(layer "B.Fab")
			(hide yes)
			(effects
				(font
					(size 0.7 0.7)
					(thickness 0.15)
				)
				(justify right bottom mirror)
			)
		)
		(fp_text user "Author: Antmicro"
			(at -1.3 -6.4 0)
			(layer "B.Fab")
			(hide yes)
			(effects
				(font
					(size 0.7 0.7)
					(thickness 0.15)
				)
				(justify right bottom mirror)
			)
		)
		(fp_text user "${REFERENCE}"
			(at -1.3 -4 0)
			(layer "B.Fab")
			(hide yes)
			(effects
				(font
					(size 0.7 0.7)
					(thickness 0.15)
				)
				(justify right bottom mirror)
			)
		)
		(pad "1" smd custom
			(at -0.948 0.752 90)
			(size 0.6 0.6)
			(layers "B.Cu" "B.Paste" "B.Mask")
			(net 328 "/Supply/VCC_IN")
			(pintype "passive")
			(options
				(clearance outline)
				(anchor rect)
			)
			(primitives)
		)
		(pad "2" smd rect
			(at -0.948 0.002 90)
			(size 0.4 0.6)
			(layers "B.Cu" "B.Paste" "B.Mask")
			(net 718 "Net-(Q14-Pad2)")
			(pintype "passive")
		)
		(pad "3" smd custom
			(at -0.948 -0.745 90)
			(size 0.6 0.6)
			(layers "B.Cu" "B.Paste" "B.Mask")
			(net 718 "Net-(Q14-Pad2)")
			(pintype "passive")
			(options
				(clearance outline)
				(anchor rect)
			)
			(primitives)
		)
		(pad "4" smd custom
			(at 0.951 -0.745 90)
			(size 0.6 0.6)
			(layers "B.Cu" "B.Paste" "B.Mask")
			(net 500 "POE_OUTPUT")
			(pintype "passive")
			(options
				(clearance outline)
				(anchor rect)
			)
			(primitives)
		)
		(pad "5" smd rect
			(at 0.951 0.002 90)
			(size 0.4 0.6)
			(layers "B.Cu" "B.Paste" "B.Mask")
			(net 718 "Net-(Q14-Pad2)")
			(pintype "passive")
		)
		(pad "6" smd custom
			(at 0.951 0.752 90)
			(size 0.6 0.6)
			(layers "B.Cu" "B.Paste" "B.Mask")
			(net 631 "Net-(Q16-G)")
			(pintype "passive")
			(options
				(clearance outline)
				(anchor rect)
			)
			(primitives)
		)
	)
	(footprint "antmicro-footprints:XSON-8_1x1.95mm_P0.5mm"
		(layer "B.Cu")
		(at 66.8 79.99 90)
		(property "Reference" "U4"
			(at 1.56 -1.3 -90)
			(layer "B.SilkS")
			(effects
				(font
					(size 0.7 0.7)
					(thickness 0.15)
				)
				(justify left bottom mirror)
			)
		)
		(property "Value" "NTS0102_XSON"
			(at 0 -2.2 -90)
			(layer "B.Fab")
			(effects
				(font
					(size 0.7 0.7)
					(thickness 0.15)
				)
				(justify left bottom mirror)
			)
		)
		(property "Footprint" "antmicro-footprints:XSON-8_1x1.95mm_P0.5mm"
			(at 0 0 90)
			(layer "F.Fab")
			(hide yes)
			(effects
				(font
					(size 1.27 1.27)
					(thickness 0.15)
				)
			)
		)
		(property "Datasheet" "http://www.farnell.com/datasheets/1760723.pdf"
			(at 0 0 90)
			(layer "F.Fab")
			(hide yes)
			(effects
				(font
					(size 1.27 1.27)
					(thickness 0.15)
				)
			)
		)
		(property "Author" "Antmicro"
			(at 146.79 13.19 0)
			(layer "B.Fab")
			(hide yes)
			(effects
				(font
					(size 1 1)
					(thickness 0.15)
				)
				(justify mirror)
			)
		)
		(property "License" "Apache-2.0"
			(at 146.79 13.19 0)
			(layer "B.Fab")
			(hide yes)
			(effects
				(font
					(size 1 1)
					(thickness 0.15)
				)
				(justify mirror)
			)
		)
		(property "MPN" "NTS0102GT"
			(at 146.79 13.19 0)
			(layer "B.Fab")
			(hide yes)
			(effects
				(font
					(size 1 1)
					(thickness 0.15)
				)
				(justify mirror)
			)
		)
		(property "Manufacturer" "NXP"
			(at 146.79 13.19 0)
			(layer "B.Fab")
			(hide yes)
			(effects
				(font
					(size 1 1)
					(thickness 0.15)
				)
				(justify mirror)
			)
		)
		(sheetname "SoM")
		(sheetfile "som.kicad_sch")
		(attr smd)
		(fp_line
			(start -0.5 -1.1)
			(end 0.5 -1.1)
			(stroke
				(width 0.15)
				(type solid)
			)
			(layer "B.SilkS")
		)
		(fp_line
			(start 0.5 1.1)
			(end -0.5 1.1)
			(stroke
				(width 0.15)
				(type solid)
			)
			(layer "B.SilkS")
		)
		(fp_circle
			(center -0.75 1.1)
			(end -0.701 1.1)
			(stroke
				(width 0.15)
				(type solid)
			)
			(fill none)
			(layer "B.SilkS")
		)
		(fp_rect
			(start -0.8 1.2)
			(end 0.8 -1.2)
			(stroke
				(width 0.05)
				(type solid)
			)
			(fill none)
			(layer "B.CrtYd")
		)
		(fp_line
			(start 0.5305 -1)
			(end 0.5305 1.001)
			(stroke
				(width 0.15)
				(type solid)
			)
			(layer "B.Fab")
		)
		(fp_line
			(start -0.5305 -1)
			(end 0.5305 -1)
			(stroke
				(width 0.15)
				(type solid)
			)
			(layer "B.Fab")
		)
		(fp_line
			(start 0.5305 1.001)
			(end -0.5305 1.001)
			(stroke
				(width 0.15)
				(type solid)
			)
			(layer "B.Fab")
		)
		(fp_line
			(start -0.5305 1.001)
			(end -0.5305 -1)
			(stroke
				(width 0.15)
				(type solid)
			)
			(layer "B.Fab")
		)
		(fp_text user "License: Apache-2.0"
			(at -0.527 -8.306 -90)
			(layer "B.Fab")
			(hide yes)
			(effects
				(font
					(size 0.7 0.7)
					(thickness 0.15)
				)
				(justify left bottom mirror)
			)
		)
		(fp_text user "Author: Antmicro"
			(at -0.527 -7.105 -90)
			(layer "B.Fab")
			(hide yes)
			(effects
				(font
					(size 0.7 0.7)
					(thickness 0.15)
				)
				(justify left bottom mirror)
			)
		)
		(fp_text user "${REFERENCE}"
			(at -0.527 -5.905 -90)
			(layer "B.Fab")
			(hide yes)
			(effects
				(font
					(size 0.7 0.7)
					(thickness 0.15)
				)
				(justify left bottom mirror)
			)
		)
		(pad "1" smd roundrect
			(at -0.45 0.75 270)
			(size 0.6 0.3)
			(layers "B.Cu" "B.Paste" "B.Mask")
			(roundrect_rratio 0.25)
			(net 475 "DEBUG_TXD")
			(pinfunction "B_{2}")
			(pintype "bidirectional")
		)
		(pad "2" smd roundrect
			(at -0.45 0.25 270)
			(size 0.6 0.25)
			(layers "B.Cu" "B.Paste" "B.Mask")
			(roundrect_rratio 0.25)
			(net 1 "GND")
			(pinfunction "GND")
			(pintype "power_in")
		)
		(pad "3" smd roundrect
			(at -0.45 -0.25 270)
			(size 0.6 0.25)
			(layers "B.Cu" "B.Paste" "B.Mask")
			(roundrect_rratio 0.25)
			(net 112 "+1V8")
			(pinfunction "VCC_{A}")
			(pintype "power_in")
		)
		(pad "4" smd roundrect
			(at -0.45 -0.75 270)
			(size 0.6 0.3)
			(layers "B.Cu" "B.Paste" "B.Mask")
			(roundrect_rratio 0.25)
			(net 168 "/SoM/DEBUG_TXD_1V8")
			(pinfunction "A_{2}")
			(pintype "bidirectional")
		)
		(pad "5" smd roundrect
			(at 0.45 -0.75 270)
			(size 0.6 0.3)
			(layers "B.Cu" "B.Paste" "B.Mask")
			(roundrect_rratio 0.25)
			(net 327 "/SoM/DEBUG_RXD_1V8")
			(pinfunction "A_{1}")
			(pintype "bidirectional")
		)
		(pad "6" smd roundrect
			(at 0.45 -0.25 270)
			(size 0.6 0.25)
			(layers "B.Cu" "B.Paste" "B.Mask")
			(roundrect_rratio 0.25)
			(net 112 "+1V8")
			(pinfunction "OE")
			(pintype "input")
		)
		(pad "7" smd roundrect
			(at 0.45 0.25 270)
			(size 0.6 0.25)
			(layers "B.Cu" "B.Paste" "B.Mask")
			(roundrect_rratio 0.25)
			(net 87 "+3V3")
			(pinfunction "VCC_{B}")
			(pintype "power_in")
		)
		(pad "8" smd roundrect
			(at 0.45 0.75 270)
			(size 0.6 0.3)
			(layers "B.Cu" "B.Paste" "B.Mask")
			(roundrect_rratio 0.25)
			(net 477 "DEBUG_RXD")
			(pinfunction "B_{1}")
			(pintype "bidirectional")
		)
	)
	(footprint "antmicro-footprints:TP_SMD_0.75mm"
		(layer "B.Cu")
		(at 63.79 97)
		(property "Reference" "TP13"
			(at 1.42 -0.42 180)
			(layer "B.SilkS")
			(hide yes)
			(effects
				(font
					(size 0.7 0.7)
					(thickness 0.15)
				)
				(justify left bottom mirror)
			)
		)
		(property "Value" "TP_0.75mm_SMD"
			(at 0 -1.2 180)
			(layer "B.Fab")
			(effects
				(font
					(size 0.7 0.7)
					(thickness 0.15)
				)
				(justify left bottom mirror)
			)
		)
		(property "Footprint" "antmicro-footprints:TP_SMD_0.75mm"
			(at 0 0 0)
			(layer "F.Fab")
			(hide yes)
			(effects
				(font
					(size 1.27 1.27)
					(thickness 0.15)
				)
			)
		)
		(property "Author" "Antmicro"
			(at 0 0 0)
			(layer "B.Fab")
			(hide yes)
			(effects
				(font
					(size 1 1)
					(thickness 0.15)
				)
				(justify mirror)
			)
		)
		(property "License" "Apache-2.0"
			(at 0 0 0)
			(layer "B.Fab")
			(hide yes)
			(effects
				(font
					(size 1 1)
					(thickness 0.15)
				)
				(justify mirror)
			)
		)
		(property "MPN" ""
			(at 0 0 0)
			(layer "B.Fab")
			(hide yes)
			(effects
				(font
					(size 1 1)
					(thickness 0.15)
				)
				(justify mirror)
			)
		)
		(property "Manufacturer" ""
			(at 0 0 0)
			(layer "B.Fab")
			(hide yes)
			(effects
				(font
					(size 1 1)
					(thickness 0.15)
				)
				(justify mirror)
			)
		)
		(sheetname "USB Debug, DP")
		(sheetfile "usb.kicad_sch")
		(attr exclude_from_pos_files exclude_from_bom)
		(fp_circle
			(center 0 0)
			(end 0.475 0)
			(stroke
				(width 0.05)
				(type default)
			)
			(fill none)
			(layer "B.CrtYd")
		)
		(fp_text user "${REFERENCE}"
			(at -0.4 -2.7 180)
			(layer "B.Fab")
			(hide yes)
			(effects
				(font
					(size 0.7 0.7)
					(thickness 0.15)
				)
				(justify left bottom mirror)
			)
		)
		(fp_text user "Author: Antmicro"
			(at -0.4 -3.901 180)
			(layer "B.Fab")
			(hide yes)
			(effects
				(font
					(size 0.7 0.7)
					(thickness 0.15)
				)
				(justify left bottom mirror)
			)
		)
		(fp_text user "License: Apache-2.0"
			(at -0.4 -5.101 180)
			(layer "B.Fab")
			(hide yes)
			(effects
				(font
					(size 0.7 0.7)
					(thickness 0.15)
				)
				(justify left bottom mirror)
			)
		)
		(pad "1" smd circle
			(at 0 0)
			(size 0.75 0.75)
			(layers "B.Cu" "B.Mask")
			(net 691 "Net-(U6A-GPIO3{slash}HPD1)")
			(pinfunction "1")
			(pintype "passive")
		)
	)
	(footprint "antmicro-footprints:DFN3538"
		(layer "B.Cu")
		(at 52.3 105.7 180)
		(property "Reference" "D13"
			(at 0 2.8 0)
			(unlocked yes)
			(layer "B.SilkS")
			(effects
				(font
					(size 0.7 0.7)
					(thickness 0.15)
				)
				(justify left bottom mirror)
			)
		)
		(property "Value" "CD-MMBL110S"
			(at 0 -3.5 0)
			(unlocked yes)
			(layer "B.Fab")
			(effects
				(font
					(size 0.7 0.7)
					(thickness 0.15)
				)
				(justify left bottom mirror)
			)
		)
		(property "Footprint" "antmicro-footprints:DFN3538"
			(at 0 0 180)
			(layer "F.Fab")
			(hide yes)
			(effects
				(font
					(size 1.27 1.27)
					(thickness 0.15)
				)
			)
		)
		(property "Datasheet" "https://www.bourns.com/docs/product-datasheets/CD-MMBL110S.pdf"
			(at 0 0 180)
			(layer "F.Fab")
			(hide yes)
			(effects
				(font
					(size 1.27 1.27)
					(thickness 0.15)
				)
			)
		)
		(property "Author" "Antmicro"
			(at 104.6 211.4 0)
			(layer "B.Fab")
			(hide yes)
			(effects
				(font
					(size 1 1)
					(thickness 0.15)
				)
				(justify mirror)
			)
		)
		(property "License" "Apache-2.0"
			(at 104.6 211.4 0)
			(layer "B.Fab")
			(hide yes)
			(effects
				(font
					(size 1 1)
					(thickness 0.15)
				)
				(justify mirror)
			)
		)
		(property "MPN" "CD-MMBL110S"
			(at 104.6 211.4 0)
			(layer "B.Fab")
			(hide yes)
			(effects
				(font
					(size 1 1)
					(thickness 0.15)
				)
				(justify mirror)
			)
		)
		(property "Manufacturer" "Bourns"
			(at 104.6 211.4 0)
			(layer "B.Fab")
			(hide yes)
			(effects
				(font
					(size 1 1)
					(thickness 0.15)
				)
				(justify mirror)
			)
		)
		(sheetname "Ethernet")
		(sheetfile "ethernet.kicad_sch")
		(attr smd)
		(fp_line
			(start 1.8 2)
			(end 1.6 2)
			(stroke
				(width 0.15)
				(type solid)
			)
			(layer "B.SilkS")
		)
		(fp_line
			(start 1.8 -2.05)
			(end 1.8 2)
			(stroke
				(width 0.15)
				(type solid)
			)
			(layer "B.SilkS")
		)
		(fp_line
			(start 1.8 -2.05)
			(end 1.6 -2.05)
			(stroke
				(width 0.15)
				(type solid)
			)
			(layer "B.SilkS")
		)
		(fp_line
			(start 0.95 2)
			(end -0.95 2)
			(stroke
				(width 0.15)
				(type solid)
			)
			(layer "B.SilkS")
		)
		(fp_line
			(start 0.95 -2.05)
			(end -0.95 -2.05)
			(stroke
				(width 0.15)
				(type solid)
			)
			(layer "B.SilkS")
		)
		(fp_line
			(start 0.748 2.15)
			(end 0.748 2.452)
			(stroke
				(width 0.15)
				(type solid)
			)
			(layer "B.SilkS")
		)
		(fp_line
			(start 0.598 2.301)
			(end 0.9 2.301)
			(stroke
				(width 0.15)
				(type solid)
			)
			(layer "B.SilkS")
		)
		(fp_line
			(start -0.6 2.25)
			(end -0.902 2.25)
			(stroke
				(width 0.15)
				(type solid)
			)
			(layer "B.SilkS")
		)
		(fp_line
			(start -1.6 -2.05)
			(end -1.8 -2.05)
			(stroke
				(width 0.15)
				(type solid)
			)
			(layer "B.SilkS")
		)
		(fp_line
			(start -1.8 -2.05)
			(end -1.8 1.5)
			(stroke
				(width 0.15)
				(type solid)
			)
			(layer "B.SilkS")
		)
		(fp_rect
			(start -2.1 2.6)
			(end 2.1 -2.6)
			(stroke
				(width 0.05)
				(type solid)
			)
			(fill none)
			(layer "B.CrtYd")
		)
		(fp_line
			(start -1.801 1.25)
			(end -1.051 2)
			(stroke
				(width 0.15)
				(type solid)
			)
			(layer "B.Fab")
		)
		(fp_rect
			(start 1.8 -2.048)
			(end -1.8 2)
			(stroke
				(width 0.15)
				(type solid)
			)
			(fill none)
			(layer "B.Fab")
		)
		(fp_text user "~"
			(at -0.31 -2.7 0)
			(unlocked yes)
			(layer "B.SilkS")
			(effects
				(font
					(size 0.7 0.7)
					(thickness 0.15)
				)
				(justify left bottom mirror)
			)
		)
		(fp_text user "${REFERENCE}"
			(at -2.1 -4.599 0)
			(layer "B.Fab")
			(hide yes)
			(effects
				(font
					(size 0.7 0.7)
					(thickness 0.15)
				)
				(justify left bottom mirror)
			)
		)
		(fp_text user "License: Apache-2.0"
			(at -2.1 -6.599 0)
			(layer "B.Fab")
			(hide yes)
			(effects
				(font
					(size 0.7 0.7)
					(thickness 0.15)
				)
				(justify left bottom mirror)
			)
		)
		(fp_text user "Author: Antmicro"
			(at -2.1 -5.599 0)
			(layer "B.Fab")
			(hide yes)
			(effects
				(font
					(size 0.7 0.7)
					(thickness 0.15)
				)
				(justify left bottom mirror)
			)
		)
		(pad "1" smd roundrect
			(at -1.27 1.85 90)
			(size 1.4 0.48)
			(layers "B.Cu" "B.Paste" "B.Mask")
			(roundrect_rratio 0.25)
			(net 148 "Net-(D12-Pad1)")
			(pinfunction "1")
			(pintype "passive")
		)
		(pad "2" smd roundrect
			(at 1.27 1.85 90)
			(size 1.4 0.48)
			(layers "B.Cu" "B.Paste" "B.Mask")
			(roundrect_rratio 0.25)
			(net 149 "Net-(D12-Pad2)")
			(pinfunction "2")
			(pintype "passive")
		)
		(pad "3" smd roundrect
			(at -1.27 -1.85 90)
			(size 1.4 0.48)
			(layers "B.Cu" "B.Paste" "B.Mask")
			(roundrect_rratio 0.25)
			(net 124 "/Ethernet/PAIR_910")
			(pinfunction "3")
			(pintype "passive")
		)
		(pad "4" smd roundrect
			(at 1.27 -1.85 90)
			(size 1.4 0.48)
			(layers "B.Cu" "B.Paste" "B.Mask")
			(roundrect_rratio 0.25)
			(net 123 "/Ethernet/PAIR_78")
			(pinfunction "4")
			(pintype "passive")
		)
	)
	(footprint "antmicro-footprints:TP_SMD_0.75mm"
		(layer "B.Cu")
		(at 98.14999 103.5508 180)
		(property "Reference" "TP43"
			(at -0.20001 -0.2992 90)
			(layer "B.SilkS")
			(effects
				(font
					(size 0.7 0.7)
					(thickness 0.15)
				)
				(justify left bottom mirror)
			)
		)
		(property "Value" "TP_0.75mm_SMD"
			(at 0 -1.2 0)
			(layer "B.Fab")
			(effects
				(font
					(size 0.7 0.7)
					(thickness 0.15)
				)
				(justify left bottom mirror)
			)
		)
		(property "Footprint" "antmicro-footprints:TP_SMD_0.75mm"
			(at 0 0 180)
			(layer "F.Fab")
			(hide yes)
			(effects
				(font
					(size 1.27 1.27)
					(thickness 0.15)
				)
			)
		)
		(property "Author" "Antmicro"
			(at 196.29998 207.1016 0)
			(layer "B.Fab")
			(hide yes)
			(effects
				(font
					(size 1 1)
					(thickness 0.15)
				)
				(justify mirror)
			)
		)
		(property "License" "Apache-2.0"
			(at 196.29998 207.1016 0)
			(layer "B.Fab")
			(hide yes)
			(effects
				(font
					(size 1 1)
					(thickness 0.15)
				)
				(justify mirror)
			)
		)
		(property "MPN" ""
			(at 196.29998 207.1016 0)
			(layer "B.Fab")
			(hide yes)
			(effects
				(font
					(size 1 1)
					(thickness 0.15)
				)
				(justify mirror)
			)
		)
		(property "Manufacturer" ""
			(at 196.29998 207.1016 0)
			(layer "B.Fab")
			(hide yes)
			(effects
				(font
					(size 1 1)
					(thickness 0.15)
				)
				(justify mirror)
			)
		)
		(sheetname "CSI")
		(sheetfile "csi.kicad_sch")
		(attr exclude_from_pos_files exclude_from_bom)
		(fp_circle
			(center 0 0)
			(end 0.475 0)
			(stroke
				(width 0.05)
				(type default)
			)
			(fill none)
			(layer "B.CrtYd")
		)
		(fp_text user "License: Apache-2.0"
			(at -0.4 -5.101 0)
			(layer "B.Fab")
			(hide yes)
			(effects
				(font
					(size 0.7 0.7)
					(thickness 0.15)
				)
				(justify left bottom mirror)
			)
		)
		(fp_text user "Author: Antmicro"
			(at -0.4 -3.901 0)
			(layer "B.Fab")
			(hide yes)
			(effects
				(font
					(size 0.7 0.7)
					(thickness 0.15)
				)
				(justify left bottom mirror)
			)
		)
		(fp_text user "${REFERENCE}"
			(at -0.4 -2.7 0)
			(layer "B.Fab")
			(hide yes)
			(effects
				(font
					(size 0.7 0.7)
					(thickness 0.15)
				)
				(justify left bottom mirror)
			)
		)
		(pad "1" smd circle
			(at 0 0 180)
			(size 0.75 0.75)
			(layers "B.Cu" "B.Mask")
			(net 544 "/CSI/MUX_I2C_7_SCL")
			(pinfunction "1")
			(pintype "passive")
		)
	)
	(footprint "antmicro-footprints:C_0402_1005Metric"
		(layer "B.Cu")
		(at 94.149999 85.85 90)
		(descr "Capacitor SMD 0402")
		(tags "capacitor SMD 0402")
		(property "Reference" "C47"
			(at -0.8 0.620001 -90)
			(layer "B.SilkS")
			(effects
				(font
					(size 0.7 0.7)
					(thickness 0.15)
				)
				(justify left bottom mirror)
			)
		)
		(property "Value" "C_1u_0402"
			(at 0 -1.4 -90)
			(layer "B.Fab")
			(effects
				(font
					(size 0.7 0.7)
					(thickness 0.15)
				)
				(justify left bottom mirror)
			)
		)
		(property "Footprint" "antmicro-footprints:C_0402_1005Metric"
			(at 0 0 90)
			(layer "F.Fab")
			(hide yes)
			(effects
				(font
					(size 1.27 1.27)
					(thickness 0.15)
				)
			)
		)
		(property "Datasheet" "https://product.tdk.com/en/search/capacitor/ceramic/mlcc/info?part_no=C1005X6S1A105K050BC"
			(at 0 0 90)
			(layer "F.Fab")
			(hide yes)
			(effects
				(font
					(size 1.27 1.27)
					(thickness 0.15)
				)
			)
		)
		(property "Author" "Antmicro"
			(at 179.999999 -8.299999 0)
			(layer "B.Fab")
			(hide yes)
			(effects
				(font
					(size 1 1)
					(thickness 0.15)
				)
				(justify mirror)
			)
		)
		(property "Dielectric" ""
			(at 179.999999 -8.299999 0)
			(layer "B.Fab")
			(hide yes)
			(effects
				(font
					(size 1 1)
					(thickness 0.15)
				)
				(justify mirror)
			)
		)
		(property "License" "Apache-2.0"
			(at 179.999999 -8.299999 0)
			(layer "B.Fab")
			(hide yes)
			(effects
				(font
					(size 1 1)
					(thickness 0.15)
				)
				(justify mirror)
			)
		)
		(property "MPN" "C1005X6S1A105K050BC"
			(at 179.999999 -8.299999 0)
			(layer "B.Fab")
			(hide yes)
			(effects
				(font
					(size 1 1)
					(thickness 0.15)
				)
				(justify mirror)
			)
		)
		(property "Manufacturer" "TDK"
			(at 179.999999 -8.299999 0)
			(layer "B.Fab")
			(hide yes)
			(effects
				(font
					(size 1 1)
					(thickness 0.15)
				)
				(justify mirror)
			)
		)
		(property "Val" "1u"
			(at 179.999999 -8.299999 0)
			(layer "B.Fab")
			(hide yes)
			(effects
				(font
					(size 1 1)
					(thickness 0.15)
				)
				(justify mirror)
			)
		)
		(property "Voltage" ""
			(at 179.999999 -8.299999 0)
			(layer "B.Fab")
			(hide yes)
			(effects
				(font
					(size 1 1)
					(thickness 0.15)
				)
				(justify mirror)
			)
		)
		(sheetname "HDMI")
		(sheetfile "hdmi.kicad_sch")
		(attr smd)
		(fp_rect
			(start -0.925 0.47)
			(end 0.925 -0.47)
			(stroke
				(width 0.05)
				(type default)
			)
			(fill none)
			(layer "B.CrtYd")
		)
		(fp_line
			(start 0.504 -0.248)
			(end 0.504 0.25)
			(stroke
				(width 0.15)
				(type solid)
			)
			(layer "B.Fab")
		)
		(fp_line
			(start -0.494 -0.248)
			(end 0.504 -0.248)
			(stroke
				(width 0.15)
				(type solid)
			)
			(layer "B.Fab")
		)
		(fp_line
			(start 0.504 0.25)
			(end -0.494 0.25)
			(stroke
				(width 0.15)
				(type solid)
			)
			(layer "B.Fab")
		)
		(fp_line
			(start -0.494 0.25)
			(end -0.494 -0.248)
			(stroke
				(width 0.15)
				(type solid)
			)
			(layer "B.Fab")
		)
		(fp_text user "${REFERENCE}"
			(at -0.932 -3.168 -90)
			(layer "B.Fab")
			(hide yes)
			(effects
				(font
					(size 0.7 0.7)
					(thickness 0.15)
				)
				(justify left bottom mirror)
			)
		)
		(fp_text user "Author: Antmicro"
			(at -0.932 -4.17 -90)
			(layer "B.Fab")
			(hide yes)
			(effects
				(font
					(size 0.7 0.7)
					(thickness 0.15)
				)
				(justify left bottom mirror)
			)
		)
		(fp_text user "License: Apache-2.0"
			(at -0.932 -5.17 -90)
			(layer "B.Fab")
			(hide yes)
			(effects
				(font
					(size 0.7 0.7)
					(thickness 0.15)
				)
				(justify left bottom mirror)
			)
		)
		(pad "1" smd roundrect
			(at -0.48 0 90)
			(size 0.59 0.64)
			(layers "B.Cu" "B.Paste" "B.Mask")
			(roundrect_rratio 0.25)
			(net 1 "GND")
			(pintype "passive")
		)
		(pad "2" smd roundrect
			(at 0.48 0 90)
			(size 0.59 0.64)
			(layers "B.Cu" "B.Paste" "B.Mask")
			(roundrect_rratio 0.25)
			(net 87 "+3V3")
			(pintype "passive")
		)
	)
	(footprint "antmicro-footprints:C_0402_1005Metric"
		(layer "B.Cu")
		(at 62.4 109.2 -90)
		(descr "Capacitor SMD 0402")
		(tags "capacitor SMD 0402")
		(property "Reference" "C136"
			(at 0.95 -0.3 90)
			(layer "B.SilkS")
			(effects
				(font
					(size 0.7 0.7)
					(thickness 0.15)
				)
				(justify left bottom mirror)
			)
		)
		(property "Value" "C_4u7_25V_0402"
			(at 0 -1.4 90)
			(layer "B.Fab")
			(effects
				(font
					(size 0.7 0.7)
					(thickness 0.15)
				)
				(justify left bottom mirror)
			)
		)
		(property "Footprint" "antmicro-footprints:C_0402_1005Metric"
			(at 0 0 -90)
			(layer "F.Fab")
			(hide yes)
			(effects
				(font
					(size 1.27 1.27)
					(thickness 0.15)
				)
			)
		)
		(property "Datasheet" "https://www.murata.com/products/productdetail?partno=GRM155C61E475ME15%23"
			(at 0 0 -90)
			(layer "F.Fab")
			(hide yes)
			(effects
				(font
					(size 1.27 1.27)
					(thickness 0.15)
				)
			)
		)
		(property "Author" "Antmicro"
			(at -46.8 171.6 0)
			(layer "B.Fab")
			(hide yes)
			(effects
				(font
					(size 1 1)
					(thickness 0.15)
				)
				(justify mirror)
			)
		)
		(property "Dielectric" "X5S"
			(at -46.8 171.6 0)
			(layer "B.Fab")
			(hide yes)
			(effects
				(font
					(size 1 1)
					(thickness 0.15)
				)
				(justify mirror)
			)
		)
		(property "License" "Apache-2.0"
			(at -46.8 171.6 0)
			(layer "B.Fab")
			(hide yes)
			(effects
				(font
					(size 1 1)
					(thickness 0.15)
				)
				(justify mirror)
			)
		)
		(property "MPN" "GRM155C61E475ME15J"
			(at -46.8 171.6 0)
			(layer "B.Fab")
			(hide yes)
			(effects
				(font
					(size 1 1)
					(thickness 0.15)
				)
				(justify mirror)
			)
		)
		(property "Manufacturer" "Murata"
			(at -46.8 171.6 0)
			(layer "B.Fab")
			(hide yes)
			(effects
				(font
					(size 1 1)
					(thickness 0.15)
				)
				(justify mirror)
			)
		)
		(property "Val" "4u7"
			(at -46.8 171.6 0)
			(layer "B.Fab")
			(hide yes)
			(effects
				(font
					(size 1 1)
					(thickness 0.15)
				)
				(justify mirror)
			)
		)
		(property "Voltage" "25V"
			(at -46.8 171.6 0)
			(layer "B.Fab")
			(hide yes)
			(effects
				(font
					(size 1 1)
					(thickness 0.15)
				)
				(justify mirror)
			)
		)
		(sheetname "USB Debug, DP")
		(sheetfile "usb.kicad_sch")
		(attr smd)
		(fp_rect
			(start -0.925 0.47)
			(end 0.925 -0.47)
			(stroke
				(width 0.05)
				(type default)
			)
			(fill none)
			(layer "B.CrtYd")
		)
		(fp_line
			(start -0.494 0.25)
			(end -0.494 -0.248)
			(stroke
				(width 0.15)
				(type solid)
			)
			(layer "B.Fab")
		)
		(fp_line
			(start 0.504 0.25)
			(end -0.494 0.25)
			(stroke
				(width 0.15)
				(type solid)
			)
			(layer "B.Fab")
		)
		(fp_line
			(start -0.494 -0.248)
			(end 0.504 -0.248)
			(stroke
				(width 0.15)
				(type solid)
			)
			(layer "B.Fab")
		)
		(fp_line
			(start 0.504 -0.248)
			(end 0.504 0.25)
			(stroke
				(width 0.15)
				(type solid)
			)
			(layer "B.Fab")
		)
		(fp_text user "${REFERENCE}"
			(at -0.932 -3.168 90)
			(layer "B.Fab")
			(hide yes)
			(effects
				(font
					(size 0.7 0.7)
					(thickness 0.15)
				)
				(justify left bottom mirror)
			)
		)
		(fp_text user "Author: Antmicro"
			(at -0.932 -4.17 90)
			(layer "B.Fab")
			(hide yes)
			(effects
				(font
					(size 0.7 0.7)
					(thickness 0.15)
				)
				(justify left bottom mirror)
			)
		)
		(fp_text user "License: Apache-2.0"
			(at -0.932 -5.17 90)
			(layer "B.Fab")
			(hide yes)
			(effects
				(font
					(size 0.7 0.7)
					(thickness 0.15)
				)
				(justify left bottom mirror)
			)
		)
		(pad "1" smd roundrect
			(at -0.48 0 270)
			(size 0.59 0.64)
			(layers "B.Cu" "B.Paste" "B.Mask")
			(roundrect_rratio 0.25)
			(net 480 "USBPD1_HV")
			(pintype "passive")
		)
		(pad "2" smd roundrect
			(at 0.48 0 270)
			(size 0.59 0.64)
			(layers "B.Cu" "B.Paste" "B.Mask")
			(roundrect_rratio 0.25)
			(net 1 "GND")
			(pintype "passive")
		)
	)
	(footprint "antmicro-footprints:TP_SMD_0.75mm"
		(layer "B.Cu")
		(at 99.14999 103.5508 180)
		(property "Reference" "TP42"
			(at 0 0.6 0)
			(layer "B.SilkS")
			(hide yes)
			(effects
				(font
					(size 0.7 0.7)
					(thickness 0.15)
				)
				(justify left bottom mirror)
			)
		)
		(property "Value" "TP_0.75mm_SMD"
			(at 0 -1.2 0)
			(layer "B.Fab")
			(effects
				(font
					(size 0.7 0.7)
					(thickness 0.15)
				)
				(justify left bottom mirror)
			)
		)
		(property "Footprint" "antmicro-footprints:TP_SMD_0.75mm"
			(at 0 0 180)
			(layer "F.Fab")
			(hide yes)
			(effects
				(font
					(size 1.27 1.27)
					(thickness 0.15)
				)
			)
		)
		(property "Author" "Antmicro"
			(at 198.29998 207.1016 0)
			(layer "B.Fab")
			(hide yes)
			(effects
				(font
					(size 1 1)
					(thickness 0.15)
				)
				(justify mirror)
			)
		)
		(property "License" "Apache-2.0"
			(at 198.29998 207.1016 0)
			(layer "B.Fab")
			(hide yes)
			(effects
				(font
					(size 1 1)
					(thickness 0.15)
				)
				(justify mirror)
			)
		)
		(property "MPN" ""
			(at 198.29998 207.1016 0)
			(layer "B.Fab")
			(hide yes)
			(effects
				(font
					(size 1 1)
					(thickness 0.15)
				)
				(justify mirror)
			)
		)
		(property "Manufacturer" ""
			(at 198.29998 207.1016 0)
			(layer "B.Fab")
			(hide yes)
			(effects
				(font
					(size 1 1)
					(thickness 0.15)
				)
				(justify mirror)
			)
		)
		(sheetname "CSI")
		(sheetfile "csi.kicad_sch")
		(attr exclude_from_pos_files exclude_from_bom)
		(fp_circle
			(center 0 0)
			(end 0.475 0)
			(stroke
				(width 0.05)
				(type default)
			)
			(fill none)
			(layer "B.CrtYd")
		)
		(fp_text user "${REFERENCE}"
			(at -0.4 -2.7 0)
			(layer "B.Fab")
			(hide yes)
			(effects
				(font
					(size 0.7 0.7)
					(thickness 0.15)
				)
				(justify left bottom mirror)
			)
		)
		(fp_text user "License: Apache-2.0"
			(at -0.4 -5.101 0)
			(layer "B.Fab")
			(hide yes)
			(effects
				(font
					(size 0.7 0.7)
					(thickness 0.15)
				)
				(justify left bottom mirror)
			)
		)
		(fp_text user "Author: Antmicro"
			(at -0.4 -3.901 0)
			(layer "B.Fab")
			(hide yes)
			(effects
				(font
					(size 0.7 0.7)
					(thickness 0.15)
				)
				(justify left bottom mirror)
			)
		)
		(pad "1" smd circle
			(at 0 0 180)
			(size 0.75 0.75)
			(layers "B.Cu" "B.Mask")
			(net 543 "/CSI/MUX_I2C_7_SDA")
			(pinfunction "1")
			(pintype "passive")
		)
	)
	(footprint "antmicro-footprints:QFN-16-1EP_4x4mm_P0.65mm"
		(layer "B.Cu")
		(at 53.4 113.25 180)
		(property "Reference" "U5"
			(at -1.47 2.6 0)
			(layer "B.SilkS")
			(effects
				(font
					(size 0.7 0.7)
					(thickness 0.15)
				)
				(justify left bottom mirror)
			)
		)
		(property "Value" "FT230X_QFN"
			(at 0 -3.3 0)
			(layer "B.Fab")
			(effects
				(font
					(size 0.7 0.7)
					(thickness 0.15)
				)
				(justify left bottom mirror)
			)
		)
		(property "Footprint" "antmicro-footprints:QFN-16-1EP_4x4mm_P0.65mm"
			(at 0 0 180)
			(layer "F.Fab")
			(hide yes)
			(effects
				(font
					(size 1.27 1.27)
					(thickness 0.15)
				)
			)
		)
		(property "Datasheet" "https://ftdichip.com/wp-content/uploads/2021/10/DS_FT230X.pdf"
			(at 0 0 180)
			(layer "F.Fab")
			(hide yes)
			(effects
				(font
					(size 1.27 1.27)
					(thickness 0.15)
				)
			)
		)
		(property "Author" "Antmicro"
			(at 106.8 226.5 0)
			(layer "B.Fab")
			(hide yes)
			(effects
				(font
					(size 1 1)
					(thickness 0.15)
				)
				(justify mirror)
			)
		)
		(property "License" "Apache-2.0"
			(at 106.8 226.5 0)
			(layer "B.Fab")
			(hide yes)
			(effects
				(font
					(size 1 1)
					(thickness 0.15)
				)
				(justify mirror)
			)
		)
		(property "MPN" "FT230XQ-R"
			(at 106.8 226.5 0)
			(layer "B.Fab")
			(hide yes)
			(effects
				(font
					(size 1 1)
					(thickness 0.15)
				)
				(justify mirror)
			)
		)
		(property "Manufacturer" "FTDI Chip"
			(at 106.8 226.5 0)
			(layer "B.Fab")
			(hide yes)
			(effects
				(font
					(size 1 1)
					(thickness 0.15)
				)
				(justify mirror)
			)
		)
		(sheetname "USB Debug, DP")
		(sheetfile "usb.kicad_sch")
		(attr smd)
		(fp_line
			(start 2.1 2.101)
			(end 1.499 2.101)
			(stroke
				(width 0.15)
				(type solid)
			)
			(layer "B.SilkS")
		)
		(fp_line
			(start 2.1 1.401)
			(end 2.1 2.101)
			(stroke
				(width 0.15)
				(type solid)
			)
			(layer "B.SilkS")
		)
		(fp_line
			(start 2.1 -1.398)
			(end 2.1 -2.1)
			(stroke
				(width 0.15)
				(type solid)
			)
			(layer "B.SilkS")
		)
		(fp_line
			(start 2.1 -2.1)
			(end 1.499 -2.1)
			(stroke
				(width 0.15)
				(type solid)
			)
			(layer "B.SilkS")
		)
		(fp_line
			(start -1.5 -2.1)
			(end -2.101 -2.1)
			(stroke
				(width 0.15)
				(type solid)
			)
			(layer "B.SilkS")
		)
		(fp_line
			(start -2.1 2.1)
			(end -1.4 2.1)
			(stroke
				(width 0.15)
				(type solid)
			)
			(layer "B.SilkS")
		)
		(fp_line
			(start -2.101 1.4)
			(end -2.1 2.1)
			(stroke
				(width 0.15)
				(type solid)
			)
			(layer "B.SilkS")
		)
		(fp_line
			(start -2.101 -2.1)
			(end -2.101 -1.398)
			(stroke
				(width 0.15)
				(type solid)
			)
			(layer "B.SilkS")
		)
		(fp_circle
			(center -2.35 1.4)
			(end -2.3 1.4)
			(stroke
				(width 0.15)
				(type solid)
			)
			(fill solid)
			(layer "B.SilkS")
		)
		(fp_rect
			(start -2.35 2.35)
			(end 2.35 -2.35)
			(stroke
				(width 0.05)
				(type solid)
			)
			(fill none)
			(layer "B.CrtYd")
		)
		(fp_line
			(start -2 1.5)
			(end -1.5 2)
			(stroke
				(width 0.15)
				(type solid)
			)
			(layer "B.Fab")
		)
		(fp_rect
			(start 2 -2)
			(end -2 2)
			(stroke
				(width 0.15)
				(type solid)
			)
			(fill none)
			(layer "B.Fab")
		)
		(fp_text user "Author: Antmicro"
			(at -2.35 -6.799 0)
			(layer "B.Fab")
			(hide yes)
			(effects
				(font
					(size 0.7 0.7)
					(thickness 0.15)
				)
				(justify left bottom mirror)
			)
		)
		(fp_text user "License: Apache-2.0"
			(at -2.35 -7.999 0)
			(layer "B.Fab")
			(hide yes)
			(effects
				(font
					(size 0.7 0.7)
					(thickness 0.15)
				)
				(justify left bottom mirror)
			)
		)
		(fp_text user "${REFERENCE}"
			(at -2.35 -5.599 0)
			(layer "B.Fab")
			(hide yes)
			(effects
				(font
					(size 0.7 0.7)
					(thickness 0.15)
				)
				(justify left bottom mirror)
			)
		)
		(pad "1" smd rect
			(at -1.9 0.975 180)
			(size 0.8 0.4)
			(layers "B.Cu" "B.Paste" "B.Mask")
			(net 185 "/USB Debug, DP/FTDI_3V3")
			(pinfunction "V_{CCIO}")
			(pintype "power_in")
		)
		(pad "2" smd rect
			(at -1.9 0.325 180)
			(size 0.8 0.4)
			(layers "B.Cu" "B.Paste" "B.Mask")
			(net 647 "Net-(U5-RXD)")
			(pinfunction "RXD")
			(pintype "input")
		)
		(pad "3" smd rect
			(at -1.9 -0.325 180)
			(size 0.8 0.4)
			(layers "B.Cu" "B.Paste" "B.Mask")
			(net 1 "GND")
			(pinfunction "GND")
			(pintype "passive")
		)
		(pad "4" smd rect
			(at -1.9 -0.975 180)
			(size 0.8 0.4)
			(layers "B.Cu" "B.Paste" "B.Mask")
			(net 649 "Net-(U5-~{CTS})")
			(pinfunction "~{CTS}")
			(pintype "input")
		)
		(pad "5" smd rect
			(at -0.975 -1.9 180)
			(size 0.4 0.8)
			(layers "B.Cu" "B.Paste" "B.Mask")
			(net 271 "/USB Debug, DP/FTDI_LED_TX")
			(pinfunction "CBUS2")
			(pintype "bidirectional")
		)
		(pad "6" smd rect
			(at -0.325 -1.9 180)
			(size 0.4 0.8)
			(layers "B.Cu" "B.Paste" "B.Mask")
			(net 313 "/USB Debug, DP/USB_FTDI_P")
			(pinfunction "D+")
			(pintype "input")
		)
		(pad "7" smd rect
			(at 0.325 -1.9 180)
			(size 0.4 0.8)
			(layers "B.Cu" "B.Paste" "B.Mask")
			(net 312 "/USB Debug, DP/USB_FTDI_N")
			(pinfunction "D-")
			(pintype "input")
		)
		(pad "8" smd rect
			(at 0.975 -1.9 180)
			(size 0.4 0.8)
			(layers "B.Cu" "B.Paste" "B.Mask")
			(net 185 "/USB Debug, DP/FTDI_3V3")
			(pinfunction "3V3_{OUT}")
			(pintype "passive")
		)
		(pad "9" smd rect
			(at 1.9 -0.975 180)
			(size 0.8 0.4)
			(layers "B.Cu" "B.Paste" "B.Mask")
			(net 126 "Net-(U5-~{RESET})")
			(pinfunction "~{RESET}")
			(pintype "input")
		)
		(pad "10" smd rect
			(at 1.9 -0.325 180)
			(size 0.8 0.4)
			(layers "B.Cu" "B.Paste" "B.Mask")
			(net 185 "/USB Debug, DP/FTDI_3V3")
			(pinfunction "V_{CC}")
			(pintype "power_in")
		)
		(pad "11" smd rect
			(at 1.9 0.325 180)
			(size 0.8 0.4)
			(layers "B.Cu" "B.Paste" "B.Mask")
			(net 272 "/USB Debug, DP/FTDI_LED_RX")
			(pinfunction "CBUS1")
			(pintype "bidirectional")
		)
		(pad "12" smd rect
			(at 1.9 0.975 180)
			(size 0.8 0.4)
			(layers "B.Cu" "B.Paste" "B.Mask")
			(net 780 "/USB Debug, DP/FTDI_CBUS0{slash}SDA")
			(pinfunction "CBUS0")
			(pintype "bidirectional")
		)
		(pad "13" smd rect
			(at 0.975 1.9 180)
			(size 0.4 0.8)
			(layers "B.Cu" "B.Paste" "B.Mask")
			(net 1 "GND")
			(pinfunction "GND")
			(pintype "power_in")
		)
		(pad "14" smd rect
			(at 0.325 1.9 180)
			(size 0.4 0.8)
			(layers "B.Cu" "B.Paste" "B.Mask")
			(net 398 "/USB Debug, DP/FTDI_CBUS3{slash}SCL")
			(pinfunction "CBUS3")
			(pintype "bidirectional")
		)
		(pad "15" smd rect
			(at -0.325 1.9 180)
			(size 0.4 0.8)
			(layers "B.Cu" "B.Paste" "B.Mask")
			(net 646 "Net-(U5-TXD)")
			(pinfunction "TXD")
			(pintype "output")
		)
		(pad "16" smd rect
			(at -0.975 1.9 180)
			(size 0.4 0.8)
			(layers "B.Cu" "B.Paste" "B.Mask")
			(net 648 "Net-(U5-~{RTS})")
			(pinfunction "~{RTS}")
			(pintype "output")
		)
		(pad "17" smd rect
			(at 0 0 180)
			(size 2.3 2.3)
			(layers "B.Cu" "B.Paste" "B.Mask")
			(net 1 "GND")
			(pinfunction "GND")
			(pintype "passive")
		)
	)
	(footprint "antmicro-footprints:SOT-23-3"
		(layer "B.Cu")
		(at 58.885627 92.05 -90)
		(property "Reference" "Q6"
			(at 1.545339 -1.864373 0)
			(layer "B.SilkS")
			(effects
				(font
					(size 0.7 0.7)
					(thickness 0.15)
				)
				(justify left top mirror)
			)
		)
		(property "Value" "SSM3J332R"
			(at -1.9 -2.7 90)
			(layer "B.Fab")
			(effects
				(font
					(size 0.7 0.7)
					(thickness 0.15)
				)
				(justify left top mirror)
			)
		)
		(property "Footprint" "antmicro-footprints:SOT-23-3"
			(at 0 0 90)
			(layer "B.Fab")
			(hide yes)
			(effects
				(font
					(size 1.27 1.27)
					(thickness 0.15)
				)
				(justify mirror)
			)
		)
		(property "Datasheet" "https://www.mouser.com/datasheet/2/408/SSM3J332R_datasheet_en_20181015-1150575.pdf"
			(at 0 0 90)
			(layer "B.Fab")
			(hide yes)
			(effects
				(font
					(size 1.27 1.27)
					(thickness 0.15)
				)
				(justify mirror)
			)
		)
		(property "MPN" "SSM3J332R,LF"
			(at 0 0 -90)
			(unlocked yes)
			(layer "B.Fab")
			(hide yes)
			(effects
				(font
					(size 1 1)
					(thickness 0.15)
				)
				(justify mirror)
			)
		)
		(property "Manufacturer" "Toshiba"
			(at 0 0 -90)
			(unlocked yes)
			(layer "B.Fab")
			(hide yes)
			(effects
				(font
					(size 1 1)
					(thickness 0.15)
				)
				(justify mirror)
			)
		)
		(property "Author" "Antmicro"
			(at 0 0 -90)
			(unlocked yes)
			(layer "B.Fab")
			(hide yes)
			(effects
				(font
					(size 1 1)
					(thickness 0.15)
				)
				(justify mirror)
			)
		)
		(property "License" "Apache-2.0"
			(at 0 0 -90)
			(unlocked yes)
			(layer "B.Fab")
			(hide yes)
			(effects
				(font
					(size 1 1)
					(thickness 0.15)
				)
				(justify mirror)
			)
		)
		(sheetname "Supply")
		(sheetfile "supply.kicad_sch")
		(attr smd)
		(fp_line
			(start -0.7 1.5)
			(end 0.7 1.5)
			(stroke
				(width 0.15)
				(type solid)
			)
			(layer "B.SilkS")
		)
		(fp_line
			(start -0.7 1.5)
			(end -0.85 1.35)
			(stroke
				(width 0.15)
				(type solid)
			)
			(layer "B.SilkS")
		)
		(fp_line
			(start 0.7 1.5)
			(end 0.7 0.4)
			(stroke
				(width 0.15)
				(type solid)
			)
			(layer "B.SilkS")
		)
		(fp_line
			(start -0.85 1.35)
			(end -1.45 1.35)
			(stroke
				(width 0.15)
				(type solid)
			)
			(layer "B.SilkS")
		)
		(fp_line
			(start -0.7 -1.35)
			(end -0.7 -1.5)
			(stroke
				(width 0.15)
				(type solid)
			)
			(layer "B.SilkS")
		)
		(fp_line
			(start -0.7 -1.5)
			(end 0.7 -1.5)
			(stroke
				(width 0.15)
				(type solid)
			)
			(layer "B.SilkS")
		)
		(fp_line
			(start 0.7 -1.5)
			(end 0.7 -0.4)
			(stroke
				(width 0.15)
				(type solid)
			)
			(layer "B.SilkS")
		)
		(fp_line
			(start 0.825 1.6)
			(end -0.9 1.6)
			(stroke
				(width 0.05)
				(type solid)
			)
			(layer "B.CrtYd")
		)
		(fp_line
			(start -1.75 1.4)
			(end -0.9 1.4)
			(stroke
				(width 0.05)
				(type solid)
			)
			(layer "B.CrtYd")
		)
		(fp_line
			(start -1.75 1.4)
			(end -1.75 0.5)
			(stroke
				(width 0.05)
				(type solid)
			)
			(layer "B.CrtYd")
		)
		(fp_line
			(start -0.9 1.4)
			(end -0.9 1.6)
			(stroke
				(width 0.05)
				(type solid)
			)
			(layer "B.CrtYd")
		)
		(fp_line
			(start -1.75 0.5)
			(end -0.85 0.5)
			(stroke
				(width 0.05)
				(type solid)
			)
			(layer "B.CrtYd")
		)
		(fp_line
			(start -0.85 0.5)
			(end -0.85 -0.5)
			(stroke
				(width 0.05)
				(type solid)
			)
			(layer "B.CrtYd")
		)
		(fp_line
			(start 0.825 0.45)
			(end 0.825 1.6)
			(stroke
				(width 0.05)
				(type solid)
			)
			(layer "B.CrtYd")
		)
		(fp_line
			(start 1.75 0.45)
			(end 0.825 0.45)
			(stroke
				(width 0.05)
				(type solid)
			)
			(layer "B.CrtYd")
		)
		(fp_line
			(start 0.85 -0.45)
			(end 1.75 -0.45)
			(stroke
				(width 0.05)
				(type solid)
			)
			(layer "B.CrtYd")
		)
		(fp_line
			(start 1.75 -0.45)
			(end 1.75 0.45)
			(stroke
				(width 0.05)
				(type solid)
			)
			(layer "B.CrtYd")
		)
		(fp_line
			(start -1.75 -0.5)
			(end -1.75 -1.4)
			(stroke
				(width 0.05)
				(type solid)
			)
			(layer "B.CrtYd")
		)
		(fp_line
			(start -0.85 -0.5)
			(end -1.75 -0.5)
			(stroke
				(width 0.05)
				(type solid)
			)
			(layer "B.CrtYd")
		)
		(fp_line
			(start -1.75 -1.4)
			(end -0.85 -1.4)
			(stroke
				(width 0.05)
				(type solid)
			)
			(layer "B.CrtYd")
		)
		(fp_line
			(start -0.85 -1.4)
			(end -0.85 -1.65)
			(stroke
				(width 0.05)
				(type solid)
			)
			(layer "B.CrtYd")
		)
		(fp_line
			(start -0.85 -1.65)
			(end 0.85 -1.65)
			(stroke
				(width 0.05)
				(type solid)
			)
			(layer "B.CrtYd")
		)
		(fp_line
			(start 0.85 -1.65)
			(end 0.85 -0.45)
			(stroke
				(width 0.05)
				(type solid)
			)
			(layer "B.CrtYd")
		)
		(fp_line
			(start 0.688 1.526)
			(end -0.437 1.526)
			(stroke
				(width 0.15)
				(type solid)
			)
			(layer "B.Fab")
		)
		(fp_line
			(start 0.688 1.52)
			(end 0.688 -1.519)
			(stroke
				(width 0.15)
				(type solid)
			)
			(layer "B.Fab")
		)
		(fp_line
			(start -0.712 1.325)
			(end -0.437 1.526)
			(stroke
				(width 0.15)
				(type solid)
			)
			(layer "B.Fab")
		)
		(fp_line
			(start 0.688 -1.519)
			(end -0.712 -1.519)
			(stroke
				(width 0.15)
				(type solid)
			)
			(layer "B.Fab")
		)
		(fp_line
			(start -0.712 -1.523)
			(end -0.712 1.325)
			(stroke
				(width 0.15)
				(type solid)
			)
			(layer "B.Fab")
		)
		(fp_text user "License: Apache-2.0"
			(at -1.8 -6.8 90)
			(layer "B.Fab")
			(hide yes)
			(effects
				(font
					(size 0.7 0.7)
					(thickness 0.15)
				)
				(justify left top mirror)
			)
		)
		(fp_text user "Author: Antmicro"
			(at -1.837 -5.3 90)
			(layer "B.Fab")
			(hide yes)
			(effects
				(font
					(size 0.7 0.7)
					(thickness 0.15)
				)
				(justify left top mirror)
			)
		)
		(fp_text user "${REFERENCE}"
			(at -1.837 -4 90)
			(layer "B.Fab")
			(hide yes)
			(effects
				(font
					(size 0.7 0.7)
					(thickness 0.15)
				)
				(justify left top mirror)
			)
		)
		(pad "1" smd roundrect
			(at -1.1 0.951 270)
			(size 1 0.6)
			(layers "B.Cu" "B.Paste" "B.Mask")
			(roundrect_rratio 0.15)
			(net 768 "/Supply/5V_GATE")
			(pinfunction "G")
			(pintype "bidirectional")
		)
		(pad "2" smd roundrect
			(at -1.1 -0.949 270)
			(size 1 0.6)
			(layers "B.Cu" "B.Paste" "B.Mask")
			(roundrect_rratio 0.15)
			(net 787 "+5V_SoM")
			(pinfunction "S")
			(pintype "bidirectional")
		)
		(pad "3" smd roundrect
			(at 1.1 0.0005 270)
			(size 1 0.6)
			(layers "B.Cu" "B.Paste" "B.Mask")
			(roundrect_rratio 0.15)
			(net 99 "+5V")
			(pinfunction "D")
			(pintype "bidirectional")
		)
	)
	(footprint "antmicro-footprints:R_0402_1005Metric"
		(layer "B.Cu")
		(at 87 112.6 90)
		(descr "Resistor SMD 0402")
		(tags "resistor SMD 0402")
		(property "Reference" "R215"
			(at 0.965 -3.6 -90)
			(layer "B.SilkS")
			(effects
				(font
					(size 0.7 0.7)
					(thickness 0.15)
				)
				(justify left bottom mirror)
			)
		)
		(property "Value" "R_0R_0402"
			(at 0 -1.4 -90)
			(layer "B.Fab")
			(effects
				(font
					(size 0.7 0.7)
					(thickness 0.15)
				)
				(justify left bottom mirror)
			)
		)
		(property "Footprint" "antmicro-footprints:R_0402_1005Metric"
			(at 0 0 90)
			(layer "F.Fab")
			(hide yes)
			(effects
				(font
					(size 1.27 1.27)
					(thickness 0.15)
				)
			)
		)
		(property "Datasheet" "https://industrial.panasonic.com/cdbs/www-data/pdf/RDA0000/AOA0000C301.pdf"
			(at 0 0 90)
			(layer "F.Fab")
			(hide yes)
			(effects
				(font
					(size 1.27 1.27)
					(thickness 0.15)
				)
			)
		)
		(property "Author" "Antmicro"
			(at 199.6 25.6 0)
			(layer "B.Fab")
			(hide yes)
			(effects
				(font
					(size 1 1)
					(thickness 0.15)
				)
				(justify mirror)
			)
		)
		(property "Current" "1A"
			(at 199.6 25.6 0)
			(layer "B.Fab")
			(hide yes)
			(effects
				(font
					(size 1 1)
					(thickness 0.15)
				)
				(justify mirror)
			)
		)
		(property "License" "Apache-2.0"
			(at 199.6 25.6 0)
			(layer "B.Fab")
			(hide yes)
			(effects
				(font
					(size 1 1)
					(thickness 0.15)
				)
				(justify mirror)
			)
		)
		(property "MPN" "ERJ2GE0R00X"
			(at 199.6 25.6 0)
			(layer "B.Fab")
			(hide yes)
			(effects
				(font
					(size 1 1)
					(thickness 0.15)
				)
				(justify mirror)
			)
		)
		(property "Manufacturer" "Panasonic"
			(at 199.6 25.6 0)
			(layer "B.Fab")
			(hide yes)
			(effects
				(font
					(size 1 1)
					(thickness 0.15)
				)
				(justify mirror)
			)
		)
		(property "Tolerance" ""
			(at 199.6 25.6 0)
			(layer "B.Fab")
			(hide yes)
			(effects
				(font
					(size 1 1)
					(thickness 0.15)
				)
				(justify mirror)
			)
		)
		(property "Val" "0R"
			(at 199.6 25.6 0)
			(layer "B.Fab")
			(hide yes)
			(effects
				(font
					(size 1 1)
					(thickness 0.15)
				)
				(justify mirror)
			)
		)
		(sheetname "Peripherals")
		(sheetfile "peripherals.kicad_sch")
		(attr smd)
		(fp_rect
			(start -0.925 0.47)
			(end 0.925 -0.47)
			(stroke
				(width 0.05)
				(type default)
			)
			(fill none)
			(layer "B.CrtYd")
		)
		(fp_rect
			(start -0.5 0.25)
			(end 0.5 -0.25)
			(stroke
				(width 0.15)
				(type solid)
			)
			(fill none)
			(layer "B.Fab")
		)
		(fp_text user "License: Apache-2.0"
			(at -0.95 -5.169 -90)
			(layer "B.Fab")
			(hide yes)
			(effects
				(font
					(size 0.7 0.7)
					(thickness 0.15)
				)
				(justify left bottom mirror)
			)
		)
		(fp_text user "${REFERENCE}"
			(at -0.95 -3.168 -90)
			(layer "B.Fab")
			(hide yes)
			(effects
				(font
					(size 0.7 0.7)
					(thickness 0.15)
				)
				(justify left bottom mirror)
			)
		)
		(fp_text user "Author: Antmicro"
			(at -0.95 -4.169 -90)
			(layer "B.Fab")
			(hide yes)
			(effects
				(font
					(size 0.7 0.7)
					(thickness 0.15)
				)
				(justify left bottom mirror)
			)
		)
		(pad "1" smd roundrect
			(at -0.48 0 90)
			(size 0.59 0.64)
			(layers "B.Cu" "B.Paste" "B.Mask")
			(roundrect_rratio 0.25)
			(net 251 "SYS_SDA")
			(pintype "passive")
		)
		(pad "2" smd roundrect
			(at 0.48 0 90)
			(size 0.59 0.64)
			(layers "B.Cu" "B.Paste" "B.Mask")
			(roundrect_rratio 0.25)
			(net 349 "/Peripherals/GPIOEX_I2C_SDA")
			(pintype "passive")
		)
	)
	(footprint "antmicro-footprints:R_0402_1005Metric"
		(layer "B.Cu")
		(at 136.8 124.06)
		(descr "Resistor SMD 0402")
		(tags "resistor SMD 0402")
		(property "Reference" "R191"
			(at 1.05 -0.41 0)
			(layer "B.SilkS")
			(effects
				(font
					(size 0.7 0.7)
					(thickness 0.15)
				)
				(justify left bottom mirror)
			)
		)
		(property "Value" "R_200R_0402"
			(at 0 -1.4 180)
			(layer "B.Fab")
			(effects
				(font
					(size 0.7 0.7)
					(thickness 0.15)
				)
				(justify left bottom mirror)
			)
		)
		(property "Footprint" "antmicro-footprints:R_0402_1005Metric"
			(at 0 0 0)
			(layer "F.Fab")
			(hide yes)
			(effects
				(font
					(size 1.27 1.27)
					(thickness 0.15)
				)
			)
		)
		(property "Datasheet" "https://www.bourns.com/docs/product-datasheets/cr.pdf"
			(at 0 0 0)
			(layer "F.Fab")
			(hide yes)
			(effects
				(font
					(size 1.27 1.27)
					(thickness 0.15)
				)
			)
		)
		(property "Author" "Antmicro"
			(at 0 0 0)
			(layer "B.Fab")
			(hide yes)
			(effects
				(font
					(size 1 1)
					(thickness 0.15)
				)
				(justify mirror)
			)
		)
		(property "License" "Apache-2.0"
			(at 0 0 0)
			(layer "B.Fab")
			(hide yes)
			(effects
				(font
					(size 1 1)
					(thickness 0.15)
				)
				(justify mirror)
			)
		)
		(property "MPN" "CR0402-FX-2000GLF"
			(at 0 0 0)
			(layer "B.Fab")
			(hide yes)
			(effects
				(font
					(size 1 1)
					(thickness 0.15)
				)
				(justify mirror)
			)
		)
		(property "Manufacturer" "Bourns"
			(at 0 0 0)
			(layer "B.Fab")
			(hide yes)
			(effects
				(font
					(size 1 1)
					(thickness 0.15)
				)
				(justify mirror)
			)
		)
		(property "Tolerance" "1%"
			(at 0 0 0)
			(layer "B.Fab")
			(hide yes)
			(effects
				(font
					(size 1 1)
					(thickness 0.15)
				)
				(justify mirror)
			)
		)
		(property "Val" "200R"
			(at 0 0 0)
			(layer "B.Fab")
			(hide yes)
			(effects
				(font
					(size 1 1)
					(thickness 0.15)
				)
				(justify mirror)
			)
		)
		(sheetname "Peripherals")
		(sheetfile "peripherals.kicad_sch")
		(attr smd)
		(fp_rect
			(start -0.925 0.47)
			(end 0.925 -0.47)
			(stroke
				(width 0.05)
				(type default)
			)
			(fill none)
			(layer "B.CrtYd")
		)
		(fp_rect
			(start -0.5 0.25)
			(end 0.5 -0.25)
			(stroke
				(width 0.15)
				(type solid)
			)
			(fill none)
			(layer "B.Fab")
		)
		(fp_text user "Author: Antmicro"
			(at -0.95 -4.169 180)
			(layer "B.Fab")
			(hide yes)
			(effects
				(font
					(size 0.7 0.7)
					(thickness 0.15)
				)
				(justify left bottom mirror)
			)
		)
		(fp_text user "License: Apache-2.0"
			(at -0.95 -5.169 180)
			(layer "B.Fab")
			(hide yes)
			(effects
				(font
					(size 0.7 0.7)
					(thickness 0.15)
				)
				(justify left bottom mirror)
			)
		)
		(fp_text user "${REFERENCE}"
			(at -0.95 -3.168 180)
			(layer "B.Fab")
			(hide yes)
			(effects
				(font
					(size 0.7 0.7)
					(thickness 0.15)
				)
				(justify left bottom mirror)
			)
		)
		(pad "1" smd roundrect
			(at -0.48 0)
			(size 0.59 0.64)
			(layers "B.Cu" "B.Paste" "B.Mask")
			(roundrect_rratio 0.25)
			(net 661 "Net-(D54-A)")
			(pintype "passive")
		)
		(pad "2" smd roundrect
			(at 0.48 0)
			(size 0.59 0.64)
			(layers "B.Cu" "B.Paste" "B.Mask")
			(roundrect_rratio 0.25)
			(net 662 "/Peripherals/I2C_CONN_3V3")
			(pintype "passive")
		)
	)
	(footprint "antmicro-footprints:USON-10_2.5x1mm_P0.5mm"
		(layer "B.Cu")
		(at 53.4 119 90)
		(descr "USON-10 2.5x1mm_ Pitch 0.5mm")
		(tags "USON-10 2.5x1mm Pitch 0.5mm")
		(property "Reference" "U11"
			(at 0.8 2.4 90)
			(layer "B.SilkS")
			(effects
				(font
					(size 0.7 0.7)
					(thickness 0.15)
				)
				(justify left bottom mirror)
			)
		)
		(property "Value" "TPD4E05U06QDQARQ1"
			(at 0.018 -2.499 -90)
			(layer "B.Fab")
			(effects
				(font
					(size 0.7 0.7)
					(thickness 0.15)
				)
				(justify left bottom mirror)
			)
		)
		(property "Footprint" "antmicro-footprints:USON-10_2.5x1mm_P0.5mm"
			(at 0 0 90)
			(layer "F.Fab")
			(hide yes)
			(effects
				(font
					(size 1.27 1.27)
					(thickness 0.15)
				)
			)
		)
		(property "Datasheet" "https://www.ti.com/lit/ds/symlink/tpd4e05u06-q1.pdf?HQS=dis-mous-null-mousermode-dsf-pf-null-wwe&ts=1663591265741&ref_url=https%253A%252F%252Fwww.mouser.com%252F"
			(at 0 0 90)
			(layer "F.Fab")
			(hide yes)
			(effects
				(font
					(size 1.27 1.27)
					(thickness 0.15)
				)
			)
		)
		(property "Author" "Antmicro"
			(at 172.4 65.6 0)
			(layer "B.Fab")
			(hide yes)
			(effects
				(font
					(size 1 1)
					(thickness 0.15)
				)
				(justify mirror)
			)
		)
		(property "License" "Apache-2.0"
			(at 172.4 65.6 0)
			(layer "B.Fab")
			(hide yes)
			(effects
				(font
					(size 1 1)
					(thickness 0.15)
				)
				(justify mirror)
			)
		)
		(property "MPN" "TPD4E05U06QDQARQ1"
			(at 172.4 65.6 0)
			(layer "B.Fab")
			(hide yes)
			(effects
				(font
					(size 1 1)
					(thickness 0.15)
				)
				(justify mirror)
			)
		)
		(property "Manufacturer" "Texas Instruments"
			(at 172.4 65.6 0)
			(layer "B.Fab")
			(hide yes)
			(effects
				(font
					(size 1 1)
					(thickness 0.15)
				)
				(justify mirror)
			)
		)
		(sheetname "USB Debug, DP")
		(sheetfile "usb.kicad_sch")
		(attr smd)
		(fp_line
			(start -0.5 -1.398)
			(end 0.498 -1.398)
			(stroke
				(width 0.15)
				(type solid)
			)
			(layer "B.SilkS")
		)
		(fp_line
			(start -0.5 1.401)
			(end 0.498 1.401)
			(stroke
				(width 0.15)
				(type solid)
			)
			(layer "B.SilkS")
		)
		(fp_circle
			(center -0.68 1.27)
			(end -0.63 1.27)
			(stroke
				(width 0.15)
				(type solid)
			)
			(fill solid)
			(layer "B.SilkS")
		)
		(fp_rect
			(start -0.8 1.5)
			(end 0.8 -1.499)
			(stroke
				(width 0.05)
				(type solid)
			)
			(fill none)
			(layer "B.CrtYd")
		)
		(fp_line
			(start 0.498 -1.249)
			(end -0.5 -1.249)
			(stroke
				(width 0.15)
				(type solid)
			)
			(layer "B.Fab")
		)
		(fp_line
			(start 0.498 -1.249)
			(end 0.498 1.25)
			(stroke
				(width 0.15)
				(type solid)
			)
			(layer "B.Fab")
		)
		(fp_line
			(start -0.5 -1.249)
			(end -0.5 1)
			(stroke
				(width 0.15)
				(type solid)
			)
			(layer "B.Fab")
		)
		(fp_line
			(start -0.5 1)
			(end -0.25 1.25)
			(stroke
				(width 0.15)
				(type solid)
			)
			(layer "B.Fab")
		)
		(fp_line
			(start -0.25 1.25)
			(end 0.498 1.25)
			(stroke
				(width 0.15)
				(type solid)
			)
			(layer "B.Fab")
		)
		(fp_text user "License: Apache-2.0"
			(at -0.802 -6.9 -90)
			(layer "B.Fab")
			(hide yes)
			(effects
				(font
					(size 0.7 0.7)
					(thickness 0.15)
				)
				(justify left bottom mirror)
			)
		)
		(fp_text user "Author: Antmicro"
			(at -0.802 -5.7 -90)
			(layer "B.Fab")
			(hide yes)
			(effects
				(font
					(size 0.7 0.7)
					(thickness 0.15)
				)
				(justify left bottom mirror)
			)
		)
		(fp_text user "${REFERENCE}"
			(at -0.802 -4.498 -90)
			(layer "B.Fab")
			(hide yes)
			(effects
				(font
					(size 0.7 0.7)
					(thickness 0.15)
				)
				(justify left bottom mirror)
			)
		)
		(pad "1" smd roundrect
			(at -0.387 1 180)
			(size 0.25 0.55)
			(layers "B.Cu" "B.Paste" "B.Mask")
			(roundrect_rratio 0.25)
			(net 273 "/USB Debug, DP/USBC3_CC1")
			(pintype "passive")
		)
		(pad "2" smd roundrect
			(at -0.387 0.5 180)
			(size 0.25 0.55)
			(layers "B.Cu" "B.Paste" "B.Mask")
			(roundrect_rratio 0.25)
			(net 613 "/USB Debug, DP/USBC3_D_P")
			(pintype "passive")
		)
		(pad "3" smd roundrect
			(at -0.387 0 180)
			(size 0.4 0.55)
			(layers "B.Cu" "B.Paste" "B.Mask")
			(roundrect_rratio 0.25)
			(net 1 "GND")
			(pintype "power_in")
		)
		(pad "4" smd roundrect
			(at -0.387 -0.498 180)
			(size 0.25 0.55)
			(layers "B.Cu" "B.Paste" "B.Mask")
			(roundrect_rratio 0.25)
			(net 275 "/USB Debug, DP/USBC3_D_N")
			(pintype "passive")
		)
		(pad "5" smd roundrect
			(at -0.387 -0.998 180)
			(size 0.25 0.55)
			(layers "B.Cu" "B.Paste" "B.Mask")
			(roundrect_rratio 0.25)
			(net 276 "/USB Debug, DP/USBC3_CC2")
			(pintype "passive")
		)
		(pad "6" smd roundrect
			(at 0.385 -0.998 180)
			(size 0.25 0.55)
			(layers "B.Cu" "B.Paste" "B.Mask")
			(roundrect_rratio 0.25)
			(net 276 "/USB Debug, DP/USBC3_CC2")
			(pintype "passive")
		)
		(pad "7" smd roundrect
			(at 0.385 -0.498 180)
			(size 0.25 0.55)
			(layers "B.Cu" "B.Paste" "B.Mask")
			(roundrect_rratio 0.25)
			(net 275 "/USB Debug, DP/USBC3_D_N")
			(pintype "passive")
		)
		(pad "8" smd roundrect
			(at 0.385 0 180)
			(size 0.4 0.55)
			(layers "B.Cu" "B.Paste" "B.Mask")
			(roundrect_rratio 0.25)
			(net 1 "GND")
			(pintype "passive")
		)
		(pad "9" smd roundrect
			(at 0.385 0.5 180)
			(size 0.25 0.55)
			(layers "B.Cu" "B.Paste" "B.Mask")
			(roundrect_rratio 0.25)
			(net 613 "/USB Debug, DP/USBC3_D_P")
			(pintype "passive")
		)
		(pad "10" smd roundrect
			(at 0.385 1 180)
			(size 0.25 0.55)
			(layers "B.Cu" "B.Paste" "B.Mask")
			(roundrect_rratio 0.25)
			(net 273 "/USB Debug, DP/USBC3_CC1")
			(pintype "passive")
		)
	)
	(footprint "antmicro-footprints:TP_SMD_0.75mm"
		(layer "B.Cu")
		(at 103.175 103.55 -90)
		(property "Reference" "TP38"
			(at 0.54 -0.5 90)
			(layer "B.SilkS")
			(hide yes)
			(effects
				(font
					(size 0.7 0.7)
					(thickness 0.15)
				)
				(justify left bottom mirror)
			)
		)
		(property "Value" "TP_0.75mm_SMD"
			(at 0 -1.2 90)
			(layer "B.Fab")
			(effects
				(font
					(size 0.7 0.7)
					(thickness 0.15)
				)
				(justify left bottom mirror)
			)
		)
		(property "Footprint" "antmicro-footprints:TP_SMD_0.75mm"
			(at 0 0 -90)
			(layer "F.Fab")
			(hide yes)
			(effects
				(font
					(size 1.27 1.27)
					(thickness 0.15)
				)
			)
		)
		(property "Author" "Antmicro"
			(at -0.375 206.725 0)
			(layer "B.Fab")
			(hide yes)
			(effects
				(font
					(size 1 1)
					(thickness 0.15)
				)
				(justify mirror)
			)
		)
		(property "License" "Apache-2.0"
			(at -0.375 206.725 0)
			(layer "B.Fab")
			(hide yes)
			(effects
				(font
					(size 1 1)
					(thickness 0.15)
				)
				(justify mirror)
			)
		)
		(property "MPN" ""
			(at -0.375 206.725 0)
			(layer "B.Fab")
			(hide yes)
			(effects
				(font
					(size 1 1)
					(thickness 0.15)
				)
				(justify mirror)
			)
		)
		(property "Manufacturer" ""
			(at -0.375 206.725 0)
			(layer "B.Fab")
			(hide yes)
			(effects
				(font
					(size 1 1)
					(thickness 0.15)
				)
				(justify mirror)
			)
		)
		(sheetname "CSI")
		(sheetfile "csi.kicad_sch")
		(attr exclude_from_pos_files exclude_from_bom)
		(fp_circle
			(center 0 0)
			(end 0.475 0)
			(stroke
				(width 0.05)
				(type default)
			)
			(fill none)
			(layer "B.CrtYd")
		)
		(fp_text user "License: Apache-2.0"
			(at -0.4 -5.101 90)
			(layer "B.Fab")
			(hide yes)
			(effects
				(font
					(size 0.7 0.7)
					(thickness 0.15)
				)
				(justify left bottom mirror)
			)
		)
		(fp_text user "Author: Antmicro"
			(at -0.4 -3.901 90)
			(layer "B.Fab")
			(hide yes)
			(effects
				(font
					(size 0.7 0.7)
					(thickness 0.15)
				)
				(justify left bottom mirror)
			)
		)
		(fp_text user "${REFERENCE}"
			(at -0.4 -2.7 90)
			(layer "B.Fab")
			(hide yes)
			(effects
				(font
					(size 0.7 0.7)
					(thickness 0.15)
				)
				(justify left bottom mirror)
			)
		)
		(pad "1" smd circle
			(at 0 0 270)
			(size 0.75 0.75)
			(layers "B.Cu" "B.Mask")
			(net 537 "/CSI/MUX_I2C_5_SDA")
			(pinfunction "1")
			(pintype "passive")
		)
	)
	(footprint "antmicro-footprints:SOT-523"
		(layer "B.Cu")
		(at 65.21 73.85 90)
		(property "Reference" "Q11"
			(at -3.94 16.57 0)
			(layer "B.SilkS")
			(effects
				(font
					(size 0.7 0.7)
					(thickness 0.15)
				)
				(justify left bottom mirror)
			)
		)
		(property "Value" "PJE138K"
			(at 0.1 -1.824 -90)
			(layer "B.Fab")
			(effects
				(font
					(size 0.7 0.7)
					(thickness 0.15)
				)
				(justify left bottom mirror)
			)
		)
		(property "Footprint" "antmicro-footprints:SOT-523"
			(at 0 0 90)
			(layer "F.Fab")
			(hide yes)
			(effects
				(font
					(size 1.27 1.27)
					(thickness 0.15)
				)
			)
		)
		(property "Datasheet" "https://www.mouser.com/datasheet/2/1057/PJE138K-1876698.pdf"
			(at 0 0 90)
			(layer "F.Fab")
			(hide yes)
			(effects
				(font
					(size 1.27 1.27)
					(thickness 0.15)
				)
			)
		)
		(property "Author" "Antmicro"
			(at 139.06 8.64 0)
			(layer "B.Fab")
			(hide yes)
			(effects
				(font
					(size 1 1)
					(thickness 0.15)
				)
				(justify mirror)
			)
		)
		(property "License" "Apache-2.0"
			(at 139.06 8.64 0)
			(layer "B.Fab")
			(hide yes)
			(effects
				(font
					(size 1 1)
					(thickness 0.15)
				)
				(justify mirror)
			)
		)
		(property "MPN" "PJE138K_R1_00001"
			(at 139.06 8.64 0)
			(layer "B.Fab")
			(hide yes)
			(effects
				(font
					(size 1 1)
					(thickness 0.15)
				)
				(justify mirror)
			)
		)
		(property "Manufacturer" "PANJIT"
			(at 139.06 8.64 0)
			(layer "B.Fab")
			(hide yes)
			(effects
				(font
					(size 1 1)
					(thickness 0.15)
				)
				(justify mirror)
			)
		)
		(sheetname "Supply")
		(sheetfile "supply.kicad_sch")
		(attr smd)
		(fp_line
			(start -0.927 0.351)
			(end -0.927 0.051)
			(stroke
				(width 0.15)
				(type solid)
			)
			(layer "B.SilkS")
		)
		(fp_line
			(start -0.277 0.551)
			(end -0.725 0.551)
			(stroke
				(width 0.15)
				(type solid)
			)
			(layer "B.SilkS")
		)
		(fp_line
			(start -0.725 0.551)
			(end -0.927 0.351)
			(stroke
				(width 0.15)
				(type solid)
			)
			(layer "B.SilkS")
		)
		(fp_line
			(start -0.277 0.75)
			(end -0.277 0.551)
			(stroke
				(width 0.15)
				(type solid)
			)
			(layer "B.SilkS")
		)
		(fp_circle
			(center -0.9652 -0.9652)
			(end -0.9152 -0.9652)
			(stroke
				(width 0.15)
				(type solid)
			)
			(fill solid)
			(layer "B.SilkS")
		)
		(fp_line
			(start 1.1 -1.15)
			(end -1.12 -1.15)
			(stroke
				(width 0.05)
				(type solid)
			)
			(layer "B.CrtYd")
		)
		(fp_line
			(start 1.1 -1.15)
			(end 1.1 1.16)
			(stroke
				(width 0.05)
				(type solid)
			)
			(layer "B.CrtYd")
		)
		(fp_line
			(start -1.12 -1.15)
			(end -1.12 1.16)
			(stroke
				(width 0.05)
				(type solid)
			)
			(layer "B.CrtYd")
		)
		(fp_line
			(start 1.1 1.16)
			(end -1.12 1.16)
			(stroke
				(width 0.05)
				(type solid)
			)
			(layer "B.CrtYd")
		)
		(fp_line
			(start 0.8 -0.424)
			(end 0.8 0.425)
			(stroke
				(width 0.15)
				(type solid)
			)
			(layer "B.Fab")
		)
		(fp_line
			(start -0.802 -0.424)
			(end 0.8 -0.424)
			(stroke
				(width 0.15)
				(type solid)
			)
			(layer "B.Fab")
		)
		(fp_line
			(start -0.802 -0.424)
			(end -0.802 0.276)
			(stroke
				(width 0.15)
				(type solid)
			)
			(layer "B.Fab")
		)
		(fp_line
			(start -0.802 0.276)
			(end -0.652 0.425)
			(stroke
				(width 0.15)
				(type solid)
			)
			(layer "B.Fab")
		)
		(fp_line
			(start -0.652 0.425)
			(end 0.8 0.425)
			(stroke
				(width 0.15)
				(type solid)
			)
			(layer "B.Fab")
		)
		(fp_circle
			(center -0.9652 -0.9652)
			(end -0.9144 -0.9652)
			(stroke
				(width 0.15)
				(type solid)
			)
			(fill none)
			(layer "B.Fab")
		)
		(fp_text user "${REFERENCE}"
			(at -1.12 -3.824 -90)
			(layer "B.Fab")
			(hide yes)
			(effects
				(font
					(size 0.7 0.7)
					(thickness 0.15)
				)
				(justify left bottom mirror)
			)
		)
		(fp_text user "Author: Antmicro"
			(at -1.12 -6.224 -90)
			(layer "B.Fab")
			(hide yes)
			(effects
				(font
					(size 0.7 0.7)
					(thickness 0.15)
				)
				(justify left bottom mirror)
			)
		)
		(fp_text user "License: Apache-2.0"
			(at -1.12 -5.024 -90)
			(layer "B.Fab")
			(hide yes)
			(effects
				(font
					(size 0.7 0.7)
					(thickness 0.15)
				)
				(justify left bottom mirror)
			)
		)
		(pad "1" smd rect
			(at -0.5 -0.65 90)
			(size 0.4 0.51)
			(layers "B.Cu" "B.Paste" "B.Mask")
			(net 628 "Net-(Q11-G)")
			(pinfunction "G")
			(pintype "passive")
		)
		(pad "2" smd rect
			(at 0.498 -0.65 90)
			(size 0.4 0.51)
			(layers "B.Cu" "B.Paste" "B.Mask")
			(net 1 "GND")
			(pinfunction "S")
			(pintype "passive")
		)
		(pad "3" smd rect
			(at 0 0.652 90)
			(size 0.4 0.51)
			(layers "B.Cu" "B.Paste" "B.Mask")
			(net 629 "Net-(D37-A)")
			(pinfunction "D")
			(pintype "passive")
		)
	)
	(footprint "antmicro-footprints:SOT-523"
		(layer "B.Cu")
		(at 108.7 108.6 180)
		(property "Reference" "Q19"
			(at -2.14 1.09 90)
			(layer "B.SilkS")
			(effects
				(font
					(size 0.7 0.7)
					(thickness 0.15)
				)
				(justify left bottom mirror)
			)
		)
		(property "Value" "PJE138K"
			(at 0.1 -1.824 0)
			(layer "B.Fab")
			(effects
				(font
					(size 0.7 0.7)
					(thickness 0.15)
				)
				(justify left bottom mirror)
			)
		)
		(property "Footprint" "antmicro-footprints:SOT-523"
			(at 0 0 180)
			(layer "F.Fab")
			(hide yes)
			(effects
				(font
					(size 1.27 1.27)
					(thickness 0.15)
				)
			)
		)
		(property "Datasheet" "https://www.mouser.com/datasheet/2/1057/PJE138K-1876698.pdf"
			(at 0 0 180)
			(layer "F.Fab")
			(hide yes)
			(effects
				(font
					(size 1.27 1.27)
					(thickness 0.15)
				)
			)
		)
		(property "Author" "Antmicro"
			(at 217.4 217.2 0)
			(layer "B.Fab")
			(hide yes)
			(effects
				(font
					(size 1 1)
					(thickness 0.15)
				)
				(justify mirror)
			)
		)
		(property "License" "Apache-2.0"
			(at 217.4 217.2 0)
			(layer "B.Fab")
			(hide yes)
			(effects
				(font
					(size 1 1)
					(thickness 0.15)
				)
				(justify mirror)
			)
		)
		(property "MPN" "PJE138K_R1_00001"
			(at 217.4 217.2 0)
			(layer "B.Fab")
			(hide yes)
			(effects
				(font
					(size 1 1)
					(thickness 0.15)
				)
				(justify mirror)
			)
		)
		(property "Manufacturer" "PANJIT"
			(at 217.4 217.2 0)
			(layer "B.Fab")
			(hide yes)
			(effects
				(font
					(size 1 1)
					(thickness 0.15)
				)
				(justify mirror)
			)
		)
		(sheetname "USB3")
		(sheetfile "usb3.kicad_sch")
		(attr smd)
		(fp_line
			(start -0.277 0.75)
			(end -0.277 0.551)
			(stroke
				(width 0.15)
				(type solid)
			)
			(layer "B.SilkS")
		)
		(fp_line
			(start -0.277 0.551)
			(end -0.725 0.551)
			(stroke
				(width 0.15)
				(type solid)
			)
			(layer "B.SilkS")
		)
		(fp_line
			(start -0.725 0.551)
			(end -0.927 0.351)
			(stroke
				(width 0.15)
				(type solid)
			)
			(layer "B.SilkS")
		)
		(fp_line
			(start -0.927 0.351)
			(end -0.927 0.051)
			(stroke
				(width 0.15)
				(type solid)
			)
			(layer "B.SilkS")
		)
		(fp_circle
			(center -0.9652 -0.9652)
			(end -0.9152 -0.9652)
			(stroke
				(width 0.15)
				(type solid)
			)
			(fill solid)
			(layer "B.SilkS")
		)
		(fp_line
			(start 1.1 1.16)
			(end -1.12 1.16)
			(stroke
				(width 0.05)
				(type solid)
			)
			(layer "B.CrtYd")
		)
		(fp_line
			(start 1.1 -1.15)
			(end 1.1 1.16)
			(stroke
				(width 0.05)
				(type solid)
			)
			(layer "B.CrtYd")
		)
		(fp_line
			(start 1.1 -1.15)
			(end -1.12 -1.15)
			(stroke
				(width 0.05)
				(type solid)
			)
			(layer "B.CrtYd")
		)
		(fp_line
			(start -1.12 -1.15)
			(end -1.12 1.16)
			(stroke
				(width 0.05)
				(type solid)
			)
			(layer "B.CrtYd")
		)
		(fp_line
			(start 0.8 -0.424)
			(end 0.8 0.425)
			(stroke
				(width 0.15)
				(type solid)
			)
			(layer "B.Fab")
		)
		(fp_line
			(start -0.652 0.425)
			(end 0.8 0.425)
			(stroke
				(width 0.15)
				(type solid)
			)
			(layer "B.Fab")
		)
		(fp_line
			(start -0.802 0.276)
			(end -0.652 0.425)
			(stroke
				(width 0.15)
				(type solid)
			)
			(layer "B.Fab")
		)
		(fp_line
			(start -0.802 -0.424)
			(end 0.8 -0.424)
			(stroke
				(width 0.15)
				(type solid)
			)
			(layer "B.Fab")
		)
		(fp_line
			(start -0.802 -0.424)
			(end -0.802 0.276)
			(stroke
				(width 0.15)
				(type solid)
			)
			(layer "B.Fab")
		)
		(fp_circle
			(center -0.9652 -0.9652)
			(end -0.9144 -0.9652)
			(stroke
				(width 0.15)
				(type solid)
			)
			(fill none)
			(layer "B.Fab")
		)
		(fp_text user "License: Apache-2.0"
			(at -1.12 -5.024 0)
			(layer "B.Fab")
			(hide yes)
			(effects
				(font
					(size 0.7 0.7)
					(thickness 0.15)
				)
				(justify left bottom mirror)
			)
		)
		(fp_text user "${REFERENCE}"
			(at -1.12 -3.824 0)
			(layer "B.Fab")
			(hide yes)
			(effects
				(font
					(size 0.7 0.7)
					(thickness 0.15)
				)
				(justify left bottom mirror)
			)
		)
		(fp_text user "Author: Antmicro"
			(at -1.12 -6.224 0)
			(layer "B.Fab")
			(hide yes)
			(effects
				(font
					(size 0.7 0.7)
					(thickness 0.15)
				)
				(justify left bottom mirror)
			)
		)
		(pad "1" smd rect
			(at -0.5 -0.65 180)
			(size 0.4 0.51)
			(layers "B.Cu" "B.Paste" "B.Mask")
			(net 632 "Net-(Q19-G)")
			(pinfunction "G")
			(pintype "passive")
		)
		(pad "2" smd rect
			(at 0.498 -0.65 180)
			(size 0.4 0.51)
			(layers "B.Cu" "B.Paste" "B.Mask")
			(net 1 "GND")
			(pinfunction "S")
			(pintype "passive")
		)
		(pad "3" smd rect
			(at 0 0.652 180)
			(size 0.4 0.51)
			(layers "B.Cu" "B.Paste" "B.Mask")
			(net 116 "USB_FLASH_ID")
			(pinfunction "D")
			(pintype "passive")
		)
	)
	(footprint "antmicro-footprints:R_0402_1005Metric"
		(layer "B.Cu")
		(at 74.05 103.4 90)
		(descr "Resistor SMD 0402")
		(tags "resistor SMD 0402")
		(property "Reference" "R85"
			(at 5.16 1.67 -90)
			(layer "B.SilkS")
			(effects
				(font
					(size 0.7 0.7)
					(thickness 0.15)
				)
				(justify left bottom mirror)
			)
		)
		(property "Value" "R_1k_0402"
			(at 0 -1.4 -90)
			(layer "B.Fab")
			(effects
				(font
					(size 0.7 0.7)
					(thickness 0.15)
				)
				(justify left bottom mirror)
			)
		)
		(property "Footprint" "antmicro-footprints:R_0402_1005Metric"
			(at 0 0 90)
			(layer "F.Fab")
			(hide yes)
			(effects
				(font
					(size 1.27 1.27)
					(thickness 0.15)
				)
			)
		)
		(property "Datasheet" "https://www.bourns.com/docs/product-datasheets/cr.pdf"
			(at 0 0 90)
			(layer "F.Fab")
			(hide yes)
			(effects
				(font
					(size 1.27 1.27)
					(thickness 0.15)
				)
			)
		)
		(property "Author" "Antmicro"
			(at 177.45 29.35 0)
			(layer "B.Fab")
			(hide yes)
			(effects
				(font
					(size 1 1)
					(thickness 0.15)
				)
				(justify mirror)
			)
		)
		(property "License" "Apache-2.0"
			(at 177.45 29.35 0)
			(layer "B.Fab")
			(hide yes)
			(effects
				(font
					(size 1 1)
					(thickness 0.15)
				)
				(justify mirror)
			)
		)
		(property "MPN" "CR0402-FX-1001GLF"
			(at 177.45 29.35 0)
			(layer "B.Fab")
			(hide yes)
			(effects
				(font
					(size 1 1)
					(thickness 0.15)
				)
				(justify mirror)
			)
		)
		(property "Manufacturer" "Bourns"
			(at 177.45 29.35 0)
			(layer "B.Fab")
			(hide yes)
			(effects
				(font
					(size 1 1)
					(thickness 0.15)
				)
				(justify mirror)
			)
		)
		(property "Tolerance" "1%"
			(at 177.45 29.35 0)
			(layer "B.Fab")
			(hide yes)
			(effects
				(font
					(size 1 1)
					(thickness 0.15)
				)
				(justify mirror)
			)
		)
		(property "Val" "1k"
			(at 177.45 29.35 0)
			(layer "B.Fab")
			(hide yes)
			(effects
				(font
					(size 1 1)
					(thickness 0.15)
				)
				(justify mirror)
			)
		)
		(sheetname "USB Debug, DP")
		(sheetfile "usb.kicad_sch")
		(attr smd exclude_from_pos_files exclude_from_bom dnp)
		(fp_rect
			(start -0.925 0.47)
			(end 0.925 -0.47)
			(stroke
				(width 0.05)
				(type default)
			)
			(fill none)
			(layer "B.CrtYd")
		)
		(fp_rect
			(start -0.5 0.25)
			(end 0.5 -0.25)
			(stroke
				(width 0.15)
				(type solid)
			)
			(fill none)
			(layer "B.Fab")
		)
		(fp_text user "${REFERENCE}"
			(at -0.95 -3.168 -90)
			(layer "B.Fab")
			(hide yes)
			(effects
				(font
					(size 0.7 0.7)
					(thickness 0.15)
				)
				(justify left bottom mirror)
			)
		)
		(fp_text user "License: Apache-2.0"
			(at -0.95 -5.169 -90)
			(layer "B.Fab")
			(hide yes)
			(effects
				(font
					(size 0.7 0.7)
					(thickness 0.15)
				)
				(justify left bottom mirror)
			)
		)
		(fp_text user "Author: Antmicro"
			(at -0.95 -4.169 -90)
			(layer "B.Fab")
			(hide yes)
			(effects
				(font
					(size 0.7 0.7)
					(thickness 0.15)
				)
				(justify left bottom mirror)
			)
		)
		(pad "1" smd roundrect
			(at -0.48 0 90)
			(size 0.59 0.64)
			(layers "B.Cu" "B.Paste" "B.Mask")
			(roundrect_rratio 0.25)
			(net 304 "/USB Debug, DP/USBC0_I2C_EN")
			(pintype "passive")
		)
		(pad "2" smd roundrect
			(at 0.48 0 90)
			(size 0.59 0.64)
			(layers "B.Cu" "B.Paste" "B.Mask")
			(roundrect_rratio 0.25)
			(net 87 "+3V3")
			(pintype "passive")
		)
	)
	(footprint "antmicro-footprints:R_0402_1005Metric"
		(layer "B.Cu")
		(at 52.9 116.8 -90)
		(descr "Resistor SMD 0402")
		(tags "resistor SMD 0402")
		(property "Reference" "R117"
			(at 0.7 1.3 90)
			(layer "B.SilkS")
			(effects
				(font
					(size 0.7 0.7)
					(thickness 0.15)
				)
				(justify left bottom mirror)
			)
		)
		(property "Value" "R_27R_0402"
			(at 0 -1.4 90)
			(layer "B.Fab")
			(effects
				(font
					(size 0.7 0.7)
					(thickness 0.15)
				)
				(justify left bottom mirror)
			)
		)
		(property "Footprint" "antmicro-footprints:R_0402_1005Metric"
			(at 0 0 -90)
			(layer "F.Fab")
			(hide yes)
			(effects
				(font
					(size 1.27 1.27)
					(thickness 0.15)
				)
			)
		)
		(property "Datasheet" "https://www.bourns.com/docs/product-datasheets/cr.pdf"
			(at 0 0 -90)
			(layer "F.Fab")
			(hide yes)
			(effects
				(font
					(size 1.27 1.27)
					(thickness 0.15)
				)
			)
		)
		(property "Author" "Antmicro"
			(at -63.9 169.7 0)
			(layer "B.Fab")
			(hide yes)
			(effects
				(font
					(size 1 1)
					(thickness 0.15)
				)
				(justify mirror)
			)
		)
		(property "License" "Apache-2.0"
			(at -63.9 169.7 0)
			(layer "B.Fab")
			(hide yes)
			(effects
				(font
					(size 1 1)
					(thickness 0.15)
				)
				(justify mirror)
			)
		)
		(property "MPN" "CR0402-FX-27R0GLF"
			(at -63.9 169.7 0)
			(layer "B.Fab")
			(hide yes)
			(effects
				(font
					(size 1 1)
					(thickness 0.15)
				)
				(justify mirror)
			)
		)
		(property "Manufacturer" "Bourns"
			(at -63.9 169.7 0)
			(layer "B.Fab")
			(hide yes)
			(effects
				(font
					(size 1 1)
					(thickness 0.15)
				)
				(justify mirror)
			)
		)
		(property "Tolerance" "1%"
			(at -63.9 169.7 0)
			(layer "B.Fab")
			(hide yes)
			(effects
				(font
					(size 1 1)
					(thickness 0.15)
				)
				(justify mirror)
			)
		)
		(property "Val" "27R"
			(at -63.9 169.7 0)
			(layer "B.Fab")
			(hide yes)
			(effects
				(font
					(size 1 1)
					(thickness 0.15)
				)
				(justify mirror)
			)
		)
		(sheetname "USB Debug, DP")
		(sheetfile "usb.kicad_sch")
		(attr smd)
		(fp_rect
			(start -0.925 0.47)
			(end 0.925 -0.47)
			(stroke
				(width 0.05)
				(type default)
			)
			(fill none)
			(layer "B.CrtYd")
		)
		(fp_rect
			(start -0.5 0.25)
			(end 0.5 -0.25)
			(stroke
				(width 0.15)
				(type solid)
			)
			(fill none)
			(layer "B.Fab")
		)
		(fp_text user "License: Apache-2.0"
			(at -0.95 -5.169 90)
			(layer "B.Fab")
			(hide yes)
			(effects
				(font
					(size 0.7 0.7)
					(thickness 0.15)
				)
				(justify left bottom mirror)
			)
		)
		(fp_text user "${REFERENCE}"
			(at -0.95 -3.168 90)
			(layer "B.Fab")
			(hide yes)
			(effects
				(font
					(size 0.7 0.7)
					(thickness 0.15)
				)
				(justify left bottom mirror)
			)
		)
		(fp_text user "Author: Antmicro"
			(at -0.95 -4.169 90)
			(layer "B.Fab")
			(hide yes)
			(effects
				(font
					(size 0.7 0.7)
					(thickness 0.15)
				)
				(justify left bottom mirror)
			)
		)
		(pad "1" smd roundrect
			(at -0.48 0 270)
			(size 0.59 0.64)
			(layers "B.Cu" "B.Paste" "B.Mask")
			(roundrect_rratio 0.25)
			(net 312 "/USB Debug, DP/USB_FTDI_N")
			(pintype "passive")
		)
		(pad "2" smd roundrect
			(at 0.48 0 270)
			(size 0.59 0.64)
			(layers "B.Cu" "B.Paste" "B.Mask")
			(roundrect_rratio 0.25)
			(net 275 "/USB Debug, DP/USBC3_D_N")
			(pintype "passive")
		)
	)
	(footprint "antmicro-footprints:R_0402_1005Metric"
		(layer "B.Cu")
		(at 61.16 98.16 -90)
		(descr "Resistor SMD 0402")
		(tags "resistor SMD 0402")
		(property "Reference" "R246"
			(at 0.86 -0.39 90)
			(layer "B.SilkS")
			(effects
				(font
					(size 0.7 0.7)
					(thickness 0.15)
				)
				(justify left bottom mirror)
			)
		)
		(property "Value" "R_4k7_0402"
			(at 0 -1.4 90)
			(layer "B.Fab")
			(effects
				(font
					(size 0.7 0.7)
					(thickness 0.15)
				)
				(justify left bottom mirror)
			)
		)
		(property "Footprint" "antmicro-footprints:R_0402_1005Metric"
			(at 0 0 -90)
			(layer "F.Fab")
			(hide yes)
			(effects
				(font
					(size 1.27 1.27)
					(thickness 0.15)
				)
			)
		)
		(property "Datasheet" "https://www.bourns.com/docs/product-datasheets/cr.pdf"
			(at 0 0 -90)
			(layer "F.Fab")
			(hide yes)
			(effects
				(font
					(size 1.27 1.27)
					(thickness 0.15)
				)
			)
		)
		(property "Author" "Antmicro"
			(at -37 159.32 0)
			(layer "B.Fab")
			(hide yes)
			(effects
				(font
					(size 1 1)
					(thickness 0.15)
				)
				(justify mirror)
			)
		)
		(property "License" "Apache-2.0"
			(at -37 159.32 0)
			(layer "B.Fab")
			(hide yes)
			(effects
				(font
					(size 1 1)
					(thickness 0.15)
				)
				(justify mirror)
			)
		)
		(property "MPN" "CR0402-FX-4701GLF"
			(at -37 159.32 0)
			(layer "B.Fab")
			(hide yes)
			(effects
				(font
					(size 1 1)
					(thickness 0.15)
				)
				(justify mirror)
			)
		)
		(property "Manufacturer" "Bourns"
			(at -37 159.32 0)
			(layer "B.Fab")
			(hide yes)
			(effects
				(font
					(size 1 1)
					(thickness 0.15)
				)
				(justify mirror)
			)
		)
		(property "Tolerance" "1%"
			(at -37 159.32 0)
			(layer "B.Fab")
			(hide yes)
			(effects
				(font
					(size 1 1)
					(thickness 0.15)
				)
				(justify mirror)
			)
		)
		(property "Val" "4k7"
			(at -37 159.32 0)
			(layer "B.Fab")
			(hide yes)
			(effects
				(font
					(size 1 1)
					(thickness 0.15)
				)
				(justify mirror)
			)
		)
		(sheetname "USB Debug, DP")
		(sheetfile "usb.kicad_sch")
		(attr smd)
		(fp_rect
			(start -0.925 0.47)
			(end 0.925 -0.47)
			(stroke
				(width 0.05)
				(type default)
			)
			(fill none)
			(layer "B.CrtYd")
		)
		(fp_rect
			(start -0.5 0.25)
			(end 0.5 -0.25)
			(stroke
				(width 0.15)
				(type solid)
			)
			(fill none)
			(layer "B.Fab")
		)
		(fp_text user "${REFERENCE}"
			(at -0.95 -3.168 90)
			(layer "B.Fab")
			(hide yes)
			(effects
				(font
					(size 0.7 0.7)
					(thickness 0.15)
				)
				(justify left bottom mirror)
			)
		)
		(fp_text user "Author: Antmicro"
			(at -0.95 -4.169 90)
			(layer "B.Fab")
			(hide yes)
			(effects
				(font
					(size 0.7 0.7)
					(thickness 0.15)
				)
				(justify left bottom mirror)
			)
		)
		(fp_text user "License: Apache-2.0"
			(at -0.95 -5.169 90)
			(layer "B.Fab")
			(hide yes)
			(effects
				(font
					(size 0.7 0.7)
					(thickness 0.15)
				)
				(justify left bottom mirror)
			)
		)
		(pad "1" smd roundrect
			(at -0.48 0 270)
			(size 0.59 0.64)
			(layers "B.Cu" "B.Paste" "B.Mask")
			(roundrect_rratio 0.25)
			(net 87 "+3V3")
			(pintype "passive")
		)
		(pad "2" smd roundrect
			(at 0.48 0 270)
			(size 0.59 0.64)
			(layers "B.Cu" "B.Paste" "B.Mask")
			(roundrect_rratio 0.25)
			(net 303 "/USB Debug, DP/PDC_I2C1_SDA")
			(pintype "passive")
		)
	)
	(footprint "antmicro-footprints:C_0402_1005Metric"
		(layer "B.Cu")
		(at 58.55 107.05 180)
		(descr "Capacitor SMD 0402")
		(tags "capacitor SMD 0402")
		(property "Reference" "C147"
			(at -1.68 -1.36 0)
			(layer "B.SilkS")
			(effects
				(font
					(size 0.7 0.7)
					(thickness 0.15)
				)
				(justify left bottom mirror)
			)
		)
		(property "Value" "C_1u_25V_0402"
			(at 0 -1.4 0)
			(layer "B.Fab")
			(effects
				(font
					(size 0.7 0.7)
					(thickness 0.15)
				)
				(justify left bottom mirror)
			)
		)
		(property "Footprint" "antmicro-footprints:C_0402_1005Metric"
			(at 0 0 180)
			(layer "F.Fab")
			(hide yes)
			(effects
				(font
					(size 1.27 1.27)
					(thickness 0.15)
				)
			)
		)
		(property "Datasheet" "https://www.murata.com/products/productdetail?partno=GRM155R61E105KE11%23"
			(at 0 0 180)
			(layer "F.Fab")
			(hide yes)
			(effects
				(font
					(size 1.27 1.27)
					(thickness 0.15)
				)
			)
		)
		(property "Author" "Antmicro"
			(at 117.1 214.1 0)
			(layer "B.Fab")
			(hide yes)
			(effects
				(font
					(size 1 1)
					(thickness 0.15)
				)
				(justify mirror)
			)
		)
		(property "Dielectric" "X5R"
			(at 117.1 214.1 0)
			(layer "B.Fab")
			(hide yes)
			(effects
				(font
					(size 1 1)
					(thickness 0.15)
				)
				(justify mirror)
			)
		)
		(property "License" "Apache-2.0"
			(at 117.1 214.1 0)
			(layer "B.Fab")
			(hide yes)
			(effects
				(font
					(size 1 1)
					(thickness 0.15)
				)
				(justify mirror)
			)
		)
		(property "MPN" "GRM155R61E105KE11J"
			(at 117.1 214.1 0)
			(layer "B.Fab")
			(hide yes)
			(effects
				(font
					(size 1 1)
					(thickness 0.15)
				)
				(justify mirror)
			)
		)
		(property "Manufacturer" "Murata"
			(at 117.1 214.1 0)
			(layer "B.Fab")
			(hide yes)
			(effects
				(font
					(size 1 1)
					(thickness 0.15)
				)
				(justify mirror)
			)
		)
		(property "Val" "1u"
			(at 117.1 214.1 0)
			(layer "B.Fab")
			(hide yes)
			(effects
				(font
					(size 1 1)
					(thickness 0.15)
				)
				(justify mirror)
			)
		)
		(property "Voltage" "25V"
			(at 117.1 214.1 0)
			(layer "B.Fab")
			(hide yes)
			(effects
				(font
					(size 1 1)
					(thickness 0.15)
				)
				(justify mirror)
			)
		)
		(sheetname "USB Debug, DP")
		(sheetfile "usb.kicad_sch")
		(attr smd)
		(fp_rect
			(start -0.925 0.47)
			(end 0.925 -0.47)
			(stroke
				(width 0.05)
				(type default)
			)
			(fill none)
			(layer "B.CrtYd")
		)
		(fp_line
			(start 0.504 0.25)
			(end -0.494 0.25)
			(stroke
				(width 0.15)
				(type solid)
			)
			(layer "B.Fab")
		)
		(fp_line
			(start 0.504 -0.248)
			(end 0.504 0.25)
			(stroke
				(width 0.15)
				(type solid)
			)
			(layer "B.Fab")
		)
		(fp_line
			(start -0.494 0.25)
			(end -0.494 -0.248)
			(stroke
				(width 0.15)
				(type solid)
			)
			(layer "B.Fab")
		)
		(fp_line
			(start -0.494 -0.248)
			(end 0.504 -0.248)
			(stroke
				(width 0.15)
				(type solid)
			)
			(layer "B.Fab")
		)
		(fp_text user "Author: Antmicro"
			(at -0.932 -4.17 0)
			(layer "B.Fab")
			(hide yes)
			(effects
				(font
					(size 0.7 0.7)
					(thickness 0.15)
				)
				(justify left bottom mirror)
			)
		)
		(fp_text user "License: Apache-2.0"
			(at -0.932 -5.17 0)
			(layer "B.Fab")
			(hide yes)
			(effects
				(font
					(size 0.7 0.7)
					(thickness 0.15)
				)
				(justify left bottom mirror)
			)
		)
		(fp_text user "${REFERENCE}"
			(at -0.932 -3.168 0)
			(layer "B.Fab")
			(hide yes)
			(effects
				(font
					(size 0.7 0.7)
					(thickness 0.15)
				)
				(justify left bottom mirror)
			)
		)
		(pad "1" smd roundrect
			(at -0.48 0 180)
			(size 0.59 0.64)
			(layers "B.Cu" "B.Paste" "B.Mask")
			(roundrect_rratio 0.25)
			(net 196 "/USB Debug, DP/USBC3_VBUS")
			(pintype "passive")
		)
		(pad "2" smd roundrect
			(at 0.48 0 180)
			(size 0.59 0.64)
			(layers "B.Cu" "B.Paste" "B.Mask")
			(roundrect_rratio 0.25)
			(net 1 "GND")
			(pintype "passive")
		)
	)
	(footprint "antmicro-footprints:R_Array_4x0201_Panasonic_EXB18V"
		(layer "B.Cu")
		(at 85.21 122.08 180)
		(property "Reference" "R112"
			(at 0.91 0.68 0)
			(layer "B.SilkS")
			(effects
				(font
					(size 0.7 0.7)
					(thickness 0.15)
				)
				(justify right bottom mirror)
			)
		)
		(property "Value" "R_4x100R_0201_array"
			(at -1.1 -1.8 0)
			(layer "B.Fab")
			(effects
				(font
					(size 0.7 0.7)
					(thickness 0.15)
				)
				(justify left bottom mirror)
			)
		)
		(property "Footprint" "antmicro-footprints:R_Array_4x0201_Panasonic_EXB18V"
			(at 0 0 180)
			(layer "F.Fab")
			(hide yes)
			(effects
				(font
					(size 1.27 1.27)
					(thickness 0.15)
				)
			)
		)
		(property "Datasheet" "http://industrial.panasonic.com/cdbs/www-data/pdf/AOC0000/AOC0000C14.pdf"
			(at 0 0 180)
			(layer "F.Fab")
			(hide yes)
			(effects
				(font
					(size 1.27 1.27)
					(thickness 0.15)
				)
			)
		)
		(property "Author" "Antmicro"
			(at 170.42 244.16 0)
			(layer "B.Fab")
			(hide yes)
			(effects
				(font
					(size 1 1)
					(thickness 0.15)
				)
				(justify mirror)
			)
		)
		(property "License" "Apache-2.0"
			(at 170.42 244.16 0)
			(layer "B.Fab")
			(hide yes)
			(effects
				(font
					(size 1 1)
					(thickness 0.15)
				)
				(justify mirror)
			)
		)
		(property "MPN" "EXB-18V101JX"
			(at 170.42 244.16 0)
			(layer "B.Fab")
			(hide yes)
			(effects
				(font
					(size 1 1)
					(thickness 0.15)
				)
				(justify mirror)
			)
		)
		(property "Manufacturer" "Panasonic"
			(at 170.42 244.16 0)
			(layer "B.Fab")
			(hide yes)
			(effects
				(font
					(size 1 1)
					(thickness 0.15)
				)
				(justify mirror)
			)
		)
		(property "Val" "R_4x100R_0201"
			(at 170.42 244.16 0)
			(layer "B.Fab")
			(hide yes)
			(effects
				(font
					(size 1 1)
					(thickness 0.15)
				)
				(justify mirror)
			)
		)
		(sheetname "Peripherals")
		(sheetfile "peripherals.kicad_sch")
		(attr smd exclude_from_pos_files exclude_from_bom dnp)
		(fp_line
			(start 0.8 -0.45)
			(end 0.8 0.45)
			(stroke
				(width 0.12)
				(type solid)
			)
			(layer "B.SilkS")
		)
		(fp_line
			(start -0.8 -0.45)
			(end -0.8 0.45)
			(stroke
				(width 0.12)
				(type solid)
			)
			(layer "B.SilkS")
		)
		(fp_rect
			(start -0.898 0.66)
			(end 0.898 -0.65)
			(stroke
				(width 0.05)
				(type solid)
			)
			(fill none)
			(layer "B.CrtYd")
		)
		(fp_text user "Author: Antmicro"
			(at -1.051 -4.599 0)
			(layer "B.Fab")
			(hide yes)
			(effects
				(font
					(size 0.7 0.7)
					(thickness 0.15)
				)
				(justify left bottom mirror)
			)
		)
		(fp_text user "${REFERENCE}"
			(at -1.051 -3.2 0)
			(layer "B.Fab")
			(hide yes)
			(effects
				(font
					(size 0.7 0.7)
					(thickness 0.15)
				)
				(justify left bottom mirror)
			)
		)
		(fp_text user "License: Apache-2.0"
			(at -1.051 -6 0)
			(layer "B.Fab")
			(hide yes)
			(effects
				(font
					(size 0.7 0.7)
					(thickness 0.15)
				)
				(justify left bottom mirror)
			)
		)
		(pad "1" smd roundrect
			(at -0.6 -0.298 180)
			(size 0.2 0.4)
			(layers "B.Cu" "B.Paste" "B.Mask")
			(roundrect_rratio 0.25)
			(net 779 "Net-(D63-A)")
			(pinfunction "R1.1")
			(pintype "passive")
		)
		(pad "2" smd roundrect
			(at -0.202 -0.298 180)
			(size 0.2 0.4)
			(layers "B.Cu" "B.Paste" "B.Mask")
			(roundrect_rratio 0.25)
			(net 773 "/Peripherals/MISO")
			(pinfunction "R2.1")
			(pintype "passive")
		)
		(pad "3" smd roundrect
			(at 0.2 -0.298 180)
			(size 0.2 0.4)
			(layers "B.Cu" "B.Paste" "B.Mask")
			(roundrect_rratio 0.25)
			(net 774 "/Peripherals/MOSI")
			(pinfunction "R3.1")
			(pintype "passive")
		)
		(pad "4" smd roundrect
			(at 0.598 -0.298 180)
			(size 0.2 0.4)
			(layers "B.Cu" "B.Paste" "B.Mask")
			(roundrect_rratio 0.25)
			(net 777 "unconnected-(R112-R4.1-Pad4)")
			(pinfunction "R4.1")
			(pintype "passive+no_connect")
		)
		(pad "5" smd roundrect
			(at 0.598 0.3 180)
			(size 0.2 0.4)
			(layers "B.Cu" "B.Paste" "B.Mask")
			(roundrect_rratio 0.25)
			(net 778 "unconnected-(R112-R4.2-Pad5)")
			(pinfunction "R4.2")
			(pintype "passive+no_connect")
		)
		(pad "6" smd roundrect
			(at 0.2 0.3 180)
			(size 0.2 0.4)
			(layers "B.Cu" "B.Paste" "B.Mask")
			(roundrect_rratio 0.25)
			(net 251 "SYS_SDA")
			(pinfunction "R3.2")
			(pintype "passive")
		)
		(pad "7" smd roundrect
			(at -0.202 0.3 180)
			(size 0.2 0.4)
			(layers "B.Cu" "B.Paste" "B.Mask")
			(roundrect_rratio 0.25)
			(net 251 "SYS_SDA")
			(pinfunction "R2.2")
			(pintype "passive")
		)
		(pad "8" smd roundrect
			(at -0.6 0.3 180)
			(size 0.2 0.4)
			(layers "B.Cu" "B.Paste" "B.Mask")
			(roundrect_rratio 0.25)
			(net 252 "SYS_SCL")
			(pinfunction "R1.2")
			(pintype "passive")
		)
	)
	(footprint "antmicro-footprints:TP_SMD_0.75mm"
		(layer "B.Cu")
		(at 102.14999 103.5508 180)
		(property "Reference" "TP39"
			(at 0 0.6 0)
			(layer "B.SilkS")
			(hide yes)
			(effects
				(font
					(size 0.7 0.7)
					(thickness 0.15)
				)
				(justify left bottom mirror)
			)
		)
		(property "Value" "TP_0.75mm_SMD"
			(at 0 -1.2 0)
			(layer "B.Fab")
			(effects
				(font
					(size 0.7 0.7)
					(thickness 0.15)
				)
				(justify left bottom mirror)
			)
		)
		(property "Footprint" "antmicro-footprints:TP_SMD_0.75mm"
			(at 0 0 180)
			(layer "F.Fab")
			(hide yes)
			(effects
				(font
					(size 1.27 1.27)
					(thickness 0.15)
				)
			)
		)
		(property "Author" "Antmicro"
			(at 204.29998 207.1016 0)
			(layer "B.Fab")
			(hide yes)
			(effects
				(font
					(size 1 1)
					(thickness 0.15)
				)
				(justify mirror)
			)
		)
		(property "License" "Apache-2.0"
			(at 204.29998 207.1016 0)
			(layer "B.Fab")
			(hide yes)
			(effects
				(font
					(size 1 1)
					(thickness 0.15)
				)
				(justify mirror)
			)
		)
		(property "MPN" ""
			(at 204.29998 207.1016 0)
			(layer "B.Fab")
			(hide yes)
			(effects
				(font
					(size 1 1)
					(thickness 0.15)
				)
				(justify mirror)
			)
		)
		(property "Manufacturer" ""
			(at 204.29998 207.1016 0)
			(layer "B.Fab")
			(hide yes)
			(effects
				(font
					(size 1 1)
					(thickness 0.15)
				)
				(justify mirror)
			)
		)
		(sheetname "CSI")
		(sheetfile "csi.kicad_sch")
		(attr exclude_from_pos_files exclude_from_bom)
		(fp_circle
			(center 0 0)
			(end 0.475 0)
			(stroke
				(width 0.05)
				(type default)
			)
			(fill none)
			(layer "B.CrtYd")
		)
		(fp_text user "${REFERENCE}"
			(at -0.4 -2.7 0)
			(layer "B.Fab")
			(hide yes)
			(effects
				(font
					(size 0.7 0.7)
					(thickness 0.15)
				)
				(justify left bottom mirror)
			)
		)
		(fp_text user "License: Apache-2.0"
			(at -0.4 -5.101 0)
			(layer "B.Fab")
			(hide yes)
			(effects
				(font
					(size 0.7 0.7)
					(thickness 0.15)
				)
				(justify left bottom mirror)
			)
		)
		(fp_text user "Author: Antmicro"
			(at -0.4 -3.901 0)
			(layer "B.Fab")
			(hide yes)
			(effects
				(font
					(size 0.7 0.7)
					(thickness 0.15)
				)
				(justify left bottom mirror)
			)
		)
		(pad "1" smd circle
			(at 0 0 180)
			(size 0.75 0.75)
			(layers "B.Cu" "B.Mask")
			(net 538 "/CSI/MUX_I2C_5_SCL")
			(pinfunction "1")
			(pintype "passive")
		)
	)
	(footprint "antmicro-footprints:USB-C_Receptacle_GCT_USB4105-GF-A"
		(layer "B.Cu")
		(at 53.59 124.74 180)
		(property "Reference" "J3"
			(at -7.61 2.49 0)
			(layer "B.SilkS")
			(effects
				(font
					(size 0.7 0.7)
					(thickness 0.15)
				)
				(justify left bottom mirror)
			)
		)
		(property "Value" "USB-C_GCT_USB4105-GF-A"
			(at 0 -5 0)
			(layer "B.Fab")
			(effects
				(font
					(size 0.7 0.7)
					(thickness 0.15)
				)
				(justify left bottom mirror)
			)
		)
		(property "Footprint" "antmicro-footprints:USB-C_Receptacle_GCT_USB4105-GF-A"
			(at 0 0 180)
			(layer "F.Fab")
			(hide yes)
			(effects
				(font
					(size 1.27 1.27)
					(thickness 0.15)
				)
			)
		)
		(property "Datasheet" "https://gct.co/files/drawings/usb4105.pdf"
			(at 0 0 180)
			(layer "F.Fab")
			(hide yes)
			(effects
				(font
					(size 1.27 1.27)
					(thickness 0.15)
				)
			)
		)
		(property "Author" "Antmicro"
			(at 107.18 249.48 0)
			(layer "B.Fab")
			(hide yes)
			(effects
				(font
					(size 1 1)
					(thickness 0.15)
				)
				(justify mirror)
			)
		)
		(property "License" "Apache-2.0"
			(at 107.18 249.48 0)
			(layer "B.Fab")
			(hide yes)
			(effects
				(font
					(size 1 1)
					(thickness 0.15)
				)
				(justify mirror)
			)
		)
		(property "MPN" "USB4105-GF-A"
			(at 107.18 249.48 0)
			(layer "B.Fab")
			(hide yes)
			(effects
				(font
					(size 1 1)
					(thickness 0.15)
				)
				(justify mirror)
			)
		)
		(property "Manufacturer" "GCT"
			(at 107.18 249.48 0)
			(layer "B.Fab")
			(hide yes)
			(effects
				(font
					(size 1 1)
					(thickness 0.15)
				)
				(justify mirror)
			)
		)
		(sheetname "USB Debug, DP")
		(sheetfile "usb.kicad_sch")
		(attr smd)
		(fp_line
			(start 4.788 0.145)
			(end 4.788 1.395)
			(stroke
				(width 0.15)
				(type solid)
			)
			(layer "B.SilkS")
		)
		(fp_line
			(start 4.788 -2.575)
			(end 4.788 -3.854)
			(stroke
				(width 0.15)
				(type solid)
			)
			(layer "B.SilkS")
		)
		(fp_line
			(start 4.788 -3.854)
			(end -4.79 -3.854)
			(stroke
				(width 0.15)
				(type solid)
			)
			(layer "B.SilkS")
		)
		(fp_line
			(start -4.79 0.145)
			(end -4.79 1.395)
			(stroke
				(width 0.15)
				(type solid)
			)
			(layer "B.SilkS")
		)
		(fp_line
			(start -4.79 -3.854)
			(end -4.79 -2.575)
			(stroke
				(width 0.15)
				(type solid)
			)
			(layer "B.SilkS")
		)
		(fp_circle
			(center -3.8 4.27071)
			(end -3.75 4.22071)
			(stroke
				(width 0.15)
				(type solid)
			)
			(fill solid)
			(layer "B.SilkS")
		)
		(fp_rect
			(start -5.1 4.4)
			(end 5.1 -3.9)
			(stroke
				(width 0.05)
				(type solid)
			)
			(fill none)
			(layer "B.CrtYd")
		)
		(fp_line
			(start 4.788 3.676)
			(end -4.79 3.676)
			(stroke
				(width 0.15)
				(type solid)
			)
			(layer "B.Fab")
		)
		(fp_line
			(start 4.788 -3.854)
			(end 4.788 3.676)
			(stroke
				(width 0.15)
				(type solid)
			)
			(layer "B.Fab")
		)
		(fp_line
			(start 4.788 -3.854)
			(end -4.702 -3.854)
			(stroke
				(width 0.15)
				(type solid)
			)
			(layer "B.Fab")
		)
		(fp_line
			(start -4.79 3.676)
			(end -4.79 -3.854)
			(stroke
				(width 0.15)
				(type solid)
			)
			(layer "B.Fab")
		)
		(fp_line
			(start -4.79 -3.854)
			(end 4.788 -3.854)
			(stroke
				(width 0.15)
				(type solid)
			)
			(layer "B.Fab")
		)
		(fp_text user "${REFERENCE}"
			(at -4.79 -6.853 0)
			(layer "B.Fab")
			(hide yes)
			(effects
				(font
					(size 0.7 0.7)
					(thickness 0.15)
				)
				(justify left bottom mirror)
			)
		)
		(fp_text user "License: Apache-2.0"
			(at -4.79 -8.855 0)
			(layer "B.Fab")
			(hide yes)
			(effects
				(font
					(size 0.7 0.7)
					(thickness 0.15)
				)
				(justify left bottom mirror)
			)
		)
		(fp_text user "Author: Antmicro"
			(at -4.79 -7.853 0)
			(layer "B.Fab")
			(hide yes)
			(effects
				(font
					(size 0.7 0.7)
					(thickness 0.15)
				)
				(justify left bottom mirror)
			)
		)
		(fp_text user "PCB-EDGE"
			(at -4.79 -5.853 0)
			(layer "B.Fab")
			(hide yes)
			(effects
				(font
					(size 0.7 0.7)
					(thickness 0.15)
				)
				(justify left bottom mirror)
			)
		)
		(pad "" np_thru_hole circle
			(at -2.891 2.426 180)
			(size 0.65 0.65)
			(drill 0.65)
			(layers "*.Cu" "*.Mask")
		)
		(pad "" np_thru_hole circle
			(at 2.89 2.426 180)
			(size 0.65 0.65)
			(drill 0.65)
			(layers "*.Cu" "*.Mask")
		)
		(pad "A1" smd roundrect
			(at -3.202 3.5 180)
			(size 0.6 1.15)
			(layers "B.Cu" "B.Paste" "B.Mask")
			(roundrect_rratio 0.25)
			(net 1 "GND")
			(pinfunction "GND")
			(pintype "power_in")
		)
		(pad "A4" smd roundrect
			(at -2.4 3.5 180)
			(size 0.6 1.15)
			(layers "B.Cu" "B.Paste" "B.Mask")
			(roundrect_rratio 0.25)
			(net 196 "/USB Debug, DP/USBC3_VBUS")
			(pinfunction "VBUS")
			(pintype "passive")
		)
		(pad "A5" smd roundrect
			(at -1.25 3.5 180)
			(size 0.3 1.15)
			(layers "B.Cu" "B.Paste" "B.Mask")
			(roundrect_rratio 0.25)
			(net 273 "/USB Debug, DP/USBC3_CC1")
			(pinfunction "CC_{1}")
			(pintype "bidirectional")
		)
		(pad "A6" smd roundrect
			(at -0.25 3.5 180)
			(size 0.3 1.15)
			(layers "B.Cu" "B.Paste" "B.Mask")
			(roundrect_rratio 0.25)
			(net 613 "/USB Debug, DP/USBC3_D_P")
			(pinfunction "D_{A}+")
			(pintype "bidirectional")
		)
		(pad "A7" smd roundrect
			(at 0.248 3.5 180)
			(size 0.3 1.15)
			(layers "B.Cu" "B.Paste" "B.Mask")
			(roundrect_rratio 0.25)
			(net 275 "/USB Debug, DP/USBC3_D_N")
			(pinfunction "D_{A}-")
			(pintype "bidirectional")
		)
		(pad "A8" smd roundrect
			(at 1.249 3.5 180)
			(size 0.3 1.15)
			(layers "B.Cu" "B.Paste" "B.Mask")
			(roundrect_rratio 0.25)
			(net 533 "unconnected-(J3-SBU_{1}-PadA8)")
			(pinfunction "SBU_{1}")
			(pintype "bidirectional+no_connect")
		)
		(pad "A9" smd roundrect
			(at 2.398 3.5 180)
			(size 0.6 1.15)
			(layers "B.Cu" "B.Paste" "B.Mask")
			(roundrect_rratio 0.25)
			(net 196 "/USB Debug, DP/USBC3_VBUS")
			(pinfunction "VBUS")
			(pintype "passive")
		)
		(pad "A12" smd roundrect
			(at 3.2 3.5 180)
			(size 0.6 1.15)
			(layers "B.Cu" "B.Paste" "B.Mask")
			(roundrect_rratio 0.25)
			(net 1 "GND")
			(pinfunction "GND")
			(pintype "passive")
		)
		(pad "B1" smd roundrect
			(at 3.2 3.5 180)
			(size 0.6 1.15)
			(layers "B.Cu" "B.Paste" "B.Mask")
			(roundrect_rratio 0.25)
			(net 1 "GND")
			(pinfunction "GND")
			(pintype "passive")
		)
		(pad "B4" smd roundrect
			(at 2.398 3.5 180)
			(size 0.6 1.15)
			(layers "B.Cu" "B.Paste" "B.Mask")
			(roundrect_rratio 0.25)
			(net 196 "/USB Debug, DP/USBC3_VBUS")
			(pinfunction "VBUS")
			(pintype "passive")
		)
		(pad "B5" smd roundrect
			(at 1.749 3.5 180)
			(size 0.3 1.15)
			(layers "B.Cu" "B.Paste" "B.Mask")
			(roundrect_rratio 0.25)
			(net 276 "/USB Debug, DP/USBC3_CC2")
			(pinfunction "CC_{2}")
			(pintype "bidirectional")
		)
		(pad "B6" smd roundrect
			(at 0.748 3.5 180)
			(size 0.3 1.15)
			(layers "B.Cu" "B.Paste" "B.Mask")
			(roundrect_rratio 0.25)
			(net 613 "/USB Debug, DP/USBC3_D_P")
			(pinfunction "D_{B}+")
			(pintype "bidirectional")
		)
		(pad "B7" smd roundrect
			(at -0.75 3.5 180)
			(size 0.3 1.15)
			(layers "B.Cu" "B.Paste" "B.Mask")
			(roundrect_rratio 0.25)
			(net 275 "/USB Debug, DP/USBC3_D_N")
			(pinfunction "D_{B}-")
			(pintype "bidirectional")
		)
		(pad "B8" smd roundrect
			(at -1.75 3.5 180)
			(size 0.3 1.15)
			(layers "B.Cu" "B.Paste" "B.Mask")
			(roundrect_rratio 0.25)
			(net 547 "unconnected-(J3-SBU_{2}-PadB8)")
			(pinfunction "SBU_{2}")
			(pintype "bidirectional+no_connect")
		)
		(pad "B9" smd roundrect
			(at -2.4 3.5 180)
			(size 0.6 1.15)
			(layers "B.Cu" "B.Paste" "B.Mask")
			(roundrect_rratio 0.25)
			(net 196 "/USB Debug, DP/USBC3_VBUS")
			(pinfunction "VBUS")
			(pintype "passive")
		)
		(pad "B12" smd roundrect
			(at -3.202 3.5 180)
			(size 0.6 1.15)
			(layers "B.Cu" "B.Paste" "B.Mask")
			(roundrect_rratio 0.25)
			(net 1 "GND")
			(pinfunction "GND")
			(pintype "passive")
		)
		(pad "SH" thru_hole oval
			(at -4.321 -1.255 180)
			(size 1 2)
			(drill oval 0.6 1.4)
			(layers "*.Cu" "*.Mask")
			(remove_unused_layers no)
			(net 1 "GND")
			(pinfunction "SH")
			(pintype "passive")
		)
		(pad "SH" thru_hole oval
			(at -4.321 2.926 180)
			(size 1.05 2.1)
			(drill oval 0.6 1.7)
			(layers "*.Cu" "*.Mask")
			(remove_unused_layers no)
			(net 1 "GND")
			(pinfunction "SH")
			(pintype "passive")
		)
		(pad "SH" thru_hole oval
			(at 4.32 -1.255 180)
			(size 1 2)
			(drill oval 0.6 1.4)
			(layers "*.Cu" "*.Mask")
			(remove_unused_layers no)
			(net 1 "GND")
			(pinfunction "SH")
			(pintype "passive")
		)
		(pad "SH" thru_hole oval
			(at 4.32 2.926 180)
			(size 1.05 2.1)
			(drill oval 0.6 1.7)
			(layers "*.Cu" "*.Mask")
			(remove_unused_layers no)
			(net 1 "GND")
			(pinfunction "SH")
			(pintype "passive")
		)
	)
	(footprint "antmicro-footprints:R_0402_1005Metric"
		(layer "B.Cu")
		(at 50.4 74.3 -90)
		(descr "Resistor SMD 0402")
		(tags "resistor SMD 0402")
		(property "Reference" "R285"
			(at 0.6 -1.4 90)
			(layer "B.SilkS")
			(effects
				(font
					(size 0.7 0.7)
					(thickness 0.15)
				)
				(justify left bottom mirror)
			)
		)
		(property "Value" "R_100k_0402"
			(at -1.011843 -1.772046 90)
			(layer "B.Fab")
			(effects
				(font
					(size 0.7 0.7)
					(thickness 0.15)
				)
				(justify left bottom mirror)
			)
		)
		(property "Footprint" "antmicro-footprints:R_0402_1005Metric"
			(at 0 0 90)
			(layer "B.Fab")
			(hide yes)
			(effects
				(font
					(size 1.27 1.27)
					(thickness 0.15)
				)
				(justify mirror)
			)
		)
		(property "Datasheet" "https://www.bourns.com/docs/product-datasheets/cr.pdf"
			(at 0 0 90)
			(layer "B.Fab")
			(hide yes)
			(effects
				(font
					(size 1.27 1.27)
					(thickness 0.15)
				)
				(justify mirror)
			)
		)
		(property "Manufacturer" "Bourns"
			(at 0 0 90)
			(unlocked yes)
			(layer "B.Fab")
			(hide yes)
			(effects
				(font
					(size 1 1)
					(thickness 0.15)
				)
				(justify mirror)
			)
		)
		(property "MPN" "CR0402-FX-1003GLF"
			(at 0 0 90)
			(unlocked yes)
			(layer "B.Fab")
			(hide yes)
			(effects
				(font
					(size 1 1)
					(thickness 0.15)
				)
				(justify mirror)
			)
		)
		(property "Val" "100k"
			(at 0 0 90)
			(unlocked yes)
			(layer "B.Fab")
			(hide yes)
			(effects
				(font
					(size 1 1)
					(thickness 0.15)
				)
				(justify mirror)
			)
		)
		(property "License" "Apache-2.0"
			(at 0 0 90)
			(unlocked yes)
			(layer "B.Fab")
			(hide yes)
			(effects
				(font
					(size 1 1)
					(thickness 0.15)
				)
				(justify mirror)
			)
		)
		(property "Author" "Antmicro"
			(at 0 0 90)
			(unlocked yes)
			(layer "B.Fab")
			(hide yes)
			(effects
				(font
					(size 1 1)
					(thickness 0.15)
				)
				(justify mirror)
			)
		)
		(property "Tolerance" "1%"
			(at 0 0 90)
			(unlocked yes)
			(layer "B.Fab")
			(hide yes)
			(effects
				(font
					(size 1 1)
					(thickness 0.15)
				)
				(justify mirror)
			)
		)
		(sheetname "Supply")
		(sheetfile "supply.kicad_sch")
		(attr smd)
		(fp_poly
			(pts
				(xy -0.925 0.47) (xy 0.925 0.47) (xy 0.925 -0.47) (xy -0.925 -0.47)
			)
			(stroke
				(width 0.05)
				(type default)
			)
			(fill none)
			(layer "B.CrtYd")
		)
		(fp_poly
			(pts
				(xy -0.5 0.25) (xy 0.5 0.25) (xy 0.5 -0.25) (xy -0.5 -0.25)
			)
			(stroke
				(width 0.15)
				(type solid)
			)
			(fill none)
			(layer "B.Fab")
		)
		(fp_text user "License: Apache-2.0"
			(at -0.949999 -5.169 90)
			(layer "B.Fab")
			(hide yes)
			(effects
				(font
					(size 0.7 0.7)
					(thickness 0.15)
				)
				(justify left bottom mirror)
			)
		)
		(fp_text user "${REFERENCE}"
			(at -0.95 -3.168 90)
			(layer "B.Fab")
			(hide yes)
			(effects
				(font
					(size 0.7 0.7)
					(thickness 0.15)
				)
				(justify left bottom mirror)
			)
		)
		(fp_text user "Author: Antmicro"
			(at -0.95 -4.169 90)
			(layer "B.Fab")
			(hide yes)
			(effects
				(font
					(size 0.7 0.7)
					(thickness 0.15)
				)
				(justify left bottom mirror)
			)
		)
		(pad "1" smd roundrect
			(at -0.48 0 270)
			(size 0.59 0.64)
			(layers "B.Cu" "B.Paste" "B.Mask")
			(roundrect_rratio 0.25)
			(net 1 "GND")
			(pintype "passive")
		)
		(pad "2" smd roundrect
			(at 0.48 0 270)
			(size 0.59 0.64)
			(layers "B.Cu" "B.Paste" "B.Mask")
			(roundrect_rratio 0.25)
			(net 799 "/Supply/PG_{HP}")
			(pintype "passive")
		)
	)
	(footprint "antmicro-footprints:R_0402_1005Metric"
		(layer "B.Cu")
		(at 88.05 103.1 -135)
		(descr "Resistor SMD 0402")
		(tags "resistor SMD 0402")
		(property "Reference" "R180"
			(at -1.52028 0.388909 45)
			(layer "B.SilkS")
			(effects
				(font
					(size 0.7 0.7)
					(thickness 0.15)
				)
				(justify left bottom mirror)
			)
		)
		(property "Value" "R_100k_0402"
			(at 0 -1.399999 45)
			(layer "B.Fab")
			(effects
				(font
					(size 0.7 0.7)
					(thickness 0.15)
				)
				(justify left bottom mirror)
			)
		)
		(property "Footprint" "antmicro-footprints:R_0402_1005Metric"
			(at 0 0 -135)
			(layer "F.Fab")
			(hide yes)
			(effects
				(font
					(size 1.27 1.27)
					(thickness 0.15)
				)
			)
		)
		(property "Datasheet" "https://www.bourns.com/docs/product-datasheets/cr.pdf"
			(at 0 0 -135)
			(layer "F.Fab")
			(hide yes)
			(effects
				(font
					(size 1.27 1.27)
					(thickness 0.15)
				)
			)
		)
		(property "Author" "Antmicro"
			(at 77.408043 238.263461 0)
			(layer "B.Fab")
			(hide yes)
			(effects
				(font
					(size 1 1)
					(thickness 0.15)
				)
				(justify mirror)
			)
		)
		(property "License" "Apache-2.0"
			(at 77.408043 238.263461 0)
			(layer "B.Fab")
			(hide yes)
			(effects
				(font
					(size 1 1)
					(thickness 0.15)
				)
				(justify mirror)
			)
		)
		(property "MPN" "CR0402-FX-1003GLF"
			(at 77.408043 238.263461 0)
			(layer "B.Fab")
			(hide yes)
			(effects
				(font
					(size 1 1)
					(thickness 0.15)
				)
				(justify mirror)
			)
		)
		(property "Manufacturer" "Bourns"
			(at 77.408043 238.263461 0)
			(layer "B.Fab")
			(hide yes)
			(effects
				(font
					(size 1 1)
					(thickness 0.15)
				)
				(justify mirror)
			)
		)
		(property "Tolerance" "1%"
			(at 77.408043 238.263461 0)
			(layer "B.Fab")
			(hide yes)
			(effects
				(font
					(size 1 1)
					(thickness 0.15)
				)
				(justify mirror)
			)
		)
		(property "Val" "100k"
			(at 77.408043 238.263461 0)
			(layer "B.Fab")
			(hide yes)
			(effects
				(font
					(size 1 1)
					(thickness 0.15)
				)
				(justify mirror)
			)
		)
		(sheetname "CSI")
		(sheetfile "csi.kicad_sch")
		(attr smd)
		(fp_poly
			(pts
				(xy -0.925 0.47) (xy 0.925 0.47) (xy 0.925 -0.47) (xy -0.925 -0.47)
			)
			(stroke
				(width 0.05)
				(type default)
			)
			(fill none)
			(layer "B.CrtYd")
		)
		(fp_poly
			(pts
				(xy -0.5 0.25) (xy 0.5 0.25) (xy 0.5 -0.25) (xy -0.5 -0.25)
			)
			(stroke
				(width 0.15)
				(type solid)
			)
			(fill none)
			(layer "B.Fab")
		)
		(fp_text user "${REFERENCE}"
			(at -0.95 -3.168 45)
			(layer "B.Fab")
			(hide yes)
			(effects
				(font
					(size 0.7 0.7)
					(thickness 0.15)
				)
				(justify left bottom mirror)
			)
		)
		(fp_text user "Author: Antmicro"
			(at -0.95 -4.169 45)
			(layer "B.Fab")
			(hide yes)
			(effects
				(font
					(size 0.7 0.7)
					(thickness 0.15)
				)
				(justify left bottom mirror)
			)
		)
		(fp_text user "License: Apache-2.0"
			(at -0.949999 -5.169 45)
			(layer "B.Fab")
			(hide yes)
			(effects
				(font
					(size 0.7 0.7)
					(thickness 0.15)
				)
				(justify left bottom mirror)
			)
		)
		(pad "1" smd roundrect
			(at -0.48 0 225)
			(size 0.59 0.64)
			(layers "B.Cu" "B.Paste" "B.Mask")
			(roundrect_rratio 0.25)
			(net 1 "GND")
			(pintype "passive")
		)
		(pad "2" smd roundrect
			(at 0.48 0 225)
			(size 0.59 0.64)
			(layers "B.Cu" "B.Paste" "B.Mask")
			(roundrect_rratio 0.25)
			(net 338 "CSIB_PEN")
			(pintype "passive")
		)
	)
	(footprint "antmicro-footprints:C_2220_5650Metric"
		(layer "B.Cu")
		(at 33.8 83.6 180)
		(descr "Capacitor SMD 2220")
		(tags "capacitor SMD 2220")
		(property "Reference" "C81"
			(at -1.85 3.12 0)
			(layer "B.SilkS")
			(effects
				(font
					(size 0.7 0.7)
					(thickness 0.15)
				)
				(justify left bottom mirror)
			)
		)
		(property "Value" "C_22u_100V_2220"
			(at 0 -3.9 0)
			(layer "B.Fab")
			(effects
				(font
					(size 0.7 0.7)
					(thickness 0.15)
				)
				(justify left bottom mirror)
			)
		)
		(property "Footprint" "antmicro-footprints:C_2220_5650Metric"
			(at 0 0 180)
			(layer "F.Fab")
			(hide yes)
			(effects
				(font
					(size 1.27 1.27)
					(thickness 0.15)
				)
			)
		)
		(property "Datasheet" "https://product.tdk.com/en/search/capacitor/ceramic/mlcc/info?part_no=C5750X7S2A226M280KB"
			(at 0 0 180)
			(layer "F.Fab")
			(hide yes)
			(effects
				(font
					(size 1.27 1.27)
					(thickness 0.15)
				)
			)
		)
		(property "Author" "Antmicro"
			(at 67.6 167.2 0)
			(layer "B.Fab")
			(hide yes)
			(effects
				(font
					(size 1 1)
					(thickness 0.15)
				)
				(justify mirror)
			)
		)
		(property "Dielectric" "X7S"
			(at 67.6 167.2 0)
			(layer "B.Fab")
			(hide yes)
			(effects
				(font
					(size 1 1)
					(thickness 0.15)
				)
				(justify mirror)
			)
		)
		(property "License" "Apache-2.0"
			(at 67.6 167.2 0)
			(layer "B.Fab")
			(hide yes)
			(effects
				(font
					(size 1 1)
					(thickness 0.15)
				)
				(justify mirror)
			)
		)
		(property "MPN" "C5750X7S2A226M280KB"
			(at 67.6 167.2 0)
			(layer "B.Fab")
			(hide yes)
			(effects
				(font
					(size 1 1)
					(thickness 0.15)
				)
				(justify mirror)
			)
		)
		(property "Manufacturer" "TDK"
			(at 67.6 167.2 0)
			(layer "B.Fab")
			(hide yes)
			(effects
				(font
					(size 1 1)
					(thickness 0.15)
				)
				(justify mirror)
			)
		)
		(property "Public" "False"
			(at 67.6 167.2 0)
			(layer "B.Fab")
			(hide yes)
			(effects
				(font
					(size 1 1)
					(thickness 0.15)
				)
				(justify mirror)
			)
		)
		(property "Val" "22u"
			(at 67.6 167.2 0)
			(layer "B.Fab")
			(hide yes)
			(effects
				(font
					(size 1 1)
					(thickness 0.15)
				)
				(justify mirror)
			)
		)
		(property "Voltage" "100V"
			(at 67.6 167.2 0)
			(layer "B.Fab")
			(hide yes)
			(effects
				(font
					(size 1 1)
					(thickness 0.15)
				)
				(justify mirror)
			)
		)
		(sheetname "Ethernet")
		(sheetfile "ethernet.kicad_sch")
		(attr smd)
		(fp_line
			(start 1.415 2.61)
			(end -1.415 2.61)
			(stroke
				(width 0.15)
				(type solid)
			)
			(layer "B.SilkS")
		)
		(fp_line
			(start 1.415 -2.61)
			(end -1.415 -2.61)
			(stroke
				(width 0.15)
				(type solid)
			)
			(layer "B.SilkS")
		)
		(fp_rect
			(start -3.7 2.95)
			(end 3.7 -2.95)
			(stroke
				(width 0.05)
				(type solid)
			)
			(fill none)
			(layer "B.CrtYd")
		)
		(fp_rect
			(start -2.85 2.5)
			(end 2.85 -2.5)
			(stroke
				(width 0.15)
				(type solid)
			)
			(fill none)
			(layer "B.Fab")
		)
		(fp_text user "${REFERENCE}"
			(at -3.7 -5.9 0)
			(layer "B.Fab")
			(hide yes)
			(effects
				(font
					(size 0.7 0.7)
					(thickness 0.15)
				)
				(justify left bottom mirror)
			)
		)
		(fp_text user "Author: Antmicro"
			(at -3.7 -7.9 0)
			(layer "B.Fab")
			(hide yes)
			(effects
				(font
					(size 0.7 0.7)
					(thickness 0.15)
				)
				(justify left bottom mirror)
			)
		)
		(fp_text user "License: Apache-2.0"
			(at -3.7 -6.9 0)
			(layer "B.Fab")
			(hide yes)
			(effects
				(font
					(size 0.7 0.7)
					(thickness 0.15)
				)
				(justify left bottom mirror)
			)
		)
		(pad "1" smd roundrect
			(at -2.55 0 180)
			(size 1.8 5.4)
			(layers "B.Cu" "B.Paste" "B.Mask")
			(roundrect_rratio 0.138889)
			(net 106 "GNDD")
			(pintype "passive")
		)
		(pad "2" smd roundrect
			(at 2.55 0 180)
			(size 1.8 5.4)
			(layers "B.Cu" "B.Paste" "B.Mask")
			(roundrect_rratio 0.138889)
			(net 105 "/Ethernet/VDD")
			(pintype "passive")
		)
	)
	(footprint "antmicro-footprints:R_Array_4x0201_Panasonic_EXB18V"
		(layer "B.Cu")
		(at 96.33 103.6)
		(property "Reference" "R36"
			(at -2.62 1.42 180)
			(layer "B.SilkS")
			(effects
				(font
					(size 0.7 0.7)
					(thickness 0.15)
				)
				(justify right bottom mirror)
			)
		)
		(property "Value" "R_4x2k2_0201_array"
			(at -1.1 -1.8 180)
			(layer "B.Fab")
			(effects
				(font
					(size 0.7 0.7)
					(thickness 0.15)
				)
				(justify left bottom mirror)
			)
		)
		(property "Footprint" "antmicro-footprints:R_Array_4x0201_Panasonic_EXB18V"
			(at 0 0 0)
			(layer "F.Fab")
			(hide yes)
			(effects
				(font
					(size 1.27 1.27)
					(thickness 0.15)
				)
			)
		)
		(property "Datasheet" "http://industrial.panasonic.com/cdbs/www-data/pdf/AOC0000/AOC0000C14.pdf"
			(at 0 0 0)
			(layer "F.Fab")
			(hide yes)
			(effects
				(font
					(size 1.27 1.27)
					(thickness 0.15)
				)
			)
		)
		(property "Author" "Antmicro"
			(at 0 0 0)
			(layer "B.Fab")
			(hide yes)
			(effects
				(font
					(size 1 1)
					(thickness 0.15)
				)
				(justify mirror)
			)
		)
		(property "License" "Apache-2.0"
			(at 0 0 0)
			(layer "B.Fab")
			(hide yes)
			(effects
				(font
					(size 1 1)
					(thickness 0.15)
				)
				(justify mirror)
			)
		)
		(property "MPN" "EXB-18V222JX"
			(at 0 0 0)
			(layer "B.Fab")
			(hide yes)
			(effects
				(font
					(size 1 1)
					(thickness 0.15)
				)
				(justify mirror)
			)
		)
		(property "Manufacturer" "Panasonic"
			(at 0 0 0)
			(layer "B.Fab")
			(hide yes)
			(effects
				(font
					(size 1 1)
					(thickness 0.15)
				)
				(justify mirror)
			)
		)
		(property "Val" "4x2k2_0201"
			(at 0 0 0)
			(layer "B.Fab")
			(hide yes)
			(effects
				(font
					(size 1 1)
					(thickness 0.15)
				)
				(justify mirror)
			)
		)
		(sheetname "CSI")
		(sheetfile "csi.kicad_sch")
		(attr smd)
		(fp_line
			(start -0.8 -0.45)
			(end -0.8 0.45)
			(stroke
				(width 0.12)
				(type solid)
			)
			(layer "B.SilkS")
		)
		(fp_line
			(start 0.8 -0.45)
			(end 0.8 0.45)
			(stroke
				(width 0.12)
				(type solid)
			)
			(layer "B.SilkS")
		)
		(fp_rect
			(start -0.898 0.66)
			(end 0.898 -0.65)
			(stroke
				(width 0.05)
				(type solid)
			)
			(fill none)
			(layer "B.CrtYd")
		)
		(fp_text user "License: Apache-2.0"
			(at -1.051 -6 180)
			(layer "B.Fab")
			(hide yes)
			(effects
				(font
					(size 0.7 0.7)
					(thickness 0.15)
				)
				(justify left bottom mirror)
			)
		)
		(fp_text user "${REFERENCE}"
			(at -1.051 -3.2 180)
			(layer "B.Fab")
			(hide yes)
			(effects
				(font
					(size 0.7 0.7)
					(thickness 0.15)
				)
				(justify left bottom mirror)
			)
		)
		(fp_text user "Author: Antmicro"
			(at -1.051 -4.599 180)
			(layer "B.Fab")
			(hide yes)
			(effects
				(font
					(size 0.7 0.7)
					(thickness 0.15)
				)
				(justify left bottom mirror)
			)
		)
		(pad "1" smd roundrect
			(at -0.6 -0.298)
			(size 0.2 0.4)
			(layers "B.Cu" "B.Paste" "B.Mask")
			(roundrect_rratio 0.25)
			(net 330 "/CSI/SCL_CAM1")
			(pinfunction "R1.1")
			(pintype "passive")
		)
		(pad "2" smd roundrect
			(at -0.202 -0.298)
			(size 0.2 0.4)
			(layers "B.Cu" "B.Paste" "B.Mask")
			(roundrect_rratio 0.25)
			(net 329 "/CSI/SDA_CAM1")
			(pinfunction "R2.1")
			(pintype "passive")
		)
		(pad "3" smd roundrect
			(at 0.2 -0.298)
			(size 0.2 0.4)
			(layers "B.Cu" "B.Paste" "B.Mask")
			(roundrect_rratio 0.25)
			(net 323 "/CSI/SCL_CAM0")
			(pinfunction "R3.1")
			(pintype "passive")
		)
		(pad "4" smd roundrect
			(at 0.598 -0.298)
			(size 0.2 0.4)
			(layers "B.Cu" "B.Paste" "B.Mask")
			(roundrect_rratio 0.25)
			(net 320 "/CSI/SDA_CAM0")
			(pinfunction "R4.1")
			(pintype "passive")
		)
		(pad "5" smd roundrect
			(at 0.598 0.3)
			(size 0.2 0.4)
			(layers "B.Cu" "B.Paste" "B.Mask")
			(roundrect_rratio 0.25)
			(net 321 "/CSI/CSIA_I2C_VCC")
			(pinfunction "R4.2")
			(pintype "passive")
		)
		(pad "6" smd roundrect
			(at 0.2 0.3)
			(size 0.2 0.4)
			(layers "B.Cu" "B.Paste" "B.Mask")
			(roundrect_rratio 0.25)
			(net 321 "/CSI/CSIA_I2C_VCC")
			(pinfunction "R3.2")
			(pintype "passive")
		)
		(pad "7" smd roundrect
			(at -0.202 0.3)
			(size 0.2 0.4)
			(layers "B.Cu" "B.Paste" "B.Mask")
			(roundrect_rratio 0.25)
			(net 321 "/CSI/CSIA_I2C_VCC")
			(pinfunction "R2.2")
			(pintype "passive")
		)
		(pad "8" smd roundrect
			(at -0.6 0.3)
			(size 0.2 0.4)
			(layers "B.Cu" "B.Paste" "B.Mask")
			(roundrect_rratio 0.25)
			(net 321 "/CSI/CSIA_I2C_VCC")
			(pinfunction "R1.2")
			(pintype "passive")
		)
	)
	(footprint "antmicro-footprints:R_0402_1005Metric"
		(layer "B.Cu")
		(at 76 110.2 -90)
		(descr "Resistor SMD 0402")
		(tags "resistor SMD 0402")
		(property "Reference" "R95"
			(at 0.76 -2.4 90)
			(layer "B.SilkS")
			(effects
				(font
					(size 0.7 0.7)
					(thickness 0.15)
				)
				(justify left bottom mirror)
			)
		)
		(property "Value" "R_1k_0402"
			(at 0 -1.4 90)
			(layer "B.Fab")
			(effects
				(font
					(size 0.7 0.7)
					(thickness 0.15)
				)
				(justify left bottom mirror)
			)
		)
		(property "Footprint" "antmicro-footprints:R_0402_1005Metric"
			(at 0 0 -90)
			(layer "F.Fab")
			(hide yes)
			(effects
				(font
					(size 1.27 1.27)
					(thickness 0.15)
				)
			)
		)
		(property "Datasheet" "https://www.bourns.com/docs/product-datasheets/cr.pdf"
			(at 0 0 -90)
			(layer "F.Fab")
			(hide yes)
			(effects
				(font
					(size 1.27 1.27)
					(thickness 0.15)
				)
			)
		)
		(property "Author" "Antmicro"
			(at -34.2 186.2 0)
			(layer "B.Fab")
			(hide yes)
			(effects
				(font
					(size 1 1)
					(thickness 0.15)
				)
				(justify mirror)
			)
		)
		(property "License" "Apache-2.0"
			(at -34.2 186.2 0)
			(layer "B.Fab")
			(hide yes)
			(effects
				(font
					(size 1 1)
					(thickness 0.15)
				)
				(justify mirror)
			)
		)
		(property "MPN" "CR0402-FX-1001GLF"
			(at -34.2 186.2 0)
			(layer "B.Fab")
			(hide yes)
			(effects
				(font
					(size 1 1)
					(thickness 0.15)
				)
				(justify mirror)
			)
		)
		(property "Manufacturer" "Bourns"
			(at -34.2 186.2 0)
			(layer "B.Fab")
			(hide yes)
			(effects
				(font
					(size 1 1)
					(thickness 0.15)
				)
				(justify mirror)
			)
		)
		(property "Tolerance" "1%"
			(at -34.2 186.2 0)
			(layer "B.Fab")
			(hide yes)
			(effects
				(font
					(size 1 1)
					(thickness 0.15)
				)
				(justify mirror)
			)
		)
		(property "Val" "1k"
			(at -34.2 186.2 0)
			(layer "B.Fab")
			(hide yes)
			(effects
				(font
					(size 1 1)
					(thickness 0.15)
				)
				(justify mirror)
			)
		)
		(sheetname "USB Debug, DP")
		(sheetfile "usb.kicad_sch")
		(attr smd exclude_from_pos_files exclude_from_bom dnp)
		(fp_rect
			(start -0.925 0.47)
			(end 0.925 -0.47)
			(stroke
				(width 0.05)
				(type default)
			)
			(fill none)
			(layer "B.CrtYd")
		)
		(fp_rect
			(start -0.5 0.25)
			(end 0.5 -0.25)
			(stroke
				(width 0.15)
				(type solid)
			)
			(fill none)
			(layer "B.Fab")
		)
		(fp_text user "${REFERENCE}"
			(at -0.95 -3.168 90)
			(layer "B.Fab")
			(hide yes)
			(effects
				(font
					(size 0.7 0.7)
					(thickness 0.15)
				)
				(justify left bottom mirror)
			)
		)
		(fp_text user "License: Apache-2.0"
			(at -0.95 -5.169 90)
			(layer "B.Fab")
			(hide yes)
			(effects
				(font
					(size 0.7 0.7)
					(thickness 0.15)
				)
				(justify left bottom mirror)
			)
		)
		(fp_text user "Author: Antmicro"
			(at -0.95 -4.169 90)
			(layer "B.Fab")
			(hide yes)
			(effects
				(font
					(size 0.7 0.7)
					(thickness 0.15)
				)
				(justify left bottom mirror)
			)
		)
		(pad "1" smd roundrect
			(at -0.48 0 270)
			(size 0.59 0.64)
			(layers "B.Cu" "B.Paste" "B.Mask")
			(roundrect_rratio 0.25)
			(net 309 "/USB Debug, DP/USBC0_EQ0")
			(pintype "passive")
		)
		(pad "2" smd roundrect
			(at 0.48 0 270)
			(size 0.59 0.64)
			(layers "B.Cu" "B.Paste" "B.Mask")
			(roundrect_rratio 0.25)
			(net 87 "+3V3")
			(pintype "passive")
		)
	)
	(footprint "antmicro-footprints:R_0402_1005Metric"
		(layer "B.Cu")
		(at 138.65 117.55)
		(descr "Resistor SMD 0402")
		(tags "resistor SMD 0402")
		(property "Reference" "R6"
			(at 0.7 1.3 180)
			(layer "B.SilkS")
			(effects
				(font
					(size 0.7 0.7)
					(thickness 0.15)
				)
				(justify left bottom mirror)
			)
		)
		(property "Value" "R_100k_0402"
			(at 0 -1.4 180)
			(layer "B.Fab")
			(effects
				(font
					(size 0.7 0.7)
					(thickness 0.15)
				)
				(justify left bottom mirror)
			)
		)
		(property "Footprint" "antmicro-footprints:R_0402_1005Metric"
			(at 0 0 0)
			(layer "F.Fab")
			(hide yes)
			(effects
				(font
					(size 1.27 1.27)
					(thickness 0.15)
				)
			)
		)
		(property "Datasheet" "https://www.bourns.com/docs/product-datasheets/cr.pdf"
			(at 0 0 0)
			(layer "F.Fab")
			(hide yes)
			(effects
				(font
					(size 1.27 1.27)
					(thickness 0.15)
				)
			)
		)
		(property "Author" "Antmicro"
			(at 0 0 0)
			(layer "B.Fab")
			(hide yes)
			(effects
				(font
					(size 1 1)
					(thickness 0.15)
				)
				(justify mirror)
			)
		)
		(property "License" "Apache-2.0"
			(at 0 0 0)
			(layer "B.Fab")
			(hide yes)
			(effects
				(font
					(size 1 1)
					(thickness 0.15)
				)
				(justify mirror)
			)
		)
		(property "MPN" "CR0402-FX-1003GLF"
			(at 0 0 0)
			(layer "B.Fab")
			(hide yes)
			(effects
				(font
					(size 1 1)
					(thickness 0.15)
				)
				(justify mirror)
			)
		)
		(property "Manufacturer" "Bourns"
			(at 0 0 0)
			(layer "B.Fab")
			(hide yes)
			(effects
				(font
					(size 1 1)
					(thickness 0.15)
				)
				(justify mirror)
			)
		)
		(property "Tolerance" "1%"
			(at 0 0 0)
			(layer "B.Fab")
			(hide yes)
			(effects
				(font
					(size 1 1)
					(thickness 0.15)
				)
				(justify mirror)
			)
		)
		(property "Val" "100k"
			(at 0 0 0)
			(layer "B.Fab")
			(hide yes)
			(effects
				(font
					(size 1 1)
					(thickness 0.15)
				)
				(justify mirror)
			)
		)
		(sheetname "CSI")
		(sheetfile "csi.kicad_sch")
		(attr smd)
		(fp_rect
			(start -0.925 0.47)
			(end 0.925 -0.47)
			(stroke
				(width 0.05)
				(type default)
			)
			(fill none)
			(layer "B.CrtYd")
		)
		(fp_rect
			(start -0.5 0.25)
			(end 0.5 -0.25)
			(stroke
				(width 0.15)
				(type solid)
			)
			(fill none)
			(layer "B.Fab")
		)
		(fp_text user "${REFERENCE}"
			(at -0.95 -3.168 180)
			(layer "B.Fab")
			(hide yes)
			(effects
				(font
					(size 0.7 0.7)
					(thickness 0.15)
				)
				(justify left bottom mirror)
			)
		)
		(fp_text user "Author: Antmicro"
			(at -0.95 -4.169 180)
			(layer "B.Fab")
			(hide yes)
			(effects
				(font
					(size 0.7 0.7)
					(thickness 0.15)
				)
				(justify left bottom mirror)
			)
		)
		(fp_text user "License: Apache-2.0"
			(at -0.95 -5.169 180)
			(layer "B.Fab")
			(hide yes)
			(effects
				(font
					(size 0.7 0.7)
					(thickness 0.15)
				)
				(justify left bottom mirror)
			)
		)
		(pad "1" smd roundrect
			(at -0.48 0)
			(size 0.59 0.64)
			(layers "B.Cu" "B.Paste" "B.Mask")
			(roundrect_rratio 0.25)
			(net 1 "GND")
			(pintype "passive")
		)
		(pad "2" smd roundrect
			(at 0.48 0)
			(size 0.59 0.64)
			(layers "B.Cu" "B.Paste" "B.Mask")
			(roundrect_rratio 0.25)
			(net 322 "CSIA_PEN")
			(pintype "passive")
		)
	)
	(footprint "antmicro-footprints:TP_SMD_0.75mm"
		(layer "B.Cu")
		(at 68.165 115.57 180)
		(property "Reference" "TP17"
			(at 0 0.6 0)
			(layer "B.SilkS")
			(hide yes)
			(effects
				(font
					(size 0.7 0.7)
					(thickness 0.15)
				)
				(justify left bottom mirror)
			)
		)
		(property "Value" "TP_0.75mm_SMD"
			(at 0 -1.2 0)
			(layer "B.Fab")
			(effects
				(font
					(size 0.7 0.7)
					(thickness 0.15)
				)
				(justify left bottom mirror)
			)
		)
		(property "Footprint" "antmicro-footprints:TP_SMD_0.75mm"
			(at 0 0 180)
			(layer "F.Fab")
			(hide yes)
			(effects
				(font
					(size 1.27 1.27)
					(thickness 0.15)
				)
			)
		)
		(property "Author" "Antmicro"
			(at 136.33 231.14 0)
			(layer "B.Fab")
			(hide yes)
			(effects
				(font
					(size 1 1)
					(thickness 0.15)
				)
				(justify mirror)
			)
		)
		(property "License" "Apache-2.0"
			(at 136.33 231.14 0)
			(layer "B.Fab")
			(hide yes)
			(effects
				(font
					(size 1 1)
					(thickness 0.15)
				)
				(justify mirror)
			)
		)
		(property "MPN" ""
			(at 136.33 231.14 0)
			(layer "B.Fab")
			(hide yes)
			(effects
				(font
					(size 1 1)
					(thickness 0.15)
				)
				(justify mirror)
			)
		)
		(property "Manufacturer" ""
			(at 136.33 231.14 0)
			(layer "B.Fab")
			(hide yes)
			(effects
				(font
					(size 1 1)
					(thickness 0.15)
				)
				(justify mirror)
			)
		)
		(sheetname "USB Debug, DP")
		(sheetfile "usb.kicad_sch")
		(attr exclude_from_pos_files exclude_from_bom)
		(fp_circle
			(center 0 0)
			(end 0.475 0)
			(stroke
				(width 0.05)
				(type default)
			)
			(fill none)
			(layer "B.CrtYd")
		)
		(fp_text user "Author: Antmicro"
			(at -0.4 -3.901 0)
			(layer "B.Fab")
			(hide yes)
			(effects
				(font
					(size 0.7 0.7)
					(thickness 0.15)
				)
				(justify left bottom mirror)
			)
		)
		(fp_text user "${REFERENCE}"
			(at -0.4 -2.7 0)
			(layer "B.Fab")
			(hide yes)
			(effects
				(font
					(size 0.7 0.7)
					(thickness 0.15)
				)
				(justify left bottom mirror)
			)
		)
		(fp_text user "License: Apache-2.0"
			(at -0.4 -5.101 0)
			(layer "B.Fab")
			(hide yes)
			(effects
				(font
					(size 0.7 0.7)
					(thickness 0.15)
				)
				(justify left bottom mirror)
			)
		)
		(pad "1" smd circle
			(at 0 0 180)
			(size 0.75 0.75)
			(layers "B.Cu" "B.Mask")
			(net 261 "/USB Debug, DP/USBC0_VBUS")
			(pinfunction "1")
			(pintype "passive")
		)
	)
	(footprint "antmicro-footprints:C_0603_1608Metric"
		(layer "B.Cu")
		(at 114.45 77.95 180)
		(descr "Capacitor SMD 0603")
		(tags "capacitor 0603")
		(property "Reference" "C21"
			(at -1.1 0.6 0)
			(layer "B.SilkS")
			(effects
				(font
					(size 0.7 0.7)
					(thickness 0.15)
				)
				(justify left bottom mirror)
			)
		)
		(property "Value" "C_10u_0603"
			(at 0 -1.6 0)
			(layer "B.Fab")
			(effects
				(font
					(size 0.7 0.7)
					(thickness 0.15)
				)
				(justify left bottom mirror)
			)
		)
		(property "Footprint" "antmicro-footprints:C_0603_1608Metric"
			(at 0 0 180)
			(layer "F.Fab")
			(hide yes)
			(effects
				(font
					(size 1.27 1.27)
					(thickness 0.15)
				)
			)
		)
		(property "Datasheet" "https://www.murata.com/products/productdetail?partno=GRM188R61A106KE69%23"
			(at 0 0 180)
			(layer "F.Fab")
			(hide yes)
			(effects
				(font
					(size 1.27 1.27)
					(thickness 0.15)
				)
			)
		)
		(property "Author" "Antmicro"
			(at 228.9 155.9 0)
			(layer "B.Fab")
			(hide yes)
			(effects
				(font
					(size 1 1)
					(thickness 0.15)
				)
				(justify mirror)
			)
		)
		(property "Dielectric" "template_dielectric"
			(at 228.9 155.9 0)
			(layer "B.Fab")
			(hide yes)
			(effects
				(font
					(size 1 1)
					(thickness 0.15)
				)
				(justify mirror)
			)
		)
		(property "License" "Apache-2.0"
			(at 228.9 155.9 0)
			(layer "B.Fab")
			(hide yes)
			(effects
				(font
					(size 1 1)
					(thickness 0.15)
				)
				(justify mirror)
			)
		)
		(property "MPN" "GRM188R61A106KE69D"
			(at 228.9 155.9 0)
			(layer "B.Fab")
			(hide yes)
			(effects
				(font
					(size 1 1)
					(thickness 0.15)
				)
				(justify mirror)
			)
		)
		(property "Manufacturer" "Murata"
			(at 228.9 155.9 0)
			(layer "B.Fab")
			(hide yes)
			(effects
				(font
					(size 1 1)
					(thickness 0.15)
				)
				(justify mirror)
			)
		)
		(property "Val" "10u"
			(at 228.9 155.9 0)
			(layer "B.Fab")
			(hide yes)
			(effects
				(font
					(size 1 1)
					(thickness 0.15)
				)
				(justify mirror)
			)
		)
		(property "Voltage" ""
			(at 228.9 155.9 0)
			(layer "B.Fab")
			(hide yes)
			(effects
				(font
					(size 1 1)
					(thickness 0.15)
				)
				(justify mirror)
			)
		)
		(sheetname "M.2")
		(sheetfile "m-2.kicad_sch")
		(attr smd)
		(fp_line
			(start 0.15 0.4)
			(end -0.15 0.4)
			(stroke
				(width 0.15)
				(type solid)
			)
			(layer "B.SilkS")
		)
		(fp_line
			(start 0.15 -0.4)
			(end -0.15 -0.4)
			(stroke
				(width 0.15)
				(type solid)
			)
			(layer "B.SilkS")
		)
		(fp_rect
			(start -1.25 0.65)
			(end 1.25 -0.65)
			(stroke
				(width 0.05)
				(type solid)
			)
			(fill none)
			(layer "B.CrtYd")
		)
		(fp_rect
			(start -0.8 0.4)
			(end 0.8 -0.4)
			(stroke
				(width 0.15)
				(type solid)
			)
			(fill none)
			(layer "B.Fab")
		)
		(fp_text user "Author: Antmicro"
			(at -1.682 -4.894 0)
			(layer "B.Fab")
			(hide yes)
			(effects
				(font
					(size 0.7 0.7)
					(thickness 0.15)
				)
				(justify left bottom mirror)
			)
		)
		(fp_text user "License: Apache-2.0"
			(at -1.682 -5.895 0)
			(layer "B.Fab")
			(hide yes)
			(effects
				(font
					(size 0.7 0.7)
					(thickness 0.15)
				)
				(justify left bottom mirror)
			)
		)
		(fp_text user "${REFERENCE}"
			(at -1.682 -3.895 0)
			(layer "B.Fab")
			(hide yes)
			(effects
				(font
					(size 0.7 0.7)
					(thickness 0.15)
				)
				(justify left bottom mirror)
			)
		)
		(pad "1" smd roundrect
			(at -0.7 0 180)
			(size 0.8 1)
			(layers "B.Cu" "B.Paste" "B.Mask")
			(roundrect_rratio 0.2)
			(net 635 "/M.2/3V3_M2")
			(pintype "passive")
		)
		(pad "2" smd roundrect
			(at 0.7 0 180)
			(size 0.8 1)
			(layers "B.Cu" "B.Paste" "B.Mask")
			(roundrect_rratio 0.2)
			(net 1 "GND")
			(pintype "passive")
		)
	)
	(footprint "antmicro-footprints:TSOT23-6"
		(layer "B.Cu")
		(at 97.52 81.75 -90)
		(property "Reference" "U27"
			(at -0.8 -2.71 90)
			(layer "B.SilkS")
			(effects
				(font
					(size 0.7 0.7)
					(thickness 0.15)
				)
				(justify left bottom mirror)
			)
		)
		(property "Value" "AP22615A_TSOT26"
			(at 0 -2.6 90)
			(layer "B.Fab")
			(effects
				(font
					(size 0.7 0.7)
					(thickness 0.15)
				)
				(justify left bottom mirror)
			)
		)
		(property "Footprint" "antmicro-footprints:TSOT23-6"
			(at 0 0 -90)
			(layer "F.Fab")
			(hide yes)
			(effects
				(font
					(size 1.27 1.27)
					(thickness 0.15)
				)
			)
		)
		(property "Datasheet" "https://www.mouser.com/datasheet/2/115/DIOD_S_A0008958405_1-2543193.pdf"
			(at 0 0 -90)
			(layer "F.Fab")
			(hide yes)
			(effects
				(font
					(size 1.27 1.27)
					(thickness 0.15)
				)
			)
		)
		(property "Author" "Antmicro"
			(at 15.77 179.27 0)
			(layer "B.Fab")
			(hide yes)
			(effects
				(font
					(size 1 1)
					(thickness 0.15)
				)
				(justify mirror)
			)
		)
		(property "License" "Apache-2.0"
			(at 15.77 179.27 0)
			(layer "B.Fab")
			(hide yes)
			(effects
				(font
					(size 1 1)
					(thickness 0.15)
				)
				(justify mirror)
			)
		)
		(property "MPN" "AP22615AWU-7"
			(at 15.77 179.27 0)
			(layer "B.Fab")
			(hide yes)
			(effects
				(font
					(size 1 1)
					(thickness 0.15)
				)
				(justify mirror)
			)
		)
		(property "Manufacturer" "Diodes Incorporated"
			(at 15.77 179.27 0)
			(layer "B.Fab")
			(hide yes)
			(effects
				(font
					(size 1 1)
					(thickness 0.15)
				)
				(justify mirror)
			)
		)
		(sheetname "CSI")
		(sheetfile "csi.kicad_sch")
		(attr smd)
		(fp_line
			(start -1 1.5)
			(end 1 1.497)
			(stroke
				(width 0.15)
				(type solid)
			)
			(layer "B.SilkS")
		)
		(fp_line
			(start -1 1.375)
			(end -1 1.5)
			(stroke
				(width 0.15)
				(type solid)
			)
			(layer "B.SilkS")
		)
		(fp_line
			(start 1 1.375)
			(end 1 1.497)
			(stroke
				(width 0.15)
				(type solid)
			)
			(layer "B.SilkS")
		)
		(fp_line
			(start -1 -1.4)
			(end -1 -1.55)
			(stroke
				(width 0.15)
				(type solid)
			)
			(layer "B.SilkS")
		)
		(fp_line
			(start 1 -1.4)
			(end 1 -1.55)
			(stroke
				(width 0.15)
				(type solid)
			)
			(layer "B.SilkS")
		)
		(fp_line
			(start -1 -1.55)
			(end 1 -1.55)
			(stroke
				(width 0.15)
				(type solid)
			)
			(layer "B.SilkS")
		)
		(fp_circle
			(center -1.44 1.5)
			(end -1.39 1.5)
			(stroke
				(width 0.15)
				(type solid)
			)
			(fill solid)
			(layer "B.SilkS")
		)
		(fp_rect
			(start 1.93 1.7)
			(end -1.93 -1.7)
			(stroke
				(width 0.05)
				(type solid)
			)
			(fill none)
			(layer "B.CrtYd")
		)
		(fp_line
			(start -0.876 1.096)
			(end -0.45 1.521)
			(stroke
				(width 0.15)
				(type solid)
			)
			(layer "B.Fab")
		)
		(fp_rect
			(start 0.875 -1.528)
			(end -0.875 1.525)
			(stroke
				(width 0.15)
				(type solid)
			)
			(fill none)
			(layer "B.Fab")
		)
		(fp_text user "Author: Antmicro"
			(at -1.93 -5 90)
			(layer "B.Fab")
			(hide yes)
			(effects
				(font
					(size 0.7 0.7)
					(thickness 0.15)
				)
				(justify left bottom mirror)
			)
		)
		(fp_text user "License: Apache-2.0"
			(at -1.93 -6.199 90)
			(layer "B.Fab")
			(hide yes)
			(effects
				(font
					(size 0.7 0.7)
					(thickness 0.15)
				)
				(justify left bottom mirror)
			)
		)
		(fp_text user "${REFERENCE}"
			(at -1.93 -3.8 90)
			(layer "B.Fab")
			(hide yes)
			(effects
				(font
					(size 0.7 0.7)
					(thickness 0.15)
				)
				(justify left bottom mirror)
			)
		)
		(pad "1" smd rect
			(at -1.301 0.947)
			(size 0.7 1.2)
			(layers "B.Cu" "B.Paste" "B.Mask")
			(net 111 "/CSI/CSIB_5V")
			(pinfunction "OUT")
			(pintype "power_out")
		)
		(pad "2" smd rect
			(at -1.301 -0.004)
			(size 0.7 1.2)
			(layers "B.Cu" "B.Paste" "B.Mask")
			(net 1 "GND")
			(pinfunction "GND")
			(pintype "power_in")
		)
		(pad "3" smd rect
			(at -1.301 -0.954)
			(size 0.7 1.2)
			(layers "B.Cu" "B.Paste" "B.Mask")
			(net 393 "CSIB_FLG")
			(pinfunction "FLG")
			(pintype "output")
		)
		(pad "4" smd rect
			(at 1.299 -0.954)
			(size 0.7 1.2)
			(layers "B.Cu" "B.Paste" "B.Mask")
			(net 338 "CSIB_PEN")
			(pinfunction "EN")
			(pintype "input")
		)
		(pad "5" smd rect
			(at 1.299 -0.004)
			(size 0.7 1.2)
			(layers "B.Cu" "B.Paste" "B.Mask")
			(net 343 "/CSI/CSIB_5V_ISET")
			(pinfunction "ISET")
			(pintype "passive")
		)
		(pad "6" smd rect
			(at 1.299 0.947)
			(size 0.7 1.2)
			(layers "B.Cu" "B.Paste" "B.Mask")
			(net 99 "+5V")
			(pinfunction "IN")
			(pintype "power_in")
		)
	)
	(footprint "antmicro-footprints:TP_SMD_0.75mm"
		(layer "B.Cu")
		(at 90.745 114.4 90)
		(property "Reference" "TP57"
			(at -1.855 -1.49 90)
			(layer "B.SilkS")
			(effects
				(font
					(size 0.7 0.7)
					(thickness 0.15)
				)
				(justify right bottom mirror)
			)
		)
		(property "Value" "TP_0.75mm_SMD"
			(at 0 -1.2 90)
			(layer "B.Fab")
			(effects
				(font
					(size 0.7 0.7)
					(thickness 0.15)
				)
				(justify right bottom mirror)
			)
		)
		(property "Footprint" "antmicro-footprints:TP_SMD_0.75mm"
			(at 0 0 90)
			(layer "F.Fab")
			(hide yes)
			(effects
				(font
					(size 1.27 1.27)
					(thickness 0.15)
				)
			)
		)
		(property "Author" "Antmicro"
			(at 205.145 23.655 0)
			(layer "B.Fab")
			(hide yes)
			(effects
				(font
					(size 1 1)
					(thickness 0.15)
				)
				(justify mirror)
			)
		)
		(property "License" "Apache-2.0"
			(at 205.145 23.655 0)
			(layer "B.Fab")
			(hide yes)
			(effects
				(font
					(size 1 1)
					(thickness 0.15)
				)
				(justify mirror)
			)
		)
		(property "MPN" ""
			(at 205.145 23.655 0)
			(layer "B.Fab")
			(hide yes)
			(effects
				(font
					(size 1 1)
					(thickness 0.15)
				)
				(justify mirror)
			)
		)
		(property "Manufacturer" ""
			(at 205.145 23.655 0)
			(layer "B.Fab")
			(hide yes)
			(effects
				(font
					(size 1 1)
					(thickness 0.15)
				)
				(justify mirror)
			)
		)
		(sheetname "HDMI")
		(sheetfile "hdmi.kicad_sch")
		(attr exclude_from_pos_files exclude_from_bom)
		(fp_circle
			(center 0 0)
			(end 0.475 0)
			(stroke
				(width 0.05)
				(type default)
			)
			(fill none)
			(layer "B.CrtYd")
		)
		(fp_text user "License: Apache-2.0"
			(at -0.4 -5.101 90)
			(layer "B.Fab")
			(hide yes)
			(effects
				(font
					(size 0.7 0.7)
					(thickness 0.15)
				)
				(justify right bottom mirror)
			)
		)
		(fp_text user "${REFERENCE}"
			(at -0.4 -2.7 90)
			(layer "B.Fab")
			(hide yes)
			(effects
				(font
					(size 0.7 0.7)
					(thickness 0.15)
				)
				(justify right bottom mirror)
			)
		)
		(fp_text user "Author: Antmicro"
			(at -0.4 -3.901 90)
			(layer "B.Fab")
			(hide yes)
			(effects
				(font
					(size 0.7 0.7)
					(thickness 0.15)
				)
				(justify right bottom mirror)
			)
		)
		(pad "1" smd circle
			(at 0 0 90)
			(size 0.75 0.75)
			(layers "B.Cu" "B.Mask")
			(net 555 "/HDMI/HDMI_SCL_3V3")
			(pinfunction "1")
			(pintype "passive")
		)
	)
	(footprint "antmicro-footprints:TP_SMD_0.75mm"
		(layer "B.Cu")
		(at 68.165 117.07 180)
		(property "Reference" "TP1"
			(at 0 0.6 0)
			(layer "B.SilkS")
			(hide yes)
			(effects
				(font
					(size 0.7 0.7)
					(thickness 0.15)
				)
				(justify left bottom mirror)
			)
		)
		(property "Value" "TP_0.75mm_SMD"
			(at 0 -1.2 0)
			(layer "B.Fab")
			(effects
				(font
					(size 0.7 0.7)
					(thickness 0.15)
				)
				(justify left bottom mirror)
			)
		)
		(property "Footprint" "antmicro-footprints:TP_SMD_0.75mm"
			(at 0 0 180)
			(layer "F.Fab")
			(hide yes)
			(effects
				(font
					(size 1.27 1.27)
					(thickness 0.15)
				)
			)
		)
		(property "Author" "Antmicro"
			(at 136.33 234.14 0)
			(layer "B.Fab")
			(hide yes)
			(effects
				(font
					(size 1 1)
					(thickness 0.15)
				)
				(justify mirror)
			)
		)
		(property "License" "Apache-2.0"
			(at 136.33 234.14 0)
			(layer "B.Fab")
			(hide yes)
			(effects
				(font
					(size 1 1)
					(thickness 0.15)
				)
				(justify mirror)
			)
		)
		(property "MPN" ""
			(at 136.33 234.14 0)
			(layer "B.Fab")
			(hide yes)
			(effects
				(font
					(size 1 1)
					(thickness 0.15)
				)
				(justify mirror)
			)
		)
		(property "Manufacturer" ""
			(at 136.33 234.14 0)
			(layer "B.Fab")
			(hide yes)
			(effects
				(font
					(size 1 1)
					(thickness 0.15)
				)
				(justify mirror)
			)
		)
		(sheetname "USB Debug, DP")
		(sheetfile "usb.kicad_sch")
		(attr exclude_from_pos_files exclude_from_bom)
		(fp_circle
			(center 0 0)
			(end 0.475 0)
			(stroke
				(width 0.05)
				(type default)
			)
			(fill none)
			(layer "B.CrtYd")
		)
		(fp_text user "${REFERENCE}"
			(at -0.4 -2.7 0)
			(layer "B.Fab")
			(hide yes)
			(effects
				(font
					(size 0.7 0.7)
					(thickness 0.15)
				)
				(justify left bottom mirror)
			)
		)
		(fp_text user "License: Apache-2.0"
			(at -0.4 -5.101 0)
			(layer "B.Fab")
			(hide yes)
			(effects
				(font
					(size 0.7 0.7)
					(thickness 0.15)
				)
				(justify left bottom mirror)
			)
		)
		(fp_text user "Author: Antmicro"
			(at -0.4 -3.901 0)
			(layer "B.Fab")
			(hide yes)
			(effects
				(font
					(size 0.7 0.7)
					(thickness 0.15)
				)
				(justify left bottom mirror)
			)
		)
		(pad "1" smd circle
			(at 0 0 180)
			(size 0.75 0.75)
			(layers "B.Cu" "B.Mask")
			(net 196 "/USB Debug, DP/USBC3_VBUS")
			(pinfunction "1")
			(pintype "passive")
		)
	)
	(footprint "antmicro-footprints:SOT-523"
		(layer "B.Cu")
		(at 71.4 71.2)
		(property "Reference" "Q8"
			(at 0.77 -1.03 0)
			(layer "B.SilkS")
			(effects
				(font
					(size 0.7 0.7)
					(thickness 0.15)
				)
				(justify left bottom mirror)
			)
		)
		(property "Value" "PJE138K"
			(at 0.1 -1.824 180)
			(layer "B.Fab")
			(effects
				(font
					(size 0.7 0.7)
					(thickness 0.15)
				)
				(justify left bottom mirror)
			)
		)
		(property "Footprint" "antmicro-footprints:SOT-523"
			(at 0 0 0)
			(layer "F.Fab")
			(hide yes)
			(effects
				(font
					(size 1.27 1.27)
					(thickness 0.15)
				)
			)
		)
		(property "Datasheet" "https://www.mouser.com/datasheet/2/1057/PJE138K-1876698.pdf"
			(at 0 0 0)
			(layer "F.Fab")
			(hide yes)
			(effects
				(font
					(size 1.27 1.27)
					(thickness 0.15)
				)
			)
		)
		(property "Author" "Antmicro"
			(at 0 0 0)
			(layer "B.Fab")
			(hide yes)
			(effects
				(font
					(size 1 1)
					(thickness 0.15)
				)
				(justify mirror)
			)
		)
		(property "License" "Apache-2.0"
			(at 0 0 0)
			(layer "B.Fab")
			(hide yes)
			(effects
				(font
					(size 1 1)
					(thickness 0.15)
				)
				(justify mirror)
			)
		)
		(property "MPN" "PJE138K_R1_00001"
			(at 0 0 0)
			(layer "B.Fab")
			(hide yes)
			(effects
				(font
					(size 1 1)
					(thickness 0.15)
				)
				(justify mirror)
			)
		)
		(property "Manufacturer" "PANJIT"
			(at 0 0 0)
			(layer "B.Fab")
			(hide yes)
			(effects
				(font
					(size 1 1)
					(thickness 0.15)
				)
				(justify mirror)
			)
		)
		(sheetname "Supply")
		(sheetfile "supply.kicad_sch")
		(attr smd)
		(fp_line
			(start -0.927 0.351)
			(end -0.927 0.051)
			(stroke
				(width 0.15)
				(type solid)
			)
			(layer "B.SilkS")
		)
		(fp_line
			(start -0.725 0.551)
			(end -0.927 0.351)
			(stroke
				(width 0.15)
				(type solid)
			)
			(layer "B.SilkS")
		)
		(fp_line
			(start -0.277 0.551)
			(end -0.725 0.551)
			(stroke
				(width 0.15)
				(type solid)
			)
			(layer "B.SilkS")
		)
		(fp_line
			(start -0.277 0.75)
			(end -0.277 0.551)
			(stroke
				(width 0.15)
				(type solid)
			)
			(layer "B.SilkS")
		)
		(fp_circle
			(center -0.9652 -0.9652)
			(end -0.9152 -0.9652)
			(stroke
				(width 0.15)
				(type solid)
			)
			(fill solid)
			(layer "B.SilkS")
		)
		(fp_line
			(start -1.12 -1.15)
			(end -1.12 1.16)
			(stroke
				(width 0.05)
				(type solid)
			)
			(layer "B.CrtYd")
		)
		(fp_line
			(start 1.1 -1.15)
			(end -1.12 -1.15)
			(stroke
				(width 0.05)
				(type solid)
			)
			(layer "B.CrtYd")
		)
		(fp_line
			(start 1.1 -1.15)
			(end 1.1 1.16)
			(stroke
				(width 0.05)
				(type solid)
			)
			(layer "B.CrtYd")
		)
		(fp_line
			(start 1.1 1.16)
			(end -1.12 1.16)
			(stroke
				(width 0.05)
				(type solid)
			)
			(layer "B.CrtYd")
		)
		(fp_line
			(start -0.802 -0.424)
			(end -0.802 0.276)
			(stroke
				(width 0.15)
				(type solid)
			)
			(layer "B.Fab")
		)
		(fp_line
			(start -0.802 -0.424)
			(end 0.8 -0.424)
			(stroke
				(width 0.15)
				(type solid)
			)
			(layer "B.Fab")
		)
		(fp_line
			(start -0.802 0.276)
			(end -0.652 0.425)
			(stroke
				(width 0.15)
				(type solid)
			)
			(layer "B.Fab")
		)
		(fp_line
			(start -0.652 0.425)
			(end 0.8 0.425)
			(stroke
				(width 0.15)
				(type solid)
			)
			(layer "B.Fab")
		)
		(fp_line
			(start 0.8 -0.424)
			(end 0.8 0.425)
			(stroke
				(width 0.15)
				(type solid)
			)
			(layer "B.Fab")
		)
		(fp_circle
			(center -0.9652 -0.9652)
			(end -0.9144 -0.9652)
			(stroke
				(width 0.15)
				(type solid)
			)
			(fill none)
			(layer "B.Fab")
		)
		(fp_text user "${REFERENCE}"
			(at -1.12 -3.824 180)
			(layer "B.Fab")
			(hide yes)
			(effects
				(font
					(size 0.7 0.7)
					(thickness 0.15)
				)
				(justify left bottom mirror)
			)
		)
		(fp_text user "Author: Antmicro"
			(at -1.12 -6.224 180)
			(layer "B.Fab")
			(hide yes)
			(effects
				(font
					(size 0.7 0.7)
					(thickness 0.15)
				)
				(justify left bottom mirror)
			)
		)
		(fp_text user "License: Apache-2.0"
			(at -1.12 -5.024 180)
			(layer "B.Fab")
			(hide yes)
			(effects
				(font
					(size 0.7 0.7)
					(thickness 0.15)
				)
				(justify left bottom mirror)
			)
		)
		(pad "1" smd rect
			(at -0.5 -0.65)
			(size 0.4 0.51)
			(layers "B.Cu" "B.Paste" "B.Mask")
			(net 179 "Net-(D61-A)")
			(pinfunction "G")
			(pintype "passive")
		)
		(pad "2" smd rect
			(at 0.498 -0.65)
			(size 0.4 0.51)
			(layers "B.Cu" "B.Paste" "B.Mask")
			(net 1 "GND")
			(pinfunction "S")
			(pintype "passive")
		)
		(pad "3" smd rect
			(at 0 0.652)
			(size 0.4 0.51)
			(layers "B.Cu" "B.Paste" "B.Mask")
			(net 86 "~{RESET}")
			(pinfunction "D")
			(pintype "passive")
		)
	)
	(footprint "antmicro-footprints:C_0402_1005Metric"
		(layer "B.Cu")
		(at 67.68 78.71 180)
		(descr "Capacitor SMD 0402")
		(tags "capacitor SMD 0402")
		(property "Reference" "C41"
			(at -16.09 -3.48 0)
			(layer "B.SilkS")
			(effects
				(font
					(size 0.7 0.7)
					(thickness 0.15)
				)
				(justify left bottom mirror)
			)
		)
		(property "Value" "C_100n_0402"
			(at 0 -1.4 0)
			(layer "B.Fab")
			(effects
				(font
					(size 0.7 0.7)
					(thickness 0.15)
				)
				(justify left bottom mirror)
			)
		)
		(property "Footprint" "antmicro-footprints:C_0402_1005Metric"
			(at 0 0 180)
			(layer "F.Fab")
			(hide yes)
			(effects
				(font
					(size 1.27 1.27)
					(thickness 0.15)
				)
			)
		)
		(property "Datasheet" "https://www.murata.com/products/productdetail?partno=GRM155R61H104KE14%23"
			(at 0 0 180)
			(layer "F.Fab")
			(hide yes)
			(effects
				(font
					(size 1.27 1.27)
					(thickness 0.15)
				)
			)
		)
		(property "Author" "Antmicro"
			(at 135.36 157.42 0)
			(layer "B.Fab")
			(hide yes)
			(effects
				(font
					(size 1 1)
					(thickness 0.15)
				)
				(justify mirror)
			)
		)
		(property "Dielectric" "X5R"
			(at 135.36 157.42 0)
			(layer "B.Fab")
			(hide yes)
			(effects
				(font
					(size 1 1)
					(thickness 0.15)
				)
				(justify mirror)
			)
		)
		(property "License" "Apache-2.0"
			(at 135.36 157.42 0)
			(layer "B.Fab")
			(hide yes)
			(effects
				(font
					(size 1 1)
					(thickness 0.15)
				)
				(justify mirror)
			)
		)
		(property "MPN" "GRM155R61H104KE14D"
			(at 135.36 157.42 0)
			(layer "B.Fab")
			(hide yes)
			(effects
				(font
					(size 1 1)
					(thickness 0.15)
				)
				(justify mirror)
			)
		)
		(property "Manufacturer" "Murata"
			(at 135.36 157.42 0)
			(layer "B.Fab")
			(hide yes)
			(effects
				(font
					(size 1 1)
					(thickness 0.15)
				)
				(justify mirror)
			)
		)
		(property "Val" "100n"
			(at 135.36 157.42 0)
			(layer "B.Fab")
			(hide yes)
			(effects
				(font
					(size 1 1)
					(thickness 0.15)
				)
				(justify mirror)
			)
		)
		(property "Voltage" "50V"
			(at 135.36 157.42 0)
			(layer "B.Fab")
			(hide yes)
			(effects
				(font
					(size 1 1)
					(thickness 0.15)
				)
				(justify mirror)
			)
		)
		(sheetname "SoM")
		(sheetfile "som.kicad_sch")
		(attr smd)
		(fp_rect
			(start -0.925 0.47)
			(end 0.925 -0.47)
			(stroke
				(width 0.05)
				(type default)
			)
			(fill none)
			(layer "B.CrtYd")
		)
		(fp_line
			(start 0.504 0.25)
			(end -0.494 0.25)
			(stroke
				(width 0.15)
				(type solid)
			)
			(layer "B.Fab")
		)
		(fp_line
			(start 0.504 -0.248)
			(end 0.504 0.25)
			(stroke
				(width 0.15)
				(type solid)
			)
			(layer "B.Fab")
		)
		(fp_line
			(start -0.494 0.25)
			(end -0.494 -0.248)
			(stroke
				(width 0.15)
				(type solid)
			)
			(layer "B.Fab")
		)
		(fp_line
			(start -0.494 -0.248)
			(end 0.504 -0.248)
			(stroke
				(width 0.15)
				(type solid)
			)
			(layer "B.Fab")
		)
		(fp_text user "${REFERENCE}"
			(at -0.932 -3.168 0)
			(layer "B.Fab")
			(hide yes)
			(effects
				(font
					(size 0.7 0.7)
					(thickness 0.15)
				)
				(justify left bottom mirror)
			)
		)
		(fp_text user "License: Apache-2.0"
			(at -0.932 -5.17 0)
			(layer "B.Fab")
			(hide yes)
			(effects
				(font
					(size 0.7 0.7)
					(thickness 0.15)
				)
				(justify left bottom mirror)
			)
		)
		(fp_text user "Author: Antmicro"
			(at -0.932 -4.17 0)
			(layer "B.Fab")
			(hide yes)
			(effects
				(font
					(size 0.7 0.7)
					(thickness 0.15)
				)
				(justify left bottom mirror)
			)
		)
		(pad "1" smd roundrect
			(at -0.48 0 180)
			(size 0.59 0.64)
			(layers "B.Cu" "B.Paste" "B.Mask")
			(roundrect_rratio 0.25)
			(net 1 "GND")
			(pintype "passive")
		)
		(pad "2" smd roundrect
			(at 0.48 0 180)
			(size 0.59 0.64)
			(layers "B.Cu" "B.Paste" "B.Mask")
			(roundrect_rratio 0.25)
			(net 87 "+3V3")
			(pintype "passive")
		)
	)
	(footprint "antmicro-footprints:R_0402_1005Metric"
		(layer "B.Cu")
		(at 88.2 105.1 180)
		(descr "Resistor SMD 0402")
		(tags "resistor SMD 0402")
		(property "Reference" "R194"
			(at 0.7 0.05 0)
			(layer "B.SilkS")
			(effects
				(font
					(size 0.6 0.6)
					(thickness 0.15)
				)
				(justify left bottom mirror)
			)
		)
		(property "Value" "R_10k_0402"
			(at 0 -1.4 0)
			(layer "B.Fab")
			(effects
				(font
					(size 0.7 0.7)
					(thickness 0.15)
				)
				(justify left bottom mirror)
			)
		)
		(property "Footprint" "antmicro-footprints:R_0402_1005Metric"
			(at 0 0 180)
			(layer "F.Fab")
			(hide yes)
			(effects
				(font
					(size 1.27 1.27)
					(thickness 0.15)
				)
			)
		)
		(property "Datasheet" "https://www.bourns.com/docs/product-datasheets/cr.pdf"
			(at 0 0 180)
			(layer "F.Fab")
			(hide yes)
			(effects
				(font
					(size 1.27 1.27)
					(thickness 0.15)
				)
			)
		)
		(property "Author" "Antmicro"
			(at 176.4 210.2 0)
			(layer "B.Fab")
			(hide yes)
			(effects
				(font
					(size 1 1)
					(thickness 0.15)
				)
				(justify mirror)
			)
		)
		(property "License" "Apache-2.0"
			(at 176.4 210.2 0)
			(layer "B.Fab")
			(hide yes)
			(effects
				(font
					(size 1 1)
					(thickness 0.15)
				)
				(justify mirror)
			)
		)
		(property "MPN" "CR0402-FX-1002GLF"
			(at 176.4 210.2 0)
			(layer "B.Fab")
			(hide yes)
			(effects
				(font
					(size 1 1)
					(thickness 0.15)
				)
				(justify mirror)
			)
		)
		(property "Manufacturer" "Bourns"
			(at 176.4 210.2 0)
			(layer "B.Fab")
			(hide yes)
			(effects
				(font
					(size 1 1)
					(thickness 0.15)
				)
				(justify mirror)
			)
		)
		(property "Tolerance" "1%"
			(at 176.4 210.2 0)
			(layer "B.Fab")
			(hide yes)
			(effects
				(font
					(size 1 1)
					(thickness 0.15)
				)
				(justify mirror)
			)
		)
		(property "Val" "10k"
			(at 176.4 210.2 0)
			(layer "B.Fab")
			(hide yes)
			(effects
				(font
					(size 1 1)
					(thickness 0.15)
				)
				(justify mirror)
			)
		)
		(sheetname "CSI")
		(sheetfile "csi.kicad_sch")
		(attr smd exclude_from_pos_files exclude_from_bom dnp)
		(fp_rect
			(start -0.925 0.47)
			(end 0.925 -0.47)
			(stroke
				(width 0.05)
				(type default)
			)
			(fill none)
			(layer "B.CrtYd")
		)
		(fp_rect
			(start -0.5 0.25)
			(end 0.5 -0.25)
			(stroke
				(width 0.15)
				(type solid)
			)
			(fill none)
			(layer "B.Fab")
		)
		(fp_text user "${REFERENCE}"
			(at -0.95 -3.168 0)
			(layer "B.Fab")
			(hide yes)
			(effects
				(font
					(size 0.7 0.7)
					(thickness 0.15)
				)
				(justify left bottom mirror)
			)
		)
		(fp_text user "License: Apache-2.0"
			(at -0.95 -5.169 0)
			(layer "B.Fab")
			(hide yes)
			(effects
				(font
					(size 0.7 0.7)
					(thickness 0.15)
				)
				(justify left bottom mirror)
			)
		)
		(fp_text user "Author: Antmicro"
			(at -0.95 -4.169 0)
			(layer "B.Fab")
			(hide yes)
			(effects
				(font
					(size 0.7 0.7)
					(thickness 0.15)
				)
				(justify left bottom mirror)
			)
		)
		(pad "1" smd roundrect
			(at -0.48 0 180)
			(size 0.59 0.64)
			(layers "B.Cu" "B.Paste" "B.Mask")
			(roundrect_rratio 0.25)
			(net 338 "CSIB_PEN")
			(pintype "passive")
		)
		(pad "2" smd roundrect
			(at 0.48 0 180)
			(size 0.59 0.64)
			(layers "B.Cu" "B.Paste" "B.Mask")
			(roundrect_rratio 0.25)
			(net 87 "+3V3")
			(pintype "passive")
		)
	)
	(footprint "antmicro-footprints:SC-74-6_1.5x2.9mm_P0.95mm"
		(layer "B.Cu")
		(at 109 88.02 180)
		(tags "sc74 sc-74 sot23-6 sot457 tsop6 tsop-6")
		(property "Reference" "U3"
			(at -2.52 1.97 0)
			(layer "B.SilkS")
			(effects
				(font
					(size 0.7 0.7)
					(thickness 0.15)
				)
				(justify left bottom mirror)
			)
		)
		(property "Value" "74LVC2G07_SOT457"
			(at -2 -2.999 0)
			(layer "B.Fab")
			(effects
				(font
					(size 0.7 0.7)
					(thickness 0.15)
				)
				(justify left bottom mirror)
			)
		)
		(property "Footprint" "antmicro-footprints:SC-74-6_1.5x2.9mm_P0.95mm"
			(at 0 0 180)
			(layer "F.Fab")
			(hide yes)
			(effects
				(font
					(size 1.27 1.27)
					(thickness 0.15)
				)
			)
		)
		(property "Datasheet" "https://www.tme.eu/Document/2ad9356043a4952b9021ef50162f8c34/74LVC2G07.pdf"
			(at 0 0 180)
			(layer "F.Fab")
			(hide yes)
			(effects
				(font
					(size 1.27 1.27)
					(thickness 0.15)
				)
			)
		)
		(property "Author" "Antmicro"
			(at 218 176.04 0)
			(layer "B.Fab")
			(hide yes)
			(effects
				(font
					(size 1 1)
					(thickness 0.15)
				)
				(justify mirror)
			)
		)
		(property "License" "Apache-2.0"
			(at 218 176.04 0)
			(layer "B.Fab")
			(hide yes)
			(effects
				(font
					(size 1 1)
					(thickness 0.15)
				)
				(justify mirror)
			)
		)
		(property "MPN" "74LVC2G07GV,125"
			(at 218 176.04 0)
			(layer "B.Fab")
			(hide yes)
			(effects
				(font
					(size 1 1)
					(thickness 0.15)
				)
				(justify mirror)
			)
		)
		(property "Manufacturer" "Nexperia"
			(at 218 176.04 0)
			(layer "B.Fab")
			(hide yes)
			(effects
				(font
					(size 1 1)
					(thickness 0.15)
				)
				(justify mirror)
			)
		)
		(property ki_fp_filters "SG-74 SOT23-6 TSOP6 SOT457")
		(sheetname "M.2")
		(sheetfile "m-2.kicad_sch")
		(attr smd exclude_from_pos_files exclude_from_bom dnp)
		(fp_circle
			(center -1.11 1.454)
			(end -1.06 1.454)
			(stroke
				(width 0.15)
				(type solid)
			)
			(fill solid)
			(layer "B.SilkS")
		)
		(fp_rect
			(start -1.7 1.7)
			(end 1.7 -1.7)
			(stroke
				(width 0.05)
				(type solid)
			)
			(fill none)
			(layer "B.CrtYd")
		)
		(fp_line
			(start 1.22 1.422)
			(end 1.22 -1.372)
			(stroke
				(width 0.15)
				(type solid)
			)
			(layer "B.Fab")
		)
		(fp_line
			(start 1.22 -1.372)
			(end -1.167 -1.372)
			(stroke
				(width 0.15)
				(type solid)
			)
			(layer "B.Fab")
		)
		(fp_line
			(start -0.76 1.422)
			(end 1.22 1.422)
			(stroke
				(width 0.15)
				(type solid)
			)
			(layer "B.Fab")
		)
		(fp_line
			(start -1.167 -1.372)
			(end -1.269 -1.372)
			(stroke
				(width 0.15)
				(type solid)
			)
			(layer "B.Fab")
		)
		(fp_line
			(start -1.269 0.915)
			(end -0.76 1.422)
			(stroke
				(width 0.15)
				(type solid)
			)
			(layer "B.Fab")
		)
		(fp_line
			(start -1.269 -1.372)
			(end -1.269 0.915)
			(stroke
				(width 0.15)
				(type solid)
			)
			(layer "B.Fab")
		)
		(fp_text user "Author: Antmicro"
			(at -2.12 -4.999 0)
			(layer "B.Fab")
			(hide yes)
			(effects
				(font
					(size 0.7 0.7)
					(thickness 0.15)
				)
				(justify left bottom mirror)
			)
		)
		(fp_text user "License: Apache-2.0"
			(at -2.12 -6.199 0)
			(layer "B.Fab")
			(hide yes)
			(effects
				(font
					(size 0.7 0.7)
					(thickness 0.15)
				)
				(justify left bottom mirror)
			)
		)
		(fp_text user "${REFERENCE}"
			(at -2.12 -7.399 0)
			(layer "B.Fab")
			(hide yes)
			(effects
				(font
					(size 0.7 0.7)
					(thickness 0.15)
				)
				(justify left bottom mirror)
			)
		)
		(pad "1" smd roundrect
			(at -1.2 0.95 180)
			(size 0.8 0.55)
			(layers "B.Cu" "B.Paste" "B.Mask")
			(roundrect_rratio 0.15)
			(net 248 "/M.2/~{M2_M_CLKREQ0}")
			(pintype "input")
		)
		(pad "2" smd roundrect
			(at -1.2 0 180)
			(size 0.8 0.55)
			(layers "B.Cu" "B.Paste" "B.Mask")
			(roundrect_rratio 0.15)
			(net 1 "GND")
			(pinfunction "GND")
			(pintype "power_in")
		)
		(pad "3" smd roundrect
			(at -1.2 -0.95 180)
			(size 0.8 0.55)
			(layers "B.Cu" "B.Paste" "B.Mask")
			(roundrect_rratio 0.15)
			(net 247 "/M.2/~{M2_M_PERST}")
			(pintype "input")
		)
		(pad "4" smd roundrect
			(at 1.2 -0.95 180)
			(size 0.8 0.55)
			(layers "B.Cu" "B.Paste" "B.Mask")
			(roundrect_rratio 0.15)
			(net 455 "PCIE0_RST*")
			(pintype "output")
		)
		(pad "5" smd roundrect
			(at 1.2 0 180)
			(size 0.8 0.55)
			(layers "B.Cu" "B.Paste" "B.Mask")
			(roundrect_rratio 0.15)
			(net 87 "+3V3")
			(pinfunction "V_{CC}")
			(pintype "power_in")
		)
		(pad "6" smd roundrect
			(at 1.2 0.95 180)
			(size 0.8 0.55)
			(layers "B.Cu" "B.Paste" "B.Mask")
			(roundrect_rratio 0.15)
			(net 454 "PCIE0_CLKREQ*")
			(pintype "output")
		)
	)
	(footprint "antmicro-footprints:R_0402_1005Metric"
		(layer "B.Cu")
		(at 57.55 110.45 180)
		(descr "Resistor SMD 0402")
		(tags "resistor SMD 0402")
		(property "Reference" "R58"
			(at -2.97 -0.3 0)
			(layer "B.SilkS")
			(effects
				(font
					(size 0.7 0.7)
					(thickness 0.15)
				)
				(justify left bottom mirror)
			)
		)
		(property "Value" "R_0R_0402"
			(at 0 -1.4 0)
			(layer "B.Fab")
			(effects
				(font
					(size 0.7 0.7)
					(thickness 0.15)
				)
				(justify left bottom mirror)
			)
		)
		(property "Footprint" "antmicro-footprints:R_0402_1005Metric"
			(at 0 0 180)
			(layer "F.Fab")
			(hide yes)
			(effects
				(font
					(size 1.27 1.27)
					(thickness 0.15)
				)
			)
		)
		(property "Datasheet" "https://industrial.panasonic.com/cdbs/www-data/pdf/RDA0000/AOA0000C301.pdf"
			(at 0 0 180)
			(layer "F.Fab")
			(hide yes)
			(effects
				(font
					(size 1.27 1.27)
					(thickness 0.15)
				)
			)
		)
		(property "Author" "Antmicro"
			(at 115.1 220.9 0)
			(layer "B.Fab")
			(hide yes)
			(effects
				(font
					(size 1 1)
					(thickness 0.15)
				)
				(justify mirror)
			)
		)
		(property "Current" "1A"
			(at 115.1 220.9 0)
			(layer "B.Fab")
			(hide yes)
			(effects
				(font
					(size 1 1)
					(thickness 0.15)
				)
				(justify mirror)
			)
		)
		(property "License" "Apache-2.0"
			(at 115.1 220.9 0)
			(layer "B.Fab")
			(hide yes)
			(effects
				(font
					(size 1 1)
					(thickness 0.15)
				)
				(justify mirror)
			)
		)
		(property "MPN" "ERJ2GE0R00X"
			(at 115.1 220.9 0)
			(layer "B.Fab")
			(hide yes)
			(effects
				(font
					(size 1 1)
					(thickness 0.15)
				)
				(justify mirror)
			)
		)
		(property "Manufacturer" "Panasonic"
			(at 115.1 220.9 0)
			(layer "B.Fab")
			(hide yes)
			(effects
				(font
					(size 1 1)
					(thickness 0.15)
				)
				(justify mirror)
			)
		)
		(property "Tolerance" ""
			(at 115.1 220.9 0)
			(layer "B.Fab")
			(hide yes)
			(effects
				(font
					(size 1 1)
					(thickness 0.15)
				)
				(justify mirror)
			)
		)
		(property "Val" "0R"
			(at 115.1 220.9 0)
			(layer "B.Fab")
			(hide yes)
			(effects
				(font
					(size 1 1)
					(thickness 0.15)
				)
				(justify mirror)
			)
		)
		(sheetname "USB Debug, DP")
		(sheetfile "usb.kicad_sch")
		(attr smd exclude_from_pos_files exclude_from_bom dnp)
		(fp_rect
			(start -0.925 0.47)
			(end 0.925 -0.47)
			(stroke
				(width 0.05)
				(type default)
			)
			(fill none)
			(layer "B.CrtYd")
		)
		(fp_rect
			(start -0.5 0.25)
			(end 0.5 -0.25)
			(stroke
				(width 0.15)
				(type solid)
			)
			(fill none)
			(layer "B.Fab")
		)
		(fp_text user "${REFERENCE}"
			(at -0.95 -3.168 0)
			(layer "B.Fab")
			(hide yes)
			(effects
				(font
					(size 0.7 0.7)
					(thickness 0.15)
				)
				(justify left bottom mirror)
			)
		)
		(fp_text user "Author: Antmicro"
			(at -0.95 -4.169 0)
			(layer "B.Fab")
			(hide yes)
			(effects
				(font
					(size 0.7 0.7)
					(thickness 0.15)
				)
				(justify left bottom mirror)
			)
		)
		(fp_text user "License: Apache-2.0"
			(at -0.95 -5.169 0)
			(layer "B.Fab")
			(hide yes)
			(effects
				(font
					(size 0.7 0.7)
					(thickness 0.15)
				)
				(justify left bottom mirror)
			)
		)
		(pad "1" smd roundrect
			(at -0.48 0 180)
			(size 0.59 0.64)
			(layers "B.Cu" "B.Paste" "B.Mask")
			(roundrect_rratio 0.25)
			(net 279 "PWR_SOFT")
			(pintype "passive")
		)
		(pad "2" smd roundrect
			(at 0.48 0 180)
			(size 0.59 0.64)
			(layers "B.Cu" "B.Paste" "B.Mask")
			(roundrect_rratio 0.25)
			(net 648 "Net-(U5-~{RTS})")
			(pintype "passive")
		)
	)
	(footprint "antmicro-footprints:SOT-523"
		(layer "B.Cu")
		(at 59.36 88.9)
		(property "Reference" "Q5"
			(at -2.68 1 0)
			(layer "B.SilkS")
			(effects
				(font
					(size 0.7 0.7)
					(thickness 0.15)
				)
				(justify right bottom mirror)
			)
		)
		(property "Value" "PJE138K"
			(at 0.1 -1.824 0)
			(layer "B.Fab")
			(effects
				(font
					(size 0.7 0.7)
					(thickness 0.15)
				)
				(justify right bottom mirror)
			)
		)
		(property "Footprint" "antmicro-footprints:SOT-523"
			(at 0 0 0)
			(layer "F.Fab")
			(hide yes)
			(effects
				(font
					(size 1.27 1.27)
					(thickness 0.15)
				)
			)
		)
		(property "Datasheet" "https://www.mouser.com/datasheet/2/1057/PJE138K-1876698.pdf"
			(at 0 0 0)
			(layer "F.Fab")
			(hide yes)
			(effects
				(font
					(size 1.27 1.27)
					(thickness 0.15)
				)
			)
		)
		(property "Author" "Antmicro"
			(at 0 0 0)
			(layer "B.Fab")
			(hide yes)
			(effects
				(font
					(size 1 1)
					(thickness 0.15)
				)
				(justify mirror)
			)
		)
		(property "License" "Apache-2.0"
			(at 0 0 0)
			(layer "B.Fab")
			(hide yes)
			(effects
				(font
					(size 1 1)
					(thickness 0.15)
				)
				(justify mirror)
			)
		)
		(property "MPN" "PJE138K_R1_00001"
			(at 0 0 0)
			(layer "B.Fab")
			(hide yes)
			(effects
				(font
					(size 1 1)
					(thickness 0.15)
				)
				(justify mirror)
			)
		)
		(property "Manufacturer" "PANJIT"
			(at 0 0 0)
			(layer "B.Fab")
			(hide yes)
			(effects
				(font
					(size 1 1)
					(thickness 0.15)
				)
				(justify mirror)
			)
		)
		(sheetname "Supply")
		(sheetfile "supply.kicad_sch")
		(attr smd)
		(fp_line
			(start -0.927 0.351)
			(end -0.927 0.051)
			(stroke
				(width 0.15)
				(type solid)
			)
			(layer "B.SilkS")
		)
		(fp_line
			(start -0.725 0.551)
			(end -0.927 0.351)
			(stroke
				(width 0.15)
				(type solid)
			)
			(layer "B.SilkS")
		)
		(fp_line
			(start -0.277 0.551)
			(end -0.725 0.551)
			(stroke
				(width 0.15)
				(type solid)
			)
			(layer "B.SilkS")
		)
		(fp_line
			(start -0.277 0.75)
			(end -0.277 0.551)
			(stroke
				(width 0.15)
				(type solid)
			)
			(layer "B.SilkS")
		)
		(fp_circle
			(center -0.9652 -0.9652)
			(end -0.9152 -0.9652)
			(stroke
				(width 0.15)
				(type solid)
			)
			(fill solid)
			(layer "B.SilkS")
		)
		(fp_line
			(start -1.12 -1.15)
			(end -1.12 1.16)
			(stroke
				(width 0.05)
				(type solid)
			)
			(layer "B.CrtYd")
		)
		(fp_line
			(start 1.1 -1.15)
			(end -1.12 -1.15)
			(stroke
				(width 0.05)
				(type solid)
			)
			(layer "B.CrtYd")
		)
		(fp_line
			(start 1.1 -1.15)
			(end 1.1 1.16)
			(stroke
				(width 0.05)
				(type solid)
			)
			(layer "B.CrtYd")
		)
		(fp_line
			(start 1.1 1.16)
			(end -1.12 1.16)
			(stroke
				(width 0.05)
				(type solid)
			)
			(layer "B.CrtYd")
		)
		(fp_line
			(start -0.802 -0.424)
			(end -0.802 0.276)
			(stroke
				(width 0.15)
				(type solid)
			)
			(layer "B.Fab")
		)
		(fp_line
			(start -0.802 -0.424)
			(end 0.8 -0.424)
			(stroke
				(width 0.15)
				(type solid)
			)
			(layer "B.Fab")
		)
		(fp_line
			(start -0.802 0.276)
			(end -0.652 0.425)
			(stroke
				(width 0.15)
				(type solid)
			)
			(layer "B.Fab")
		)
		(fp_line
			(start -0.652 0.425)
			(end 0.8 0.425)
			(stroke
				(width 0.15)
				(type solid)
			)
			(layer "B.Fab")
		)
		(fp_line
			(start 0.8 -0.424)
			(end 0.8 0.425)
			(stroke
				(width 0.15)
				(type solid)
			)
			(layer "B.Fab")
		)
		(fp_circle
			(center -0.9652 -0.9652)
			(end -0.9144 -0.9652)
			(stroke
				(width 0.15)
				(type solid)
			)
			(fill none)
			(layer "B.Fab")
		)
		(fp_text user "License: Apache-2.0"
			(at -1.12 -5.024 0)
			(layer "B.Fab")
			(hide yes)
			(effects
				(font
					(size 0.7 0.7)
					(thickness 0.15)
				)
				(justify right bottom mirror)
			)
		)
		(fp_text user "Author: Antmicro"
			(at -1.12 -6.224 0)
			(layer "B.Fab")
			(hide yes)
			(effects
				(font
					(size 0.7 0.7)
					(thickness 0.15)
				)
				(justify right bottom mirror)
			)
		)
		(fp_text user "${REFERENCE}"
			(at -1.12 -3.824 0)
			(layer "B.Fab")
			(hide yes)
			(effects
				(font
					(size 0.7 0.7)
					(thickness 0.15)
				)
				(justify right bottom mirror)
			)
		)
		(pad "1" smd rect
			(at -0.5 -0.65)
			(size 0.4 0.51)
			(layers "B.Cu" "B.Paste" "B.Mask")
			(net 86 "~{RESET}")
			(pinfunction "G")
			(pintype "passive")
		)
		(pad "2" smd rect
			(at 0.498 -0.65)
			(size 0.4 0.51)
			(layers "B.Cu" "B.Paste" "B.Mask")
			(net 1 "GND")
			(pinfunction "S")
			(pintype "passive")
		)
		(pad "3" smd rect
			(at 0 0.652)
			(size 0.4 0.51)
			(layers "B.Cu" "B.Paste" "B.Mask")
			(net 768 "/Supply/5V_GATE")
			(pinfunction "D")
			(pintype "passive")
		)
	)
	(footprint "antmicro-footprints:TP_SMD_0.75mm"
		(layer "B.Cu")
		(at 59.21 104.12 -135)
		(property "Reference" "TP24"
			(at 0 0.6 45)
			(layer "B.SilkS")
			(hide yes)
			(effects
				(font
					(size 0.7 0.7)
					(thickness 0.15)
				)
				(justify left bottom mirror)
			)
		)
		(property "Value" "TP_0.75mm_SMD"
			(at 0 -1.2 45)
			(layer "B.Fab")
			(effects
				(font
					(size 0.7 0.7)
					(thickness 0.15)
				)
				(justify left bottom mirror)
			)
		)
		(property "Footprint" "antmicro-footprints:TP_SMD_0.75mm"
			(at 0 0 -135)
			(layer "F.Fab")
			(hide yes)
			(effects
				(font
					(size 1.27 1.27)
					(thickness 0.15)
				)
			)
		)
		(property "Author" "Antmicro"
			(at 27.453834 219.611751 0)
			(layer "B.Fab")
			(hide yes)
			(effects
				(font
					(size 1 1)
					(thickness 0.15)
				)
				(justify mirror)
			)
		)
		(property "License" "Apache-2.0"
			(at 27.453834 219.611751 0)
			(layer "B.Fab")
			(hide yes)
			(effects
				(font
					(size 1 1)
					(thickness 0.15)
				)
				(justify mirror)
			)
		)
		(property "MPN" ""
			(at 27.453834 219.611751 0)
			(layer "B.Fab")
			(hide yes)
			(effects
				(font
					(size 1 1)
					(thickness 0.15)
				)
				(justify mirror)
			)
		)
		(property "Manufacturer" ""
			(at 27.453834 219.611751 0)
			(layer "B.Fab")
			(hide yes)
			(effects
				(font
					(size 1 1)
					(thickness 0.15)
				)
				(justify mirror)
			)
		)
		(sheetname "USB Debug, DP")
		(sheetfile "usb.kicad_sch")
		(attr exclude_from_pos_files exclude_from_bom)
		(fp_circle
			(center 0 0)
			(end 0.475 0)
			(stroke
				(width 0.05)
				(type default)
			)
			(fill none)
			(layer "B.CrtYd")
		)
		(fp_text user "License: Apache-2.0"
			(at -0.4 -5.101 45)
			(layer "B.Fab")
			(hide yes)
			(effects
				(font
					(size 0.7 0.7)
					(thickness 0.15)
				)
				(justify left bottom mirror)
			)
		)
		(fp_text user "${REFERENCE}"
			(at -0.4 -2.7 45)
			(layer "B.Fab")
			(hide yes)
			(effects
				(font
					(size 0.7 0.7)
					(thickness 0.15)
				)
				(justify left bottom mirror)
			)
		)
		(fp_text user "Author: Antmicro"
			(at -0.4 -3.901 45)
			(layer "B.Fab")
			(hide yes)
			(effects
				(font
					(size 0.7 0.7)
					(thickness 0.15)
				)
				(justify left bottom mirror)
			)
		)
		(pad "1" smd circle
			(at 0 0 225)
			(size 0.75 0.75)
			(layers "B.Cu" "B.Mask")
			(net 639 "/USB Debug, DP/PDC_I2C3_SCL")
			(pinfunction "1")
			(pintype "passive")
		)
	)
	(footprint "antmicro-footprints:R_0402_1005Metric"
		(layer "B.Cu")
		(at 138.8 123 180)
		(descr "Resistor SMD 0402")
		(tags "resistor SMD 0402")
		(property "Reference" "R190"
			(at -1.11 1.425 180)
			(layer "B.SilkS")
			(effects
				(font
					(size 0.7 0.7)
					(thickness 0.15)
				)
				(justify left bottom mirror)
			)
		)
		(property "Value" "R_15k_0402"
			(at 0 -1.4 0)
			(layer "B.Fab")
			(effects
				(font
					(size 0.7 0.7)
					(thickness 0.15)
				)
				(justify left bottom mirror)
			)
		)
		(property "Footprint" "antmicro-footprints:R_0402_1005Metric"
			(at 0 0 180)
			(layer "F.Fab")
			(hide yes)
			(effects
				(font
					(size 1.27 1.27)
					(thickness 0.15)
				)
			)
		)
		(property "Datasheet" "https://www.bourns.com/docs/product-datasheets/cr.pdf"
			(at 0 0 180)
			(layer "F.Fab")
			(hide yes)
			(effects
				(font
					(size 1.27 1.27)
					(thickness 0.15)
				)
			)
		)
		(property "Author" "Antmicro"
			(at 277.6 246 0)
			(layer "B.Fab")
			(hide yes)
			(effects
				(font
					(size 1 1)
					(thickness 0.15)
				)
				(justify mirror)
			)
		)
		(property "License" "Apache-2.0"
			(at 277.6 246 0)
			(layer "B.Fab")
			(hide yes)
			(effects
				(font
					(size 1 1)
					(thickness 0.15)
				)
				(justify mirror)
			)
		)
		(property "MPN" "CR0402-FX-1502GLF"
			(at 277.6 246 0)
			(layer "B.Fab")
			(hide yes)
			(effects
				(font
					(size 1 1)
					(thickness 0.15)
				)
				(justify mirror)
			)
		)
		(property "Manufacturer" "Bourns"
			(at 277.6 246 0)
			(layer "B.Fab")
			(hide yes)
			(effects
				(font
					(size 1 1)
					(thickness 0.15)
				)
				(justify mirror)
			)
		)
		(property "Tolerance" "1%"
			(at 277.6 246 0)
			(layer "B.Fab")
			(hide yes)
			(effects
				(font
					(size 1 1)
					(thickness 0.15)
				)
				(justify mirror)
			)
		)
		(property "Val" "15k"
			(at 277.6 246 0)
			(layer "B.Fab")
			(hide yes)
			(effects
				(font
					(size 1 1)
					(thickness 0.15)
				)
				(justify mirror)
			)
		)
		(sheetname "Peripherals")
		(sheetfile "peripherals.kicad_sch")
		(attr smd)
		(fp_rect
			(start -0.925 0.47)
			(end 0.925 -0.47)
			(stroke
				(width 0.05)
				(type default)
			)
			(fill none)
			(layer "B.CrtYd")
		)
		(fp_rect
			(start -0.5 0.25)
			(end 0.5 -0.25)
			(stroke
				(width 0.15)
				(type solid)
			)
			(fill none)
			(layer "B.Fab")
		)
		(fp_text user "License: Apache-2.0"
			(at -0.95 -5.169 0)
			(layer "B.Fab")
			(hide yes)
			(effects
				(font
					(size 0.7 0.7)
					(thickness 0.15)
				)
				(justify left bottom mirror)
			)
		)
		(fp_text user "Author: Antmicro"
			(at -0.95 -4.169 0)
			(layer "B.Fab")
			(hide yes)
			(effects
				(font
					(size 0.7 0.7)
					(thickness 0.15)
				)
				(justify left bottom mirror)
			)
		)
		(fp_text user "${REFERENCE}"
			(at -0.95 -3.168 0)
			(layer "B.Fab")
			(hide yes)
			(effects
				(font
					(size 0.7 0.7)
					(thickness 0.15)
				)
				(justify left bottom mirror)
			)
		)
		(pad "1" smd roundrect
			(at -0.48 0 180)
			(size 0.59 0.64)
			(layers "B.Cu" "B.Paste" "B.Mask")
			(roundrect_rratio 0.25)
			(net 1 "GND")
			(pintype "passive")
		)
		(pad "2" smd roundrect
			(at 0.48 0 180)
			(size 0.59 0.64)
			(layers "B.Cu" "B.Paste" "B.Mask")
			(roundrect_rratio 0.25)
			(net 685 "Net-(U35-ISET)")
			(pintype "passive")
		)
	)
	(footprint "antmicro-footprints:R_0402_1005Metric"
		(layer "B.Cu")
		(at 91.3 118 90)
		(descr "Resistor SMD 0402")
		(tags "resistor SMD 0402")
		(property "Reference" "R282"
			(at 1.65 4.8 -90)
			(layer "B.SilkS")
			(effects
				(font
					(size 0.7 0.7)
					(thickness 0.15)
				)
				(justify left bottom mirror)
			)
		)
		(property "Value" "R_2k2_0402"
			(at 0 -1.4 -90)
			(layer "B.Fab")
			(effects
				(font
					(size 0.7 0.7)
					(thickness 0.15)
				)
				(justify left bottom mirror)
			)
		)
		(property "Footprint" "antmicro-footprints:R_0402_1005Metric"
			(at 0 0 90)
			(layer "F.Fab")
			(hide yes)
			(effects
				(font
					(size 1.27 1.27)
					(thickness 0.15)
				)
			)
		)
		(property "Datasheet" "https://www.bourns.com/docs/product-datasheets/cr.pdf"
			(at 0 0 90)
			(layer "F.Fab")
			(hide yes)
			(effects
				(font
					(size 1.27 1.27)
					(thickness 0.15)
				)
			)
		)
		(property "Author" "Antmicro"
			(at 209.3 26.7 0)
			(layer "B.Fab")
			(hide yes)
			(effects
				(font
					(size 1 1)
					(thickness 0.15)
				)
				(justify mirror)
			)
		)
		(property "License" "Apache-2.0"
			(at 209.3 26.7 0)
			(layer "B.Fab")
			(hide yes)
			(effects
				(font
					(size 1 1)
					(thickness 0.15)
				)
				(justify mirror)
			)
		)
		(property "MPN" "CR0402-FX-2201GLF"
			(at 209.3 26.7 0)
			(layer "B.Fab")
			(hide yes)
			(effects
				(font
					(size 1 1)
					(thickness 0.15)
				)
				(justify mirror)
			)
		)
		(property "Manufacturer" "Bourns"
			(at 209.3 26.7 0)
			(layer "B.Fab")
			(hide yes)
			(effects
				(font
					(size 1 1)
					(thickness 0.15)
				)
				(justify mirror)
			)
		)
		(property "Tolerance" "1%"
			(at 209.3 26.7 0)
			(layer "B.Fab")
			(hide yes)
			(effects
				(font
					(size 1 1)
					(thickness 0.15)
				)
				(justify mirror)
			)
		)
		(property "Val" "2k2"
			(at 209.3 26.7 0)
			(layer "B.Fab")
			(hide yes)
			(effects
				(font
					(size 1 1)
					(thickness 0.15)
				)
				(justify mirror)
			)
		)
		(sheetname "HDMI")
		(sheetfile "hdmi.kicad_sch")
		(attr smd exclude_from_pos_files exclude_from_bom dnp)
		(fp_rect
			(start -0.925 0.47)
			(end 0.925 -0.47)
			(stroke
				(width 0.05)
				(type default)
			)
			(fill none)
			(layer "B.CrtYd")
		)
		(fp_rect
			(start -0.5 0.25)
			(end 0.5 -0.25)
			(stroke
				(width 0.15)
				(type solid)
			)
			(fill none)
			(layer "B.Fab")
		)
		(fp_text user "License: Apache-2.0"
			(at -0.95 -5.169 -90)
			(layer "B.Fab")
			(hide yes)
			(effects
				(font
					(size 0.7 0.7)
					(thickness 0.15)
				)
				(justify left bottom mirror)
			)
		)
		(fp_text user "${REFERENCE}"
			(at -0.95 -3.168 -90)
			(layer "B.Fab")
			(hide yes)
			(effects
				(font
					(size 0.7 0.7)
					(thickness 0.15)
				)
				(justify left bottom mirror)
			)
		)
		(fp_text user "Author: Antmicro"
			(at -0.95 -4.169 -90)
			(layer "B.Fab")
			(hide yes)
			(effects
				(font
					(size 0.7 0.7)
					(thickness 0.15)
				)
				(justify left bottom mirror)
			)
		)
		(pad "1" smd roundrect
			(at -0.48 0 90)
			(size 0.59 0.64)
			(layers "B.Cu" "B.Paste" "B.Mask")
			(roundrect_rratio 0.25)
			(net 519 "/HDMI/HDMI_SCL_5V")
			(pintype "passive")
		)
		(pad "2" smd roundrect
			(at 0.48 0 90)
			(size 0.59 0.64)
			(layers "B.Cu" "B.Paste" "B.Mask")
			(roundrect_rratio 0.25)
			(net 498 "/HDMI/5V_HDMI")
			(pintype "passive")
		)
	)
	(footprint "antmicro-footprints:C_0402_1005Metric"
		(layer "B.Cu")
		(at 71.2 80.6 180)
		(descr "Capacitor SMD 0402")
		(tags "capacitor SMD 0402")
		(property "Reference" "C137"
			(at -0.94 -0.46 -90)
			(layer "B.SilkS")
			(effects
				(font
					(size 0.7 0.7)
					(thickness 0.15)
				)
				(justify left bottom mirror)
			)
		)
		(property "Value" "C_10u_0402"
			(at 0 -1.4 0)
			(layer "B.Fab")
			(effects
				(font
					(size 0.7 0.7)
					(thickness 0.15)
				)
				(justify left bottom mirror)
			)
		)
		(property "Footprint" "antmicro-footprints:C_0402_1005Metric"
			(at 0 0 180)
			(layer "F.Fab")
			(hide yes)
			(effects
				(font
					(size 1.27 1.27)
					(thickness 0.15)
				)
			)
		)
		(property "Datasheet" "https://www.yageo.com/en/Chart/Download/pdf/CC0402MRX5R5BB106"
			(at 0 0 180)
			(layer "F.Fab")
			(hide yes)
			(effects
				(font
					(size 1.27 1.27)
					(thickness 0.15)
				)
			)
		)
		(property "Author" "Antmicro"
			(at 142.4 161.2 0)
			(layer "B.Fab")
			(hide yes)
			(effects
				(font
					(size 1 1)
					(thickness 0.15)
				)
				(justify mirror)
			)
		)
		(property "Dielectric" ""
			(at 142.4 161.2 0)
			(layer "B.Fab")
			(hide yes)
			(effects
				(font
					(size 1 1)
					(thickness 0.15)
				)
				(justify mirror)
			)
		)
		(property "License" "Apache-2.0"
			(at 142.4 161.2 0)
			(layer "B.Fab")
			(hide yes)
			(effects
				(font
					(size 1 1)
					(thickness 0.15)
				)
				(justify mirror)
			)
		)
		(property "MPN" "CC0402MRX5R5BB106"
			(at 142.4 161.2 0)
			(layer "B.Fab")
			(hide yes)
			(effects
				(font
					(size 1 1)
					(thickness 0.15)
				)
				(justify mirror)
			)
		)
		(property "Manufacturer" "YAGEO"
			(at 142.4 161.2 0)
			(layer "B.Fab")
			(hide yes)
			(effects
				(font
					(size 1 1)
					(thickness 0.15)
				)
				(justify mirror)
			)
		)
		(property "Val" "10u"
			(at 142.4 161.2 0)
			(layer "B.Fab")
			(hide yes)
			(effects
				(font
					(size 1 1)
					(thickness 0.15)
				)
				(justify mirror)
			)
		)
		(property "Voltage" ""
			(at 142.4 161.2 0)
			(layer "B.Fab")
			(hide yes)
			(effects
				(font
					(size 1 1)
					(thickness 0.15)
				)
				(justify mirror)
			)
		)
		(sheetname "Supply")
		(sheetfile "supply.kicad_sch")
		(attr smd)
		(fp_rect
			(start -0.925 0.47)
			(end 0.925 -0.47)
			(stroke
				(width 0.05)
				(type default)
			)
			(fill none)
			(layer "B.CrtYd")
		)
		(fp_line
			(start 0.504 0.25)
			(end -0.494 0.25)
			(stroke
				(width 0.15)
				(type solid)
			)
			(layer "B.Fab")
		)
		(fp_line
			(start 0.504 -0.248)
			(end 0.504 0.25)
			(stroke
				(width 0.15)
				(type solid)
			)
			(layer "B.Fab")
		)
		(fp_line
			(start -0.494 0.25)
			(end -0.494 -0.248)
			(stroke
				(width 0.15)
				(type solid)
			)
			(layer "B.Fab")
		)
		(fp_line
			(start -0.494 -0.248)
			(end 0.504 -0.248)
			(stroke
				(width 0.15)
				(type solid)
			)
			(layer "B.Fab")
		)
		(fp_text user "License: Apache-2.0"
			(at -0.932 -5.17 0)
			(layer "B.Fab")
			(hide yes)
			(effects
				(font
					(size 0.7 0.7)
					(thickness 0.15)
				)
				(justify left bottom mirror)
			)
		)
		(fp_text user "${REFERENCE}"
			(at -0.932 -3.168 0)
			(layer "B.Fab")
			(hide yes)
			(effects
				(font
					(size 0.7 0.7)
					(thickness 0.15)
				)
				(justify left bottom mirror)
			)
		)
		(fp_text user "Author: Antmicro"
			(at -0.932 -4.17 0)
			(layer "B.Fab")
			(hide yes)
			(effects
				(font
					(size 0.7 0.7)
					(thickness 0.15)
				)
				(justify left bottom mirror)
			)
		)
		(pad "1" smd roundrect
			(at -0.48 0 180)
			(size 0.59 0.64)
			(layers "B.Cu" "B.Paste" "B.Mask")
			(roundrect_rratio 0.25)
			(net 1 "GND")
			(pintype "passive")
		)
		(pad "2" smd roundrect
			(at 0.48 0 180)
			(size 0.59 0.64)
			(layers "B.Cu" "B.Paste" "B.Mask")
			(roundrect_rratio 0.25)
			(net 138 "/Supply/3V3_LDO")
			(pintype "passive")
		)
	)
	(footprint "antmicro-footprints:C_0402_1005Metric"
		(layer "B.Cu")
		(at 95.55 90.975)
		(descr "Capacitor SMD 0402")
		(tags "capacitor SMD 0402")
		(property "Reference" "C132"
			(at 5.64 0.145 180)
			(layer "B.SilkS")
			(effects
				(font
					(size 0.7 0.7)
					(thickness 0.15)
				)
				(justify left bottom mirror)
			)
		)
		(property "Value" "C_100n_0402"
			(at 0 -1.4 180)
			(layer "B.Fab")
			(effects
				(font
					(size 0.7 0.7)
					(thickness 0.15)
				)
				(justify left bottom mirror)
			)
		)
		(property "Footprint" "antmicro-footprints:C_0402_1005Metric"
			(at 0 0 0)
			(layer "F.Fab")
			(hide yes)
			(effects
				(font
					(size 1.27 1.27)
					(thickness 0.15)
				)
			)
		)
		(property "Datasheet" "https://www.murata.com/products/productdetail?partno=GRM155R61H104KE14%23"
			(at 0 0 0)
			(layer "F.Fab")
			(hide yes)
			(effects
				(font
					(size 1.27 1.27)
					(thickness 0.15)
				)
			)
		)
		(property "Author" "Antmicro"
			(at 0 0 0)
			(layer "B.Fab")
			(hide yes)
			(effects
				(font
					(size 1 1)
					(thickness 0.15)
				)
				(justify mirror)
			)
		)
		(property "Dielectric" "X5R"
			(at 0 0 0)
			(layer "B.Fab")
			(hide yes)
			(effects
				(font
					(size 1 1)
					(thickness 0.15)
				)
				(justify mirror)
			)
		)
		(property "License" "Apache-2.0"
			(at 0 0 0)
			(layer "B.Fab")
			(hide yes)
			(effects
				(font
					(size 1 1)
					(thickness 0.15)
				)
				(justify mirror)
			)
		)
		(property "MPN" "GRM155R61H104KE14D"
			(at 0 0 0)
			(layer "B.Fab")
			(hide yes)
			(effects
				(font
					(size 1 1)
					(thickness 0.15)
				)
				(justify mirror)
			)
		)
		(property "Manufacturer" "Murata"
			(at 0 0 0)
			(layer "B.Fab")
			(hide yes)
			(effects
				(font
					(size 1 1)
					(thickness 0.15)
				)
				(justify mirror)
			)
		)
		(property "Val" "100n"
			(at 0 0 0)
			(layer "B.Fab")
			(hide yes)
			(effects
				(font
					(size 1 1)
					(thickness 0.15)
				)
				(justify mirror)
			)
		)
		(property "Voltage" "50V"
			(at 0 0 0)
			(layer "B.Fab")
			(hide yes)
			(effects
				(font
					(size 1 1)
					(thickness 0.15)
				)
				(justify mirror)
			)
		)
		(sheetname "HDMI")
		(sheetfile "hdmi.kicad_sch")
		(attr smd)
		(fp_rect
			(start -0.925 0.47)
			(end 0.925 -0.47)
			(stroke
				(width 0.05)
				(type default)
			)
			(fill none)
			(layer "B.CrtYd")
		)
		(fp_line
			(start -0.494 -0.248)
			(end 0.504 -0.248)
			(stroke
				(width 0.15)
				(type solid)
			)
			(layer "B.Fab")
		)
		(fp_line
			(start -0.494 0.25)
			(end -0.494 -0.248)
			(stroke
				(width 0.15)
				(type solid)
			)
			(layer "B.Fab")
		)
		(fp_line
			(start 0.504 -0.248)
			(end 0.504 0.25)
			(stroke
				(width 0.15)
				(type solid)
			)
			(layer "B.Fab")
		)
		(fp_line
			(start 0.504 0.25)
			(end -0.494 0.25)
			(stroke
				(width 0.15)
				(type solid)
			)
			(layer "B.Fab")
		)
		(fp_text user "Author: Antmicro"
			(at -0.932 -4.17 180)
			(layer "B.Fab")
			(hide yes)
			(effects
				(font
					(size 0.7 0.7)
					(thickness 0.15)
				)
				(justify left bottom mirror)
			)
		)
		(fp_text user "License: Apache-2.0"
			(at -0.932 -5.17 180)
			(layer "B.Fab")
			(hide yes)
			(effects
				(font
					(size 0.7 0.7)
					(thickness 0.15)
				)
				(justify left bottom mirror)
			)
		)
		(fp_text user "${REFERENCE}"
			(at -0.932 -3.168 180)
			(layer "B.Fab")
			(hide yes)
			(effects
				(font
					(size 0.7 0.7)
					(thickness 0.15)
				)
				(justify left bottom mirror)
			)
		)
		(pad "1" smd roundrect
			(at -0.48 0)
			(size 0.59 0.64)
			(layers "B.Cu" "B.Paste" "B.Mask")
			(roundrect_rratio 0.25)
			(net 666 "/HDMI/DP_MUX_D1+")
			(pintype "passive")
		)
		(pad "2" smd roundrect
			(at 0.48 0)
			(size 0.59 0.64)
			(layers "B.Cu" "B.Paste" "B.Mask")
			(roundrect_rratio 0.25)
			(net 419 "DP1_TXD2_HDMI_TX0_P")
			(pintype "passive")
		)
	)
	(footprint "antmicro-footprints:DFN3538"
		(layer "B.Cu")
		(at 48.04 105.7 180)
		(property "Reference" "D12"
			(at 0 2.8 0)
			(unlocked yes)
			(layer "B.SilkS")
			(effects
				(font
					(size 0.7 0.7)
					(thickness 0.15)
				)
				(justify left bottom mirror)
			)
		)
		(property "Value" "CD-MMBL110S"
			(at 0 -3.5 0)
			(unlocked yes)
			(layer "B.Fab")
			(effects
				(font
					(size 0.7 0.7)
					(thickness 0.15)
				)
				(justify left bottom mirror)
			)
		)
		(property "Footprint" "antmicro-footprints:DFN3538"
			(at 0 0 180)
			(layer "F.Fab")
			(hide yes)
			(effects
				(font
					(size 1.27 1.27)
					(thickness 0.15)
				)
			)
		)
		(property "Datasheet" "https://www.bourns.com/docs/product-datasheets/CD-MMBL110S.pdf"
			(at 0 0 180)
			(layer "F.Fab")
			(hide yes)
			(effects
				(font
					(size 1.27 1.27)
					(thickness 0.15)
				)
			)
		)
		(property "Author" "Antmicro"
			(at 96.08 211.4 0)
			(layer "B.Fab")
			(hide yes)
			(effects
				(font
					(size 1 1)
					(thickness 0.15)
				)
				(justify mirror)
			)
		)
		(property "License" "Apache-2.0"
			(at 96.08 211.4 0)
			(layer "B.Fab")
			(hide yes)
			(effects
				(font
					(size 1 1)
					(thickness 0.15)
				)
				(justify mirror)
			)
		)
		(property "MPN" "CD-MMBL110S"
			(at 96.08 211.4 0)
			(layer "B.Fab")
			(hide yes)
			(effects
				(font
					(size 1 1)
					(thickness 0.15)
				)
				(justify mirror)
			)
		)
		(property "Manufacturer" "Bourns"
			(at 96.08 211.4 0)
			(layer "B.Fab")
			(hide yes)
			(effects
				(font
					(size 1 1)
					(thickness 0.15)
				)
				(justify mirror)
			)
		)
		(sheetname "Ethernet")
		(sheetfile "ethernet.kicad_sch")
		(attr smd)
		(fp_line
			(start 1.8 2)
			(end 1.6 2)
			(stroke
				(width 0.15)
				(type solid)
			)
			(layer "B.SilkS")
		)
		(fp_line
			(start 1.8 -2.05)
			(end 1.8 2)
			(stroke
				(width 0.15)
				(type solid)
			)
			(layer "B.SilkS")
		)
		(fp_line
			(start 1.8 -2.05)
			(end 1.6 -2.05)
			(stroke
				(width 0.15)
				(type solid)
			)
			(layer "B.SilkS")
		)
		(fp_line
			(start 0.95 2)
			(end -0.95 2)
			(stroke
				(width 0.15)
				(type solid)
			)
			(layer "B.SilkS")
		)
		(fp_line
			(start 0.95 -2.05)
			(end -0.95 -2.05)
			(stroke
				(width 0.15)
				(type solid)
			)
			(layer "B.SilkS")
		)
		(fp_line
			(start 0.748 2.15)
			(end 0.748 2.452)
			(stroke
				(width 0.15)
				(type solid)
			)
			(layer "B.SilkS")
		)
		(fp_line
			(start 0.598 2.301)
			(end 0.9 2.301)
			(stroke
				(width 0.15)
				(type solid)
			)
			(layer "B.SilkS")
		)
		(fp_line
			(start -0.6 2.25)
			(end -0.902 2.25)
			(stroke
				(width 0.15)
				(type solid)
			)
			(layer "B.SilkS")
		)
		(fp_line
			(start -1.6 -2.05)
			(end -1.8 -2.05)
			(stroke
				(width 0.15)
				(type solid)
			)
			(layer "B.SilkS")
		)
		(fp_line
			(start -1.8 -2.05)
			(end -1.8 1.5)
			(stroke
				(width 0.15)
				(type solid)
			)
			(layer "B.SilkS")
		)
		(fp_rect
			(start -2.1 2.6)
			(end 2.1 -2.6)
			(stroke
				(width 0.05)
				(type solid)
			)
			(fill none)
			(layer "B.CrtYd")
		)
		(fp_line
			(start -1.801 1.25)
			(end -1.051 2)
			(stroke
				(width 0.15)
				(type solid)
			)
			(layer "B.Fab")
		)
		(fp_rect
			(start 1.8 -2.048)
			(end -1.8 2)
			(stroke
				(width 0.15)
				(type solid)
			)
			(fill none)
			(layer "B.Fab")
		)
		(fp_text user "~"
			(at -0.31 -2.8 0)
			(unlocked yes)
			(layer "B.SilkS")
			(effects
				(font
					(size 0.7 0.7)
					(thickness 0.15)
				)
				(justify left bottom mirror)
			)
		)
		(fp_text user "${REFERENCE}"
			(at -2.1 -4.599 0)
			(layer "B.Fab")
			(hide yes)
			(effects
				(font
					(size 0.7 0.7)
					(thickness 0.15)
				)
				(justify left bottom mirror)
			)
		)
		(fp_text user "License: Apache-2.0"
			(at -2.1 -6.599 0)
			(layer "B.Fab")
			(hide yes)
			(effects
				(font
					(size 0.7 0.7)
					(thickness 0.15)
				)
				(justify left bottom mirror)
			)
		)
		(fp_text user "Author: Antmicro"
			(at -2.1 -5.599 0)
			(layer "B.Fab")
			(hide yes)
			(effects
				(font
					(size 0.7 0.7)
					(thickness 0.15)
				)
				(justify left bottom mirror)
			)
		)
		(pad "1" smd roundrect
			(at -1.27 1.85 90)
			(size 1.4 0.48)
			(layers "B.Cu" "B.Paste" "B.Mask")
			(roundrect_rratio 0.25)
			(net 148 "Net-(D12-Pad1)")
			(pinfunction "1")
			(pintype "passive")
		)
		(pad "2" smd roundrect
			(at 1.27 1.85 90)
			(size 1.4 0.48)
			(layers "B.Cu" "B.Paste" "B.Mask")
			(roundrect_rratio 0.25)
			(net 149 "Net-(D12-Pad2)")
			(pinfunction "2")
			(pintype "passive")
		)
		(pad "3" smd roundrect
			(at -1.27 -1.85 90)
			(size 1.4 0.48)
			(layers "B.Cu" "B.Paste" "B.Mask")
			(roundrect_rratio 0.25)
			(net 121 "/Ethernet/PAIR_12")
			(pinfunction "3")
			(pintype "passive")
		)
		(pad "4" smd roundrect
			(at 1.27 -1.85 90)
			(size 1.4 0.48)
			(layers "B.Cu" "B.Paste" "B.Mask")
			(roundrect_rratio 0.25)
			(net 122 "/Ethernet/PAIR_36")
			(pinfunction "4")
			(pintype "passive")
		)
	)
	(footprint "antmicro-footprints:R_0402_1005Metric"
		(layer "B.Cu")
		(at 131.6 70.9 180)
		(descr "Resistor SMD 0402")
		(tags "resistor SMD 0402")
		(property "Reference" "R294"
			(at -1.4 0.4 0)
			(layer "B.SilkS")
			(effects
				(font
					(size 0.7 0.7)
					(thickness 0.15)
				)
				(justify left bottom mirror)
			)
		)
		(property "Value" "R_2k2_0402"
			(at 0 -1.4 0)
			(layer "B.Fab")
			(effects
				(font
					(size 0.7 0.7)
					(thickness 0.15)
				)
				(justify left bottom mirror)
			)
		)
		(property "Footprint" "antmicro-footprints:R_0402_1005Metric"
			(at 0 0 180)
			(layer "F.Fab")
			(hide yes)
			(effects
				(font
					(size 1.27 1.27)
					(thickness 0.15)
				)
			)
		)
		(property "Datasheet" "https://www.bourns.com/docs/product-datasheets/cr.pdf"
			(at 0 0 180)
			(layer "F.Fab")
			(hide yes)
			(effects
				(font
					(size 1.27 1.27)
					(thickness 0.15)
				)
			)
		)
		(property "Author" "Antmicro"
			(at 263.2 141.8 0)
			(layer "B.Fab")
			(hide yes)
			(effects
				(font
					(size 1 1)
					(thickness 0.15)
				)
				(justify mirror)
			)
		)
		(property "License" "Apache-2.0"
			(at 263.2 141.8 0)
			(layer "B.Fab")
			(hide yes)
			(effects
				(font
					(size 1 1)
					(thickness 0.15)
				)
				(justify mirror)
			)
		)
		(property "MPN" "CR0402-FX-2201GLF"
			(at 263.2 141.8 0)
			(layer "B.Fab")
			(hide yes)
			(effects
				(font
					(size 1 1)
					(thickness 0.15)
				)
				(justify mirror)
			)
		)
		(property "Manufacturer" "Bourns"
			(at 263.2 141.8 0)
			(layer "B.Fab")
			(hide yes)
			(effects
				(font
					(size 1 1)
					(thickness 0.15)
				)
				(justify mirror)
			)
		)
		(property "Tolerance" "1%"
			(at 263.2 141.8 0)
			(layer "B.Fab")
			(hide yes)
			(effects
				(font
					(size 1 1)
					(thickness 0.15)
				)
				(justify mirror)
			)
		)
		(property "Val" "2k2"
			(at 263.2 141.8 0)
			(layer "B.Fab")
			(hide yes)
			(effects
				(font
					(size 1 1)
					(thickness 0.15)
				)
				(justify mirror)
			)
		)
		(sheetname "SoM")
		(sheetfile "som.kicad_sch")
		(attr smd)
		(fp_rect
			(start -0.925 0.47)
			(end 0.925 -0.47)
			(stroke
				(width 0.05)
				(type default)
			)
			(fill none)
			(layer "B.CrtYd")
		)
		(fp_rect
			(start -0.5 0.25)
			(end 0.5 -0.25)
			(stroke
				(width 0.15)
				(type solid)
			)
			(fill none)
			(layer "B.Fab")
		)
		(fp_text user "Author: Antmicro"
			(at -0.95 -4.169 0)
			(layer "B.Fab")
			(hide yes)
			(effects
				(font
					(size 0.7 0.7)
					(thickness 0.15)
				)
				(justify left bottom mirror)
			)
		)
		(fp_text user "License: Apache-2.0"
			(at -0.95 -5.169 0)
			(layer "B.Fab")
			(hide yes)
			(effects
				(font
					(size 0.7 0.7)
					(thickness 0.15)
				)
				(justify left bottom mirror)
			)
		)
		(fp_text user "${REFERENCE}"
			(at -0.95 -3.168 0)
			(layer "B.Fab")
			(hide yes)
			(effects
				(font
					(size 0.7 0.7)
					(thickness 0.15)
				)
				(justify left bottom mirror)
			)
		)
		(pad "1" smd roundrect
			(at -0.48 0 180)
			(size 0.59 0.64)
			(layers "B.Cu" "B.Paste" "B.Mask")
			(roundrect_rratio 0.25)
			(net 732 "Net-(BT1-+)")
			(pintype "passive")
		)
		(pad "2" smd roundrect
			(at 0.48 0 180)
			(size 0.59 0.64)
			(layers "B.Cu" "B.Paste" "B.Mask")
			(roundrect_rratio 0.25)
			(net 85 "/SoM/PMIC_BBAT")
			(pintype "passive")
		)
	)
	(footprint "antmicro-footprints:R_Array_4x0201_Panasonic_EXB18V"
		(layer "B.Cu")
		(at 61.15 104.9 -90)
		(property "Reference" "R33"
			(at 1.32 0.64 90)
			(layer "B.SilkS")
			(effects
				(font
					(size 0.7 0.7)
					(thickness 0.15)
				)
				(justify right bottom mirror)
			)
		)
		(property "Value" "R_4x0R_0201_array"
			(at -1.1 -1.8 90)
			(layer "B.Fab")
			(effects
				(font
					(size 0.7 0.7)
					(thickness 0.15)
				)
				(justify left bottom mirror)
			)
		)
		(property "Footprint" "antmicro-footprints:R_Array_4x0201_Panasonic_EXB18V"
			(at 0 0 -90)
			(layer "F.Fab")
			(hide yes)
			(effects
				(font
					(size 1.27 1.27)
					(thickness 0.15)
				)
			)
		)
		(property "Datasheet" "http://industrial.panasonic.com/cdbs/www-data/pdf/AOC0000/AOC0000C14.pdf"
			(at 0 0 -90)
			(layer "F.Fab")
			(hide yes)
			(effects
				(font
					(size 1.27 1.27)
					(thickness 0.15)
				)
			)
		)
		(property "Author" "Antmicro"
			(at -43.75 166.05 0)
			(layer "B.Fab")
			(hide yes)
			(effects
				(font
					(size 1 1)
					(thickness 0.15)
				)
				(justify mirror)
			)
		)
		(property "License" "Apache-2.0"
			(at -43.75 166.05 0)
			(layer "B.Fab")
			(hide yes)
			(effects
				(font
					(size 1 1)
					(thickness 0.15)
				)
				(justify mirror)
			)
		)
		(property "MPN" "EXB-18VR000X"
			(at -43.75 166.05 0)
			(layer "B.Fab")
			(hide yes)
			(effects
				(font
					(size 1 1)
					(thickness 0.15)
				)
				(justify mirror)
			)
		)
		(property "Manufacturer" "Panasonic"
			(at -43.75 166.05 0)
			(layer "B.Fab")
			(hide yes)
			(effects
				(font
					(size 1 1)
					(thickness 0.15)
				)
				(justify mirror)
			)
		)
		(property "Val" "4x0R_0201"
			(at -43.75 166.05 0)
			(layer "B.Fab")
			(hide yes)
			(effects
				(font
					(size 1 1)
					(thickness 0.15)
				)
				(justify mirror)
			)
		)
		(sheetname "USB Debug, DP")
		(sheetfile "usb.kicad_sch")
		(attr smd)
		(fp_line
			(start -0.8 -0.45)
			(end -0.8 0.45)
			(stroke
				(width 0.12)
				(type solid)
			)
			(layer "B.SilkS")
		)
		(fp_line
			(start 0.8 -0.45)
			(end 0.8 0.45)
			(stroke
				(width 0.12)
				(type solid)
			)
			(layer "B.SilkS")
		)
		(fp_rect
			(start -0.898 0.66)
			(end 0.898 -0.65)
			(stroke
				(width 0.05)
				(type solid)
			)
			(fill none)
			(layer "B.CrtYd")
		)
		(fp_text user "${REFERENCE}"
			(at -1.051 -3.2 90)
			(layer "B.Fab")
			(hide yes)
			(effects
				(font
					(size 0.7 0.7)
					(thickness 0.15)
				)
				(justify left bottom mirror)
			)
		)
		(fp_text user "Author: Antmicro"
			(at -1.051 -4.599 90)
			(layer "B.Fab")
			(hide yes)
			(effects
				(font
					(size 0.7 0.7)
					(thickness 0.15)
				)
				(justify left bottom mirror)
			)
		)
		(fp_text user "License: Apache-2.0"
			(at -1.051 -6 90)
			(layer "B.Fab")
			(hide yes)
			(effects
				(font
					(size 0.7 0.7)
					(thickness 0.15)
				)
				(justify left bottom mirror)
			)
		)
		(pad "1" smd roundrect
			(at -0.6 -0.298 270)
			(size 0.2 0.4)
			(layers "B.Cu" "B.Paste" "B.Mask")
			(roundrect_rratio 0.25)
			(net 294 "/USB Debug, DP/PDC_CTL1")
			(pinfunction "R1.1")
			(pintype "passive")
		)
		(pad "2" smd roundrect
			(at -0.202 -0.298 270)
			(size 0.2 0.4)
			(layers "B.Cu" "B.Paste" "B.Mask")
			(roundrect_rratio 0.25)
			(net 298 "/USB Debug, DP/PDC_CTL0")
			(pinfunction "R2.1")
			(pintype "passive")
		)
		(pad "3" smd roundrect
			(at 0.2 -0.298 270)
			(size 0.2 0.4)
			(layers "B.Cu" "B.Paste" "B.Mask")
			(roundrect_rratio 0.25)
			(net 296 "/USB Debug, DP/PDC_FLIP")
			(pinfunction "R3.1")
			(pintype "passive")
		)
		(pad "4" smd roundrect
			(at 0.598 -0.298 270)
			(size 0.2 0.4)
			(layers "B.Cu" "B.Paste" "B.Mask")
			(roundrect_rratio 0.25)
			(net 633 "unconnected-(R33-R4.1-Pad4)")
			(pinfunction "R4.1")
			(pintype "passive+no_connect")
		)
		(pad "5" smd roundrect
			(at 0.598 0.3 270)
			(size 0.2 0.4)
			(layers "B.Cu" "B.Paste" "B.Mask")
			(roundrect_rratio 0.25)
			(net 634 "unconnected-(R33-R4.2-Pad5)")
			(pinfunction "R4.2")
			(pintype "passive+no_connect")
		)
		(pad "6" smd roundrect
			(at 0.2 0.3 270)
			(size 0.2 0.4)
			(layers "B.Cu" "B.Paste" "B.Mask")
			(roundrect_rratio 0.25)
			(net 293 "/USB Debug, DP/USBC0_FLIP")
			(pinfunction "R3.2")
			(pintype "passive")
		)
		(pad "7" smd roundrect
			(at -0.202 0.3 270)
			(size 0.2 0.4)
			(layers "B.Cu" "B.Paste" "B.Mask")
			(roundrect_rratio 0.25)
			(net 295 "/USB Debug, DP/USBC0_CTL0")
			(pinfunction "R2.2")
			(pintype "passive")
		)
		(pad "8" smd roundrect
			(at -0.6 0.3 270)
			(size 0.2 0.4)
			(layers "B.Cu" "B.Paste" "B.Mask")
			(roundrect_rratio 0.25)
			(net 297 "/USB Debug, DP/USBC0_CTL1")
			(pinfunction "R1.2")
			(pintype "passive")
		)
	)
	(footprint "antmicro-footprints:C_0402_1005Metric"
		(layer "B.Cu")
		(at 95.55 94.9)
		(descr "Capacitor SMD 0402")
		(tags "capacitor SMD 0402")
		(property "Reference" "C92"
			(at 5.21 0.62 180)
			(layer "B.SilkS")
			(effects
				(font
					(size 0.7 0.7)
					(thickness 0.15)
				)
				(justify left bottom mirror)
			)
		)
		(property "Value" "C_100n_0402"
			(at 0 -1.4 180)
			(layer "B.Fab")
			(effects
				(font
					(size 0.7 0.7)
					(thickness 0.15)
				)
				(justify left bottom mirror)
			)
		)
		(property "Footprint" "antmicro-footprints:C_0402_1005Metric"
			(at 0 0 0)
			(layer "F.Fab")
			(hide yes)
			(effects
				(font
					(size 1.27 1.27)
					(thickness 0.15)
				)
			)
		)
		(property "Datasheet" "https://www.murata.com/products/productdetail?partno=GRM155R61H104KE14%23"
			(at 0 0 0)
			(layer "F.Fab")
			(hide yes)
			(effects
				(font
					(size 1.27 1.27)
					(thickness 0.15)
				)
			)
		)
		(property "Author" "Antmicro"
			(at 0 0 0)
			(layer "B.Fab")
			(hide yes)
			(effects
				(font
					(size 1 1)
					(thickness 0.15)
				)
				(justify mirror)
			)
		)
		(property "Dielectric" "X5R"
			(at 0 0 0)
			(layer "B.Fab")
			(hide yes)
			(effects
				(font
					(size 1 1)
					(thickness 0.15)
				)
				(justify mirror)
			)
		)
		(property "License" "Apache-2.0"
			(at 0 0 0)
			(layer "B.Fab")
			(hide yes)
			(effects
				(font
					(size 1 1)
					(thickness 0.15)
				)
				(justify mirror)
			)
		)
		(property "MPN" "GRM155R61H104KE14D"
			(at 0 0 0)
			(layer "B.Fab")
			(hide yes)
			(effects
				(font
					(size 1 1)
					(thickness 0.15)
				)
				(justify mirror)
			)
		)
		(property "Manufacturer" "Murata"
			(at 0 0 0)
			(layer "B.Fab")
			(hide yes)
			(effects
				(font
					(size 1 1)
					(thickness 0.15)
				)
				(justify mirror)
			)
		)
		(property "Val" "100n"
			(at 0 0 0)
			(layer "B.Fab")
			(hide yes)
			(effects
				(font
					(size 1 1)
					(thickness 0.15)
				)
				(justify mirror)
			)
		)
		(property "Voltage" "50V"
			(at 0 0 0)
			(layer "B.Fab")
			(hide yes)
			(effects
				(font
					(size 1 1)
					(thickness 0.15)
				)
				(justify mirror)
			)
		)
		(sheetname "HDMI")
		(sheetfile "hdmi.kicad_sch")
		(attr smd)
		(fp_rect
			(start -0.925 0.47)
			(end 0.925 -0.47)
			(stroke
				(width 0.05)
				(type default)
			)
			(fill none)
			(layer "B.CrtYd")
		)
		(fp_line
			(start -0.494 -0.248)
			(end 0.504 -0.248)
			(stroke
				(width 0.15)
				(type solid)
			)
			(layer "B.Fab")
		)
		(fp_line
			(start -0.494 0.25)
			(end -0.494 -0.248)
			(stroke
				(width 0.15)
				(type solid)
			)
			(layer "B.Fab")
		)
		(fp_line
			(start 0.504 -0.248)
			(end 0.504 0.25)
			(stroke
				(width 0.15)
				(type solid)
			)
			(layer "B.Fab")
		)
		(fp_line
			(start 0.504 0.25)
			(end -0.494 0.25)
			(stroke
				(width 0.15)
				(type solid)
			)
			(layer "B.Fab")
		)
		(fp_text user "Author: Antmicro"
			(at -0.932 -4.17 180)
			(layer "B.Fab")
			(hide yes)
			(effects
				(font
					(size 0.7 0.7)
					(thickness 0.15)
				)
				(justify left bottom mirror)
			)
		)
		(fp_text user "License: Apache-2.0"
			(at -0.932 -5.17 180)
			(layer "B.Fab")
			(hide yes)
			(effects
				(font
					(size 0.7 0.7)
					(thickness 0.15)
				)
				(justify left bottom mirror)
			)
		)
		(fp_text user "${REFERENCE}"
			(at -0.932 -3.168 180)
			(layer "B.Fab")
			(hide yes)
			(effects
				(font
					(size 0.7 0.7)
					(thickness 0.15)
				)
				(justify left bottom mirror)
			)
		)
		(pad "1" smd roundrect
			(at -0.48 0)
			(size 0.59 0.64)
			(layers "B.Cu" "B.Paste" "B.Mask")
			(roundrect_rratio 0.25)
			(net 699 "/HDMI/DP_MUX_D3-")
			(pintype "passive")
		)
		(pad "2" smd roundrect
			(at 0.48 0)
			(size 0.59 0.64)
			(layers "B.Cu" "B.Paste" "B.Mask")
			(roundrect_rratio 0.25)
			(net 274 "DP1_TXD0_HDMI_TX2_N")
			(pintype "passive")
		)
	)
	(footprint "antmicro-footprints:SOT-523"
		(layer "B.Cu")
		(at 48.7 74.3 180)
		(property "Reference" "Q22"
			(at -1.75 -1.85 180)
			(layer "B.SilkS")
			(effects
				(font
					(size 0.7 0.7)
					(thickness 0.15)
				)
				(justify left bottom mirror)
			)
		)
		(property "Value" "PJE138K"
			(at 0.1 -1.824 0)
			(layer "B.Fab")
			(effects
				(font
					(size 0.7 0.7)
					(thickness 0.15)
				)
				(justify left bottom mirror)
			)
		)
		(property "Footprint" "antmicro-footprints:SOT-523"
			(at 0 0 0)
			(layer "B.Fab")
			(hide yes)
			(effects
				(font
					(size 1.27 1.27)
					(thickness 0.15)
				)
				(justify mirror)
			)
		)
		(property "Datasheet" "https://www.mouser.com/datasheet/2/1057/PJE138K-1876698.pdf"
			(at 0 0 0)
			(layer "B.Fab")
			(hide yes)
			(effects
				(font
					(size 1.27 1.27)
					(thickness 0.15)
				)
				(justify mirror)
			)
		)
		(property "MPN" "PJE138K_R1_00001"
			(at 0 0 0)
			(unlocked yes)
			(layer "B.Fab")
			(hide yes)
			(effects
				(font
					(size 1 1)
					(thickness 0.15)
				)
				(justify mirror)
			)
		)
		(property "Manufacturer" "PANJIT"
			(at 0 0 0)
			(unlocked yes)
			(layer "B.Fab")
			(hide yes)
			(effects
				(font
					(size 1 1)
					(thickness 0.15)
				)
				(justify mirror)
			)
		)
		(property "Author" "Antmicro"
			(at 0 0 0)
			(unlocked yes)
			(layer "B.Fab")
			(hide yes)
			(effects
				(font
					(size 1 1)
					(thickness 0.15)
				)
				(justify mirror)
			)
		)
		(property "License" "Apache-2.0"
			(at 0 0 0)
			(unlocked yes)
			(layer "B.Fab")
			(hide yes)
			(effects
				(font
					(size 1 1)
					(thickness 0.15)
				)
				(justify mirror)
			)
		)
		(sheetname "Supply")
		(sheetfile "supply.kicad_sch")
		(attr smd)
		(fp_line
			(start -0.277 0.75)
			(end -0.277 0.551)
			(stroke
				(width 0.15)
				(type solid)
			)
			(layer "B.SilkS")
		)
		(fp_line
			(start -0.277 0.551)
			(end -0.725 0.551)
			(stroke
				(width 0.15)
				(type solid)
			)
			(layer "B.SilkS")
		)
		(fp_line
			(start -0.725 0.551)
			(end -0.927 0.351)
			(stroke
				(width 0.15)
				(type solid)
			)
			(layer "B.SilkS")
		)
		(fp_line
			(start -0.927 0.351)
			(end -0.927 0.051)
			(stroke
				(width 0.15)
				(type solid)
			)
			(layer "B.SilkS")
		)
		(fp_circle
			(center -0.9652 -0.9652)
			(end -0.9152 -0.9652)
			(stroke
				(width 0.15)
				(type solid)
			)
			(fill solid)
			(layer "B.SilkS")
		)
		(fp_line
			(start 1.1 1.16)
			(end -1.12 1.16)
			(stroke
				(width 0.05)
				(type solid)
			)
			(layer "B.CrtYd")
		)
		(fp_line
			(start 1.1 -1.15)
			(end 1.1 1.16)
			(stroke
				(width 0.05)
				(type solid)
			)
			(layer "B.CrtYd")
		)
		(fp_line
			(start 1.1 -1.15)
			(end -1.12 -1.15)
			(stroke
				(width 0.05)
				(type solid)
			)
			(layer "B.CrtYd")
		)
		(fp_line
			(start -1.12 -1.15)
			(end -1.12 1.16)
			(stroke
				(width 0.05)
				(type solid)
			)
			(layer "B.CrtYd")
		)
		(fp_line
			(start 0.8 -0.424)
			(end 0.8 0.425)
			(stroke
				(width 0.15)
				(type solid)
			)
			(layer "B.Fab")
		)
		(fp_line
			(start -0.652 0.425)
			(end 0.8 0.425)
			(stroke
				(width 0.15)
				(type solid)
			)
			(layer "B.Fab")
		)
		(fp_line
			(start -0.802 0.276)
			(end -0.652 0.425)
			(stroke
				(width 0.15)
				(type solid)
			)
			(layer "B.Fab")
		)
		(fp_line
			(start -0.802 -0.424)
			(end 0.8 -0.424)
			(stroke
				(width 0.15)
				(type solid)
			)
			(layer "B.Fab")
		)
		(fp_line
			(start -0.802 -0.424)
			(end -0.802 0.276)
			(stroke
				(width 0.15)
				(type solid)
			)
			(layer "B.Fab")
		)
		(fp_circle
			(center -0.9652 -0.9652)
			(end -0.9144 -0.9652)
			(stroke
				(width 0.15)
				(type solid)
			)
			(fill none)
			(layer "B.Fab")
		)
		(fp_text user "Author: Antmicro"
			(at -1.12 -6.224 0)
			(layer "B.Fab")
			(hide yes)
			(effects
				(font
					(size 0.7 0.7)
					(thickness 0.15)
				)
				(justify left bottom mirror)
			)
		)
		(fp_text user "${REFERENCE}"
			(at -1.12 -3.824 0)
			(layer "B.Fab")
			(hide yes)
			(effects
				(font
					(size 0.7 0.7)
					(thickness 0.15)
				)
				(justify left bottom mirror)
			)
		)
		(fp_text user "License: Apache-2.0"
			(at -1.12 -5.024 0)
			(layer "B.Fab")
			(hide yes)
			(effects
				(font
					(size 0.7 0.7)
					(thickness 0.15)
				)
				(justify left bottom mirror)
			)
		)
		(pad "1" smd rect
			(at -0.5 -0.65 180)
			(size 0.4 0.51)
			(layers "B.Cu" "B.Paste" "B.Mask")
			(net 799 "/Supply/PG_{HP}")
			(pinfunction "G")
			(pintype "passive")
		)
		(pad "2" smd rect
			(at 0.498 -0.65 180)
			(size 0.4 0.51)
			(layers "B.Cu" "B.Paste" "B.Mask")
			(net 1 "GND")
			(pinfunction "S")
			(pintype "passive")
		)
		(pad "3" smd rect
			(at 0 0.652 180)
			(size 0.4 0.51)
			(layers "B.Cu" "B.Paste" "B.Mask")
			(net 793 "Net-(D62-C)")
			(pinfunction "D")
			(pintype "passive")
		)
	)
	(footprint "antmicro-footprints:R_0402_1005Metric"
		(layer "B.Cu")
		(at 74 105.3 -90)
		(descr "Resistor SMD 0402")
		(tags "resistor SMD 0402")
		(property "Reference" "R86"
			(at -5.03 -1.69 90)
			(layer "B.SilkS")
			(effects
				(font
					(size 0.7 0.7)
					(thickness 0.15)
				)
				(justify left bottom mirror)
			)
		)
		(property "Value" "R_1k_0402"
			(at 0 -1.4 90)
			(layer "B.Fab")
			(effects
				(font
					(size 0.7 0.7)
					(thickness 0.15)
				)
				(justify left bottom mirror)
			)
		)
		(property "Footprint" "antmicro-footprints:R_0402_1005Metric"
			(at 0 0 -90)
			(layer "F.Fab")
			(hide yes)
			(effects
				(font
					(size 1.27 1.27)
					(thickness 0.15)
				)
			)
		)
		(property "Datasheet" "https://www.bourns.com/docs/product-datasheets/cr.pdf"
			(at 0 0 -90)
			(layer "F.Fab")
			(hide yes)
			(effects
				(font
					(size 1.27 1.27)
					(thickness 0.15)
				)
			)
		)
		(property "Author" "Antmicro"
			(at -31.3 179.3 0)
			(layer "B.Fab")
			(hide yes)
			(effects
				(font
					(size 1 1)
					(thickness 0.15)
				)
				(justify mirror)
			)
		)
		(property "License" "Apache-2.0"
			(at -31.3 179.3 0)
			(layer "B.Fab")
			(hide yes)
			(effects
				(font
					(size 1 1)
					(thickness 0.15)
				)
				(justify mirror)
			)
		)
		(property "MPN" "CR0402-FX-1001GLF"
			(at -31.3 179.3 0)
			(layer "B.Fab")
			(hide yes)
			(effects
				(font
					(size 1 1)
					(thickness 0.15)
				)
				(justify mirror)
			)
		)
		(property "Manufacturer" "Bourns"
			(at -31.3 179.3 0)
			(layer "B.Fab")
			(hide yes)
			(effects
				(font
					(size 1 1)
					(thickness 0.15)
				)
				(justify mirror)
			)
		)
		(property "Tolerance" "1%"
			(at -31.3 179.3 0)
			(layer "B.Fab")
			(hide yes)
			(effects
				(font
					(size 1 1)
					(thickness 0.15)
				)
				(justify mirror)
			)
		)
		(property "Val" "1k"
			(at -31.3 179.3 0)
			(layer "B.Fab")
			(hide yes)
			(effects
				(font
					(size 1 1)
					(thickness 0.15)
				)
				(justify mirror)
			)
		)
		(sheetname "USB Debug, DP")
		(sheetfile "usb.kicad_sch")
		(attr smd)
		(fp_rect
			(start -0.925 0.47)
			(end 0.925 -0.47)
			(stroke
				(width 0.05)
				(type default)
			)
			(fill none)
			(layer "B.CrtYd")
		)
		(fp_rect
			(start -0.5 0.25)
			(end 0.5 -0.25)
			(stroke
				(width 0.15)
				(type solid)
			)
			(fill none)
			(layer "B.Fab")
		)
		(fp_text user "${REFERENCE}"
			(at -0.95 -3.168 90)
			(layer "B.Fab")
			(hide yes)
			(effects
				(font
					(size 0.7 0.7)
					(thickness 0.15)
				)
				(justify left bottom mirror)
			)
		)
		(fp_text user "Author: Antmicro"
			(at -0.95 -4.169 90)
			(layer "B.Fab")
			(hide yes)
			(effects
				(font
					(size 0.7 0.7)
					(thickness 0.15)
				)
				(justify left bottom mirror)
			)
		)
		(fp_text user "License: Apache-2.0"
			(at -0.95 -5.169 90)
			(layer "B.Fab")
			(hide yes)
			(effects
				(font
					(size 0.7 0.7)
					(thickness 0.15)
				)
				(justify left bottom mirror)
			)
		)
		(pad "1" smd roundrect
			(at -0.48 0 270)
			(size 0.59 0.64)
			(layers "B.Cu" "B.Paste" "B.Mask")
			(roundrect_rratio 0.25)
			(net 304 "/USB Debug, DP/USBC0_I2C_EN")
			(pintype "passive")
		)
		(pad "2" smd roundrect
			(at 0.48 0 270)
			(size 0.59 0.64)
			(layers "B.Cu" "B.Paste" "B.Mask")
			(roundrect_rratio 0.25)
			(net 1 "GND")
			(pintype "passive")
		)
	)
	(footprint "antmicro-footprints:R_0402_1005Metric"
		(layer "B.Cu")
		(at 134 116.55)
		(descr "Resistor SMD 0402")
		(tags "resistor SMD 0402")
		(property "Reference" "R8"
			(at -0.75 0.45 180)
			(layer "B.SilkS")
			(effects
				(font
					(size 0.7 0.7)
					(thickness 0.15)
				)
				(justify left bottom mirror)
			)
		)
		(property "Value" "R_4k7_0402"
			(at 0 -1.4 180)
			(layer "B.Fab")
			(effects
				(font
					(size 0.7 0.7)
					(thickness 0.15)
				)
				(justify left bottom mirror)
			)
		)
		(property "Footprint" "antmicro-footprints:R_0402_1005Metric"
			(at 0 0 0)
			(layer "F.Fab")
			(hide yes)
			(effects
				(font
					(size 1.27 1.27)
					(thickness 0.15)
				)
			)
		)
		(property "Datasheet" "https://www.bourns.com/docs/product-datasheets/cr.pdf"
			(at 0 0 0)
			(layer "F.Fab")
			(hide yes)
			(effects
				(font
					(size 1.27 1.27)
					(thickness 0.15)
				)
			)
		)
		(property "Author" "Antmicro"
			(at 0 0 0)
			(layer "B.Fab")
			(hide yes)
			(effects
				(font
					(size 1 1)
					(thickness 0.15)
				)
				(justify mirror)
			)
		)
		(property "License" "Apache-2.0"
			(at 0 0 0)
			(layer "B.Fab")
			(hide yes)
			(effects
				(font
					(size 1 1)
					(thickness 0.15)
				)
				(justify mirror)
			)
		)
		(property "MPN" "CR0402-FX-4701GLF"
			(at 0 0 0)
			(layer "B.Fab")
			(hide yes)
			(effects
				(font
					(size 1 1)
					(thickness 0.15)
				)
				(justify mirror)
			)
		)
		(property "Manufacturer" "Bourns"
			(at 0 0 0)
			(layer "B.Fab")
			(hide yes)
			(effects
				(font
					(size 1 1)
					(thickness 0.15)
				)
				(justify mirror)
			)
		)
		(property "Tolerance" "1%"
			(at 0 0 0)
			(layer "B.Fab")
			(hide yes)
			(effects
				(font
					(size 1 1)
					(thickness 0.15)
				)
				(justify mirror)
			)
		)
		(property "Val" "4k7"
			(at 0 0 0)
			(layer "B.Fab")
			(hide yes)
			(effects
				(font
					(size 1 1)
					(thickness 0.15)
				)
				(justify mirror)
			)
		)
		(sheetname "CSI")
		(sheetfile "csi.kicad_sch")
		(attr smd)
		(fp_rect
			(start -0.925 0.47)
			(end 0.925 -0.47)
			(stroke
				(width 0.05)
				(type default)
			)
			(fill none)
			(layer "B.CrtYd")
		)
		(fp_rect
			(start -0.5 0.25)
			(end 0.5 -0.25)
			(stroke
				(width 0.15)
				(type solid)
			)
			(fill none)
			(layer "B.Fab")
		)
		(fp_text user "License: Apache-2.0"
			(at -0.95 -5.169 180)
			(layer "B.Fab")
			(hide yes)
			(effects
				(font
					(size 0.7 0.7)
					(thickness 0.15)
				)
				(justify left bottom mirror)
			)
		)
		(fp_text user "${REFERENCE}"
			(at -0.95 -3.168 180)
			(layer "B.Fab")
			(hide yes)
			(effects
				(font
					(size 0.7 0.7)
					(thickness 0.15)
				)
				(justify left bottom mirror)
			)
		)
		(fp_text user "Author: Antmicro"
			(at -0.95 -4.169 180)
			(layer "B.Fab")
			(hide yes)
			(effects
				(font
					(size 0.7 0.7)
					(thickness 0.15)
				)
				(justify left bottom mirror)
			)
		)
		(pad "1" smd roundrect
			(at -0.48 0)
			(size 0.59 0.64)
			(layers "B.Cu" "B.Paste" "B.Mask")
			(roundrect_rratio 0.25)
			(net 1 "GND")
			(pintype "passive")
		)
		(pad "2" smd roundrect
			(at 0.48 0)
			(size 0.59 0.64)
			(layers "B.Cu" "B.Paste" "B.Mask")
			(roundrect_rratio 0.25)
			(net 335 "/CSI/CSIA_3V3_ISET")
			(pintype "passive")
		)
	)
	(footprint "antmicro-footprints:PCM12SMTR"
		(layer "B.Cu")
		(at 55.3895 72.796)
		(property "Reference" "SW1"
			(at 0.3705 2.474 180)
			(layer "B.SilkS")
			(effects
				(font
					(size 0.7 0.7)
					(thickness 0.15)
				)
				(justify left bottom mirror)
			)
		)
		(property "Value" "SW_SPDT_PCM12SMTR"
			(at 7.836 -5.94 180)
			(layer "B.Fab")
			(effects
				(font
					(size 0.7 0.7)
					(thickness 0.15)
				)
				(justify left bottom mirror)
			)
		)
		(property "Footprint" "antmicro-footprints:PCM12SMTR"
			(at 0 0 0)
			(layer "F.Fab")
			(hide yes)
			(effects
				(font
					(size 1.27 1.27)
					(thickness 0.15)
				)
			)
		)
		(property "Datasheet" "https://www.mouser.com/datasheet/2/60/pcm-1841544.pdf"
			(at 0 0 0)
			(layer "F.Fab")
			(hide yes)
			(effects
				(font
					(size 1.27 1.27)
					(thickness 0.15)
				)
			)
		)
		(property "Author" "Antmicro"
			(at 0 0 0)
			(layer "B.Fab")
			(hide yes)
			(effects
				(font
					(size 1 1)
					(thickness 0.15)
				)
				(justify mirror)
			)
		)
		(property "License" "Apache-2.0"
			(at 0 0 0)
			(layer "B.Fab")
			(hide yes)
			(effects
				(font
					(size 1 1)
					(thickness 0.15)
				)
				(justify mirror)
			)
		)
		(property "MPN" "PCM12SMTR"
			(at 0 0 0)
			(layer "B.Fab")
			(hide yes)
			(effects
				(font
					(size 1 1)
					(thickness 0.15)
				)
				(justify mirror)
			)
		)
		(property "Manufacturer" "C&K"
			(at 0 0 0)
			(layer "B.Fab")
			(hide yes)
			(effects
				(font
					(size 1 1)
					(thickness 0.15)
				)
				(justify mirror)
			)
		)
		(sheetname "Supply")
		(sheetfile "supply.kicad_sch")
		(attr smd)
		(fp_line
			(start -3.351 0.251)
			(end -3.351 -0.348)
			(stroke
				(width 0.15)
				(type solid)
			)
			(layer "B.SilkS")
		)
		(fp_line
			(start 0.1 1.251)
			(end -1.601 1.251)
			(stroke
				(width 0.15)
				(type solid)
			)
			(layer "B.SilkS")
		)
		(fp_line
			(start 2.9 -1.348)
			(end -2.901 -1.348)
			(stroke
				(width 0.15)
				(type solid)
			)
			(layer "B.SilkS")
		)
		(fp_line
			(start 3.349 -0.348)
			(end 3.349 0.251)
			(stroke
				(width 0.15)
				(type solid)
			)
			(layer "B.SilkS")
		)
		(fp_circle
			(center -3.15 2.45)
			(end -3.1 2.39)
			(stroke
				(width 0.15)
				(type solid)
			)
			(fill solid)
			(layer "B.SilkS")
		)
		(fp_line
			(start -4.42 -1.65)
			(end -1.77 -1.65)
			(stroke
				(width 0.05)
				(type solid)
			)
			(layer "B.CrtYd")
		)
		(fp_line
			(start -4.42 1.57)
			(end -4.42 -1.65)
			(stroke
				(width 0.05)
				(type solid)
			)
			(layer "B.CrtYd")
		)
		(fp_line
			(start -2.86 1.57)
			(end -4.42 1.57)
			(stroke
				(width 0.05)
				(type solid)
			)
			(layer "B.CrtYd")
		)
		(fp_line
			(start -2.86 2.7)
			(end -2.86 1.57)
			(stroke
				(width 0.05)
				(type solid)
			)
			(layer "B.CrtYd")
		)
		(fp_line
			(start -1.77 -3.08)
			(end 1.74 -3.08)
			(stroke
				(width 0.05)
				(type solid)
			)
			(layer "B.CrtYd")
		)
		(fp_line
			(start -1.77 -1.65)
			(end -1.77 -3.08)
			(stroke
				(width 0.05)
				(type solid)
			)
			(layer "B.CrtYd")
		)
		(fp_line
			(start 1.74 -3.08)
			(end 1.74 -1.65)
			(stroke
				(width 0.05)
				(type solid)
			)
			(layer "B.CrtYd")
		)
		(fp_line
			(start 1.74 -1.65)
			(end 4.4 -1.65)
			(stroke
				(width 0.05)
				(type solid)
			)
			(layer "B.CrtYd")
		)
		(fp_line
			(start 2.83 1.57)
			(end 2.83 2.7)
			(stroke
				(width 0.05)
				(type solid)
			)
			(layer "B.CrtYd")
		)
		(fp_line
			(start 2.83 2.7)
			(end -2.86 2.7)
			(stroke
				(width 0.05)
				(type solid)
			)
			(layer "B.CrtYd")
		)
		(fp_line
			(start 4.4 -1.65)
			(end 4.4 1.57)
			(stroke
				(width 0.05)
				(type solid)
			)
			(layer "B.CrtYd")
		)
		(fp_line
			(start 4.4 1.57)
			(end 2.83 1.57)
			(stroke
				(width 0.05)
				(type solid)
			)
			(layer "B.CrtYd")
		)
		(fp_line
			(start -3.351 -1.348)
			(end -1.502 -1.348)
			(stroke
				(width 0.15)
				(type solid)
			)
			(layer "B.Fab")
		)
		(fp_line
			(start -3.351 1.251)
			(end -3.351 -1.348)
			(stroke
				(width 0.15)
				(type solid)
			)
			(layer "B.Fab")
		)
		(fp_line
			(start -1.502 -2.849)
			(end -1.502 -1.348)
			(stroke
				(width 0.15)
				(type solid)
			)
			(layer "B.Fab")
		)
		(fp_line
			(start -1.502 -1.348)
			(end 1.499 -1.348)
			(stroke
				(width 0.15)
				(type solid)
			)
			(layer "B.Fab")
		)
		(fp_line
			(start 1.499 -2.849)
			(end -1.502 -2.849)
			(stroke
				(width 0.15)
				(type solid)
			)
			(layer "B.Fab")
		)
		(fp_line
			(start 1.499 -1.348)
			(end 1.499 -2.849)
			(stroke
				(width 0.15)
				(type solid)
			)
			(layer "B.Fab")
		)
		(fp_line
			(start 1.499 -1.348)
			(end 3.349 -1.348)
			(stroke
				(width 0.15)
				(type solid)
			)
			(layer "B.Fab")
		)
		(fp_line
			(start 3.349 -1.348)
			(end 3.349 1.251)
			(stroke
				(width 0.15)
				(type solid)
			)
			(layer "B.Fab")
		)
		(fp_line
			(start 3.349 1.251)
			(end -3.351 1.251)
			(stroke
				(width 0.15)
				(type solid)
			)
			(layer "B.Fab")
		)
		(fp_text user "${REFERENCE}"
			(at -2.152 -7.94 180)
			(layer "B.Fab")
			(hide yes)
			(effects
				(font
					(size 0.7 0.7)
					(thickness 0.15)
				)
				(justify left bottom mirror)
			)
		)
		(fp_text user "Author: Antmicro"
			(at -2.152 -9.14 180)
			(layer "B.Fab")
			(hide yes)
			(effects
				(font
					(size 0.7 0.7)
					(thickness 0.15)
				)
				(justify left bottom mirror)
			)
		)
		(fp_text user "License: Apache-2.0"
			(at -2.152 -10.339 180)
			(layer "B.Fab")
			(hide yes)
			(effects
				(font
					(size 0.7 0.7)
					(thickness 0.15)
				)
				(justify left bottom mirror)
			)
		)
		(pad "" np_thru_hole circle
			(at -1.502 -0.049)
			(size 0.9 0.9)
			(drill 0.9)
			(layers "*.Cu" "*.Mask")
		)
		(pad "" np_thru_hole circle
			(at 1.499 -0.049)
			(size 0.9 0.9)
			(drill 0.9)
			(layers "*.Cu" "*.Mask")
		)
		(pad "1" smd roundrect
			(at -2.25 1.7)
			(size 0.7 1.5)
			(layers "B.Cu" "B.Paste" "B.Mask")
			(roundrect_rratio 0.25)
			(net 534 "unconnected-(SW1-Pad1)")
			(pintype "passive+no_connect")
		)
		(pad "2" smd roundrect
			(at 0.749 1.7)
			(size 0.7 1.5)
			(layers "B.Cu" "B.Paste" "B.Mask")
			(roundrect_rratio 0.25)
			(net 530 "Net-(R256-Pad1)")
			(pintype "passive")
		)
		(pad "3" smd roundrect
			(at 2.248 1.7)
			(size 0.7 1.5)
			(layers "B.Cu" "B.Paste" "B.Mask")
			(roundrect_rratio 0.25)
			(net 137 "Net-(D36-A)")
			(pintype "passive")
		)
		(pad "S1" smd roundrect
			(at -3.651 0.915)
			(size 1 0.8)
			(layers "B.Cu" "B.Paste" "B.Mask")
			(roundrect_rratio 0.25)
			(net 1 "GND")
			(pinfunction "SH")
			(pintype "passive")
		)
		(pad "S2" smd roundrect
			(at -3.651 -1.013)
			(size 1 0.8)
			(layers "B.Cu" "B.Paste" "B.Mask")
			(roundrect_rratio 0.25)
			(net 1 "GND")
			(pinfunction "SH")
			(pintype "passive")
		)
		(pad "S3" smd roundrect
			(at 3.65 -1.013)
			(size 1 0.8)
			(layers "B.Cu" "B.Paste" "B.Mask")
			(roundrect_rratio 0.25)
			(net 1 "GND")
			(pinfunction "SH")
			(pintype "passive")
		)
		(pad "S4" smd roundrect
			(at 3.65 0.915)
			(size 1 0.8)
			(layers "B.Cu" "B.Paste" "B.Mask")
			(roundrect_rratio 0.25)
			(net 1 "GND")
			(pinfunction "SH")
			(pintype "passive")
		)
	)
	(footprint "antmicro-footprints:C_0402_1005Metric"
		(layer "B.Cu")
		(at 69.475 86.3 90)
		(descr "Capacitor SMD 0402")
		(tags "capacitor SMD 0402")
		(property "Reference" "C101"
			(at 1.4 1.335 -90)
			(layer "B.SilkS")
			(effects
				(font
					(size 0.7 0.7)
					(thickness 0.15)
				)
				(justify left bottom mirror)
			)
		)
		(property "Value" "C_100n_0402"
			(at 0 -1.4 -90)
			(layer "B.Fab")
			(effects
				(font
					(size 0.7 0.7)
					(thickness 0.15)
				)
				(justify left bottom mirror)
			)
		)
		(property "Footprint" "antmicro-footprints:C_0402_1005Metric"
			(at 0 0 90)
			(layer "F.Fab")
			(hide yes)
			(effects
				(font
					(size 1.27 1.27)
					(thickness 0.15)
				)
			)
		)
		(property "Datasheet" "https://www.murata.com/products/productdetail?partno=GRM155R61H104KE14%23"
			(at 0 0 90)
			(layer "F.Fab")
			(hide yes)
			(effects
				(font
					(size 1.27 1.27)
					(thickness 0.15)
				)
			)
		)
		(property "Author" "Antmicro"
			(at 155.775 16.825 0)
			(layer "B.Fab")
			(hide yes)
			(effects
				(font
					(size 1 1)
					(thickness 0.15)
				)
				(justify mirror)
			)
		)
		(property "Dielectric" "X5R"
			(at 155.775 16.825 0)
			(layer "B.Fab")
			(hide yes)
			(effects
				(font
					(size 1 1)
					(thickness 0.15)
				)
				(justify mirror)
			)
		)
		(property "License" "Apache-2.0"
			(at 155.775 16.825 0)
			(layer "B.Fab")
			(hide yes)
			(effects
				(font
					(size 1 1)
					(thickness 0.15)
				)
				(justify mirror)
			)
		)
		(property "MPN" "GRM155R61H104KE14D"
			(at 155.775 16.825 0)
			(layer "B.Fab")
			(hide yes)
			(effects
				(font
					(size 1 1)
					(thickness 0.15)
				)
				(justify mirror)
			)
		)
		(property "Manufacturer" "Murata"
			(at 155.775 16.825 0)
			(layer "B.Fab")
			(hide yes)
			(effects
				(font
					(size 1 1)
					(thickness 0.15)
				)
				(justify mirror)
			)
		)
		(property "Val" "100n"
			(at 155.775 16.825 0)
			(layer "B.Fab")
			(hide yes)
			(effects
				(font
					(size 1 1)
					(thickness 0.15)
				)
				(justify mirror)
			)
		)
		(property "Voltage" "50V"
			(at 155.775 16.825 0)
			(layer "B.Fab")
			(hide yes)
			(effects
				(font
					(size 1 1)
					(thickness 0.15)
				)
				(justify mirror)
			)
		)
		(sheetname "CSI")
		(sheetfile "csi.kicad_sch")
		(attr smd)
		(fp_rect
			(start -0.925 0.47)
			(end 0.925 -0.47)
			(stroke
				(width 0.05)
				(type default)
			)
			(fill none)
			(layer "B.CrtYd")
		)
		(fp_line
			(start 0.504 -0.248)
			(end 0.504 0.25)
			(stroke
				(width 0.15)
				(type solid)
			)
			(layer "B.Fab")
		)
		(fp_line
			(start -0.494 -0.248)
			(end 0.504 -0.248)
			(stroke
				(width 0.15)
				(type solid)
			)
			(layer "B.Fab")
		)
		(fp_line
			(start 0.504 0.25)
			(end -0.494 0.25)
			(stroke
				(width 0.15)
				(type solid)
			)
			(layer "B.Fab")
		)
		(fp_line
			(start -0.494 0.25)
			(end -0.494 -0.248)
			(stroke
				(width 0.15)
				(type solid)
			)
			(layer "B.Fab")
		)
		(fp_text user "${REFERENCE}"
			(at -0.932 -3.168 -90)
			(layer "B.Fab")
			(hide yes)
			(effects
				(font
					(size 0.7 0.7)
					(thickness 0.15)
				)
				(justify left bottom mirror)
			)
		)
		(fp_text user "License: Apache-2.0"
			(at -0.932 -5.17 -90)
			(layer "B.Fab")
			(hide yes)
			(effects
				(font
					(size 0.7 0.7)
					(thickness 0.15)
				)
				(justify left bottom mirror)
			)
		)
		(fp_text user "Author: Antmicro"
			(at -0.932 -4.17 -90)
			(layer "B.Fab")
			(hide yes)
			(effects
				(font
					(size 0.7 0.7)
					(thickness 0.15)
				)
				(justify left bottom mirror)
			)
		)
		(pad "1" smd roundrect
			(at -0.48 0 90)
			(size 0.59 0.64)
			(layers "B.Cu" "B.Paste" "B.Mask")
			(roundrect_rratio 0.25)
			(net 1 "GND")
			(pintype "passive")
		)
		(pad "2" smd roundrect
			(at 0.48 0 90)
			(size 0.59 0.64)
			(layers "B.Cu" "B.Paste" "B.Mask")
			(roundrect_rratio 0.25)
			(net 87 "+3V3")
			(pintype "passive")
		)
	)
	(footprint "antmicro-footprints:TP_SMD_0.75mm"
		(layer "B.Cu")
		(at 68 95.9)
		(property "Reference" "TP19"
			(at 5.53 0.21 -90)
			(layer "B.SilkS")
			(hide yes)
			(effects
				(font
					(size 0.7 0.7)
					(thickness 0.15)
				)
				(justify left bottom mirror)
			)
		)
		(property "Value" "TP_0.75mm_SMD"
			(at 0 -1.2 180)
			(layer "B.Fab")
			(effects
				(font
					(size 0.7 0.7)
					(thickness 0.15)
				)
				(justify left bottom mirror)
			)
		)
		(property "Footprint" "antmicro-footprints:TP_SMD_0.75mm"
			(at 0 0 0)
			(layer "F.Fab")
			(hide yes)
			(effects
				(font
					(size 1.27 1.27)
					(thickness 0.15)
				)
			)
		)
		(property "Author" "Antmicro"
			(at 0 0 0)
			(layer "B.Fab")
			(hide yes)
			(effects
				(font
					(size 1 1)
					(thickness 0.15)
				)
				(justify mirror)
			)
		)
		(property "License" "Apache-2.0"
			(at 0 0 0)
			(layer "B.Fab")
			(hide yes)
			(effects
				(font
					(size 1 1)
					(thickness 0.15)
				)
				(justify mirror)
			)
		)
		(property "MPN" ""
			(at 0 0 0)
			(layer "B.Fab")
			(hide yes)
			(effects
				(font
					(size 1 1)
					(thickness 0.15)
				)
				(justify mirror)
			)
		)
		(property "Manufacturer" ""
			(at 0 0 0)
			(layer "B.Fab")
			(hide yes)
			(effects
				(font
					(size 1 1)
					(thickness 0.15)
				)
				(justify mirror)
			)
		)
		(sheetname "USB Debug, DP")
		(sheetfile "usb.kicad_sch")
		(attr exclude_from_pos_files exclude_from_bom)
		(fp_circle
			(center 0 0)
			(end 0.475 0)
			(stroke
				(width 0.05)
				(type default)
			)
			(fill none)
			(layer "B.CrtYd")
		)
		(fp_text user "${REFERENCE}"
			(at -0.4 -2.7 180)
			(layer "B.Fab")
			(hide yes)
			(effects
				(font
					(size 0.7 0.7)
					(thickness 0.15)
				)
				(justify left bottom mirror)
			)
		)
		(fp_text user "License: Apache-2.0"
			(at -0.4 -5.101 180)
			(layer "B.Fab")
			(hide yes)
			(effects
				(font
					(size 0.7 0.7)
					(thickness 0.15)
				)
				(justify left bottom mirror)
			)
		)
		(fp_text user "Author: Antmicro"
			(at -0.4 -3.901 180)
			(layer "B.Fab")
			(hide yes)
			(effects
				(font
					(size 0.7 0.7)
					(thickness 0.15)
				)
				(justify left bottom mirror)
			)
		)
		(pad "1" smd circle
			(at 0 0)
			(size 0.75 0.75)
			(layers "B.Cu" "B.Mask")
			(net 395 "/USB Debug, DP/PDC_I2C2_SCL")
			(pinfunction "1")
			(pintype "passive")
		)
	)
	(footprint "antmicro-footprints:R_Array_4x0201_Panasonic_EXB18V"
		(layer "B.Cu")
		(at 107.89 98.24 90)
		(property "Reference" "R48"
			(at -1.06 1.51 -90)
			(layer "B.SilkS")
			(effects
				(font
					(size 0.7 0.7)
					(thickness 0.15)
				)
				(justify right bottom mirror)
			)
		)
		(property "Value" "R_4x2k2_0201_array"
			(at -1.1 -1.8 -90)
			(layer "B.Fab")
			(effects
				(font
					(size 0.7 0.7)
					(thickness 0.15)
				)
				(justify left bottom mirror)
			)
		)
		(property "Footprint" "antmicro-footprints:R_Array_4x0201_Panasonic_EXB18V"
			(at 0 0 90)
			(layer "F.Fab")
			(hide yes)
			(effects
				(font
					(size 1.27 1.27)
					(thickness 0.15)
				)
			)
		)
		(property "Datasheet" "http://industrial.panasonic.com/cdbs/www-data/pdf/AOC0000/AOC0000C14.pdf"
			(at 0 0 90)
			(layer "F.Fab")
			(hide yes)
			(effects
				(font
					(size 1.27 1.27)
					(thickness 0.15)
				)
			)
		)
		(property "Author" "Antmicro"
			(at 206.13 -9.65 0)
			(layer "B.Fab")
			(hide yes)
			(effects
				(font
					(size 1 1)
					(thickness 0.15)
				)
				(justify mirror)
			)
		)
		(property "License" "Apache-2.0"
			(at 206.13 -9.65 0)
			(layer "B.Fab")
			(hide yes)
			(effects
				(font
					(size 1 1)
					(thickness 0.15)
				)
				(justify mirror)
			)
		)
		(property "MPN" "EXB-18V222JX"
			(at 206.13 -9.65 0)
			(layer "B.Fab")
			(hide yes)
			(effects
				(font
					(size 1 1)
					(thickness 0.15)
				)
				(justify mirror)
			)
		)
		(property "Manufacturer" "Panasonic"
			(at 206.13 -9.65 0)
			(layer "B.Fab")
			(hide yes)
			(effects
				(font
					(size 1 1)
					(thickness 0.15)
				)
				(justify mirror)
			)
		)
		(property "Val" "4x2k2_0201"
			(at 206.13 -9.65 0)
			(layer "B.Fab")
			(hide yes)
			(effects
				(font
					(size 1 1)
					(thickness 0.15)
				)
				(justify mirror)
			)
		)
		(sheetname "CSI")
		(sheetfile "csi.kicad_sch")
		(attr smd)
		(fp_line
			(start 0.8 -0.45)
			(end 0.8 0.45)
			(stroke
				(width 0.12)
				(type solid)
			)
			(layer "B.SilkS")
		)
		(fp_line
			(start -0.8 -0.45)
			(end -0.8 0.45)
			(stroke
				(width 0.12)
				(type solid)
			)
			(layer "B.SilkS")
		)
		(fp_rect
			(start -0.898 0.66)
			(end 0.898 -0.65)
			(stroke
				(width 0.05)
				(type solid)
			)
			(fill none)
			(layer "B.CrtYd")
		)
		(fp_text user "${REFERENCE}"
			(at -1.051 -3.2 -90)
			(layer "B.Fab")
			(hide yes)
			(effects
				(font
					(size 0.7 0.7)
					(thickness 0.15)
				)
				(justify left bottom mirror)
			)
		)
		(fp_text user "Author: Antmicro"
			(at -1.051 -4.599 -90)
			(layer "B.Fab")
			(hide yes)
			(effects
				(font
					(size 0.7 0.7)
					(thickness 0.15)
				)
				(justify left bottom mirror)
			)
		)
		(fp_text user "License: Apache-2.0"
			(at -1.051 -6 -90)
			(layer "B.Fab")
			(hide yes)
			(effects
				(font
					(size 0.7 0.7)
					(thickness 0.15)
				)
				(justify left bottom mirror)
			)
		)
		(pad "1" smd roundrect
			(at -0.6 -0.298 90)
			(size 0.2 0.4)
			(layers "B.Cu" "B.Paste" "B.Mask")
			(roundrect_rratio 0.25)
			(net 337 "/CSI/SCL_CAM3")
			(pinfunction "R1.1")
			(pintype "passive")
		)
		(pad "2" smd roundrect
			(at -0.202 -0.298 90)
			(size 0.2 0.4)
			(layers "B.Cu" "B.Paste" "B.Mask")
			(roundrect_rratio 0.25)
			(net 336 "/CSI/SDA_CAM3")
			(pinfunction "R2.1")
			(pintype "passive")
		)
		(pad "3" smd roundrect
			(at 0.2 -0.298 90)
			(size 0.2 0.4)
			(layers "B.Cu" "B.Paste" "B.Mask")
			(roundrect_rratio 0.25)
			(net 333 "/CSI/SCL_CAM2")
			(pinfunction "R3.1")
			(pintype "passive")
		)
		(pad "4" smd roundrect
			(at 0.598 -0.298 90)
			(size 0.2 0.4)
			(layers "B.Cu" "B.Paste" "B.Mask")
			(roundrect_rratio 0.25)
			(net 331 "/CSI/SDA_CAM2")
			(pinfunction "R4.1")
			(pintype "passive")
		)
		(pad "5" smd roundrect
			(at 0.598 0.3 90)
			(size 0.2 0.4)
			(layers "B.Cu" "B.Paste" "B.Mask")
			(roundrect_rratio 0.25)
			(net 636 "/CSI/CSIB_I2C_VCC")
			(pinfunction "R4.2")
			(pintype "passive")
		)
		(pad "6" smd roundrect
			(at 0.2 0.3 90)
			(size 0.2 0.4)
			(layers "B.Cu" "B.Paste" "B.Mask")
			(roundrect_rratio 0.25)
			(net 636 "/CSI/CSIB_I2C_VCC")
			(pinfunction "R3.2")
			(pintype "passive")
		)
		(pad "7" smd roundrect
			(at -0.202 0.3 90)
			(size 0.2 0.4)
			(layers "B.Cu" "B.Paste" "B.Mask")
			(roundrect_rratio 0.25)
			(net 636 "/CSI/CSIB_I2C_VCC")
			(pinfunction "R2.2")
			(pintype "passive")
		)
		(pad "8" smd roundrect
			(at -0.6 0.3 90)
			(size 0.2 0.4)
			(layers "B.Cu" "B.Paste" "B.Mask")
			(roundrect_rratio 0.25)
			(net 636 "/CSI/CSIB_I2C_VCC")
			(pinfunction "R1.2")
			(pintype "passive")
		)
	)
	(footprint "antmicro-footprints:R_0402_1005Metric"
		(layer "B.Cu")
		(at 79.5 107.4)
		(descr "Resistor SMD 0402")
		(tags "resistor SMD 0402")
		(property "Reference" "R89"
			(at 3.3 2.34 180)
			(layer "B.SilkS")
			(effects
				(font
					(size 0.7 0.7)
					(thickness 0.15)
				)
				(justify left bottom mirror)
			)
		)
		(property "Value" "R_1k_0402"
			(at 0 -1.4 180)
			(layer "B.Fab")
			(effects
				(font
					(size 0.7 0.7)
					(thickness 0.15)
				)
				(justify left bottom mirror)
			)
		)
		(property "Footprint" "antmicro-footprints:R_0402_1005Metric"
			(at 0 0 0)
			(layer "F.Fab")
			(hide yes)
			(effects
				(font
					(size 1.27 1.27)
					(thickness 0.15)
				)
			)
		)
		(property "Datasheet" "https://www.bourns.com/docs/product-datasheets/cr.pdf"
			(at 0 0 0)
			(layer "F.Fab")
			(hide yes)
			(effects
				(font
					(size 1.27 1.27)
					(thickness 0.15)
				)
			)
		)
		(property "Author" "Antmicro"
			(at 0 0 0)
			(layer "B.Fab")
			(hide yes)
			(effects
				(font
					(size 1 1)
					(thickness 0.15)
				)
				(justify mirror)
			)
		)
		(property "License" "Apache-2.0"
			(at 0 0 0)
			(layer "B.Fab")
			(hide yes)
			(effects
				(font
					(size 1 1)
					(thickness 0.15)
				)
				(justify mirror)
			)
		)
		(property "MPN" "CR0402-FX-1001GLF"
			(at 0 0 0)
			(layer "B.Fab")
			(hide yes)
			(effects
				(font
					(size 1 1)
					(thickness 0.15)
				)
				(justify mirror)
			)
		)
		(property "Manufacturer" "Bourns"
			(at 0 0 0)
			(layer "B.Fab")
			(hide yes)
			(effects
				(font
					(size 1 1)
					(thickness 0.15)
				)
				(justify mirror)
			)
		)
		(property "Tolerance" "1%"
			(at 0 0 0)
			(layer "B.Fab")
			(hide yes)
			(effects
				(font
					(size 1 1)
					(thickness 0.15)
				)
				(justify mirror)
			)
		)
		(property "Val" "1k"
			(at 0 0 0)
			(layer "B.Fab")
			(hide yes)
			(effects
				(font
					(size 1 1)
					(thickness 0.15)
				)
				(justify mirror)
			)
		)
		(sheetname "USB Debug, DP")
		(sheetfile "usb.kicad_sch")
		(attr smd exclude_from_pos_files exclude_from_bom dnp)
		(fp_rect
			(start -0.925 0.47)
			(end 0.925 -0.47)
			(stroke
				(width 0.05)
				(type default)
			)
			(fill none)
			(layer "B.CrtYd")
		)
		(fp_rect
			(start -0.5 0.25)
			(end 0.5 -0.25)
			(stroke
				(width 0.15)
				(type solid)
			)
			(fill none)
			(layer "B.Fab")
		)
		(fp_text user "${REFERENCE}"
			(at -0.95 -3.168 180)
			(layer "B.Fab")
			(hide yes)
			(effects
				(font
					(size 0.7 0.7)
					(thickness 0.15)
				)
				(justify left bottom mirror)
			)
		)
		(fp_text user "License: Apache-2.0"
			(at -0.95 -5.169 180)
			(layer "B.Fab")
			(hide yes)
			(effects
				(font
					(size 0.7 0.7)
					(thickness 0.15)
				)
				(justify left bottom mirror)
			)
		)
		(fp_text user "Author: Antmicro"
			(at -0.95 -4.169 180)
			(layer "B.Fab")
			(hide yes)
			(effects
				(font
					(size 0.7 0.7)
					(thickness 0.15)
				)
				(justify left bottom mirror)
			)
		)
		(pad "1" smd roundrect
			(at -0.48 0)
			(size 0.59 0.64)
			(layers "B.Cu" "B.Paste" "B.Mask")
			(roundrect_rratio 0.25)
			(net 306 "/USB Debug, DP/USBC0_SSEQ1")
			(pintype "passive")
		)
		(pad "2" smd roundrect
			(at 0.48 0)
			(size 0.59 0.64)
			(layers "B.Cu" "B.Paste" "B.Mask")
			(roundrect_rratio 0.25)
			(net 87 "+3V3")
			(pintype "passive")
		)
	)
	(footprint "antmicro-footprints:R_0402_1005Metric"
		(layer "B.Cu")
		(at 92.35 115.2 -90)
		(descr "Resistor SMD 0402")
		(tags "resistor SMD 0402")
		(property "Reference" "R83"
			(at -1.12 -1.33 90)
			(layer "B.SilkS")
			(effects
				(font
					(size 0.7 0.7)
					(thickness 0.15)
				)
				(justify left bottom mirror)
			)
		)
		(property "Value" "R_10k_0402"
			(at 0 -1.4 90)
			(layer "B.Fab")
			(effects
				(font
					(size 0.7 0.7)
					(thickness 0.15)
				)
				(justify left bottom mirror)
			)
		)
		(property "Footprint" "antmicro-footprints:R_0402_1005Metric"
			(at 0 0 -90)
			(layer "F.Fab")
			(hide yes)
			(effects
				(font
					(size 1.27 1.27)
					(thickness 0.15)
				)
			)
		)
		(property "Datasheet" "https://www.bourns.com/docs/product-datasheets/cr.pdf"
			(at 0 0 -90)
			(layer "F.Fab")
			(hide yes)
			(effects
				(font
					(size 1.27 1.27)
					(thickness 0.15)
				)
			)
		)
		(property "Author" "Antmicro"
			(at -22.85 207.55 0)
			(layer "B.Fab")
			(hide yes)
			(effects
				(font
					(size 1 1)
					(thickness 0.15)
				)
				(justify mirror)
			)
		)
		(property "License" "Apache-2.0"
			(at -22.85 207.55 0)
			(layer "B.Fab")
			(hide yes)
			(effects
				(font
					(size 1 1)
					(thickness 0.15)
				)
				(justify mirror)
			)
		)
		(property "MPN" "CR0402-FX-1002GLF"
			(at -22.85 207.55 0)
			(layer "B.Fab")
			(hide yes)
			(effects
				(font
					(size 1 1)
					(thickness 0.15)
				)
				(justify mirror)
			)
		)
		(property "Manufacturer" "Bourns"
			(at -22.85 207.55 0)
			(layer "B.Fab")
			(hide yes)
			(effects
				(font
					(size 1 1)
					(thickness 0.15)
				)
				(justify mirror)
			)
		)
		(property "Tolerance" "1%"
			(at -22.85 207.55 0)
			(layer "B.Fab")
			(hide yes)
			(effects
				(font
					(size 1 1)
					(thickness 0.15)
				)
				(justify mirror)
			)
		)
		(property "Val" "10k"
			(at -22.85 207.55 0)
			(layer "B.Fab")
			(hide yes)
			(effects
				(font
					(size 1 1)
					(thickness 0.15)
				)
				(justify mirror)
			)
		)
		(sheetname "USB Debug, DP")
		(sheetfile "usb.kicad_sch")
		(attr smd)
		(fp_rect
			(start -0.925 0.47)
			(end 0.925 -0.47)
			(stroke
				(width 0.05)
				(type default)
			)
			(fill none)
			(layer "B.CrtYd")
		)
		(fp_rect
			(start -0.5 0.25)
			(end 0.5 -0.25)
			(stroke
				(width 0.15)
				(type solid)
			)
			(fill none)
			(layer "B.Fab")
		)
		(fp_text user "License: Apache-2.0"
			(at -0.95 -5.169 90)
			(layer "B.Fab")
			(hide yes)
			(effects
				(font
					(size 0.7 0.7)
					(thickness 0.15)
				)
				(justify left bottom mirror)
			)
		)
		(fp_text user "Author: Antmicro"
			(at -0.95 -4.169 90)
			(layer "B.Fab")
			(hide yes)
			(effects
				(font
					(size 0.7 0.7)
					(thickness 0.15)
				)
				(justify left bottom mirror)
			)
		)
		(fp_text user "${REFERENCE}"
			(at -0.95 -3.168 90)
			(layer "B.Fab")
			(hide yes)
			(effects
				(font
					(size 0.7 0.7)
					(thickness 0.15)
				)
				(justify left bottom mirror)
			)
		)
		(pad "1" smd roundrect
			(at -0.48 0 270)
			(size 0.59 0.64)
			(layers "B.Cu" "B.Paste" "B.Mask")
			(roundrect_rratio 0.25)
			(net 505 "USBC0_FLG")
			(pintype "passive")
		)
		(pad "2" smd roundrect
			(at 0.48 0 270)
			(size 0.59 0.64)
			(layers "B.Cu" "B.Paste" "B.Mask")
			(roundrect_rratio 0.25)
			(net 87 "+3V3")
			(pintype "passive")
		)
	)
	(footprint "antmicro-footprints:R_0402_1005Metric"
		(layer "B.Cu")
		(at 75 105.3 -90)
		(descr "Resistor SMD 0402")
		(tags "resistor SMD 0402")
		(property "Reference" "R92"
			(at -5.03 -1.69 90)
			(layer "B.SilkS")
			(effects
				(font
					(size 0.7 0.7)
					(thickness 0.15)
				)
				(justify left bottom mirror)
			)
		)
		(property "Value" "R_1k_0402"
			(at 0 -1.4 90)
			(layer "B.Fab")
			(effects
				(font
					(size 0.7 0.7)
					(thickness 0.15)
				)
				(justify left bottom mirror)
			)
		)
		(property "Footprint" "antmicro-footprints:R_0402_1005Metric"
			(at 0 0 -90)
			(layer "F.Fab")
			(hide yes)
			(effects
				(font
					(size 1.27 1.27)
					(thickness 0.15)
				)
			)
		)
		(property "Datasheet" "https://www.bourns.com/docs/product-datasheets/cr.pdf"
			(at 0 0 -90)
			(layer "F.Fab")
			(hide yes)
			(effects
				(font
					(size 1.27 1.27)
					(thickness 0.15)
				)
			)
		)
		(property "Author" "Antmicro"
			(at -30.3 180.3 0)
			(layer "B.Fab")
			(hide yes)
			(effects
				(font
					(size 1 1)
					(thickness 0.15)
				)
				(justify mirror)
			)
		)
		(property "License" "Apache-2.0"
			(at -30.3 180.3 0)
			(layer "B.Fab")
			(hide yes)
			(effects
				(font
					(size 1 1)
					(thickness 0.15)
				)
				(justify mirror)
			)
		)
		(property "MPN" "CR0402-FX-1001GLF"
			(at -30.3 180.3 0)
			(layer "B.Fab")
			(hide yes)
			(effects
				(font
					(size 1 1)
					(thickness 0.15)
				)
				(justify mirror)
			)
		)
		(property "Manufacturer" "Bourns"
			(at -30.3 180.3 0)
			(layer "B.Fab")
			(hide yes)
			(effects
				(font
					(size 1 1)
					(thickness 0.15)
				)
				(justify mirror)
			)
		)
		(property "Tolerance" "1%"
			(at -30.3 180.3 0)
			(layer "B.Fab")
			(hide yes)
			(effects
				(font
					(size 1 1)
					(thickness 0.15)
				)
				(justify mirror)
			)
		)
		(property "Val" "1k"
			(at -30.3 180.3 0)
			(layer "B.Fab")
			(hide yes)
			(effects
				(font
					(size 1 1)
					(thickness 0.15)
				)
				(justify mirror)
			)
		)
		(sheetname "USB Debug, DP")
		(sheetfile "usb.kicad_sch")
		(attr smd exclude_from_pos_files exclude_from_bom dnp)
		(fp_rect
			(start -0.925 0.47)
			(end 0.925 -0.47)
			(stroke
				(width 0.05)
				(type default)
			)
			(fill none)
			(layer "B.CrtYd")
		)
		(fp_rect
			(start -0.5 0.25)
			(end 0.5 -0.25)
			(stroke
				(width 0.15)
				(type solid)
			)
			(fill none)
			(layer "B.Fab")
		)
		(fp_text user "Author: Antmicro"
			(at -0.95 -4.169 90)
			(layer "B.Fab")
			(hide yes)
			(effects
				(font
					(size 0.7 0.7)
					(thickness 0.15)
				)
				(justify left bottom mirror)
			)
		)
		(fp_text user "License: Apache-2.0"
			(at -0.95 -5.169 90)
			(layer "B.Fab")
			(hide yes)
			(effects
				(font
					(size 0.7 0.7)
					(thickness 0.15)
				)
				(justify left bottom mirror)
			)
		)
		(fp_text user "${REFERENCE}"
			(at -0.95 -3.168 90)
			(layer "B.Fab")
			(hide yes)
			(effects
				(font
					(size 0.7 0.7)
					(thickness 0.15)
				)
				(justify left bottom mirror)
			)
		)
		(pad "1" smd roundrect
			(at -0.48 0 270)
			(size 0.59 0.64)
			(layers "B.Cu" "B.Paste" "B.Mask")
			(roundrect_rratio 0.25)
			(net 307 "/USB Debug, DP/USBC0_DPEQ0")
			(pintype "passive")
		)
		(pad "2" smd roundrect
			(at 0.48 0 270)
			(size 0.59 0.64)
			(layers "B.Cu" "B.Paste" "B.Mask")
			(roundrect_rratio 0.25)
			(net 1 "GND")
			(pintype "passive")
		)
	)
	(footprint "antmicro-footprints:Conn_FFC_WE_68715014x22"
		(locked yes)
		(layer "B.Cu")
		(at 88.74 71.44)
		(property "Reference" "J8"
			(at -0.16 3.92 180)
			(layer "B.SilkS")
			(effects
				(font
					(size 0.7 0.7)
					(thickness 0.15)
				)
				(justify left bottom mirror)
			)
		)
		(property "Value" "Conn_FFC_WE_68715014522"
			(at 0 -4.499 180)
			(layer "B.Fab")
			(effects
				(font
					(size 0.7 0.7)
					(thickness 0.15)
				)
				(justify left bottom mirror)
			)
		)
		(property "Footprint" "antmicro-footprints:Conn_FFC_WE_68715014x22"
			(at 0 0 0)
			(layer "F.Fab")
			(hide yes)
			(effects
				(font
					(size 1.27 1.27)
					(thickness 0.15)
				)
			)
		)
		(property "Datasheet" "https://www.we-online.com/components/products/datasheet/68715014522.pdf"
			(at 0 0 0)
			(layer "F.Fab")
			(hide yes)
			(effects
				(font
					(size 1.27 1.27)
					(thickness 0.15)
				)
			)
		)
		(property "Author" "Antmicro"
			(at 0 0 0)
			(layer "B.Fab")
			(hide yes)
			(effects
				(font
					(size 1 1)
					(thickness 0.15)
				)
				(justify mirror)
			)
		)
		(property "License" "Apache-2.0"
			(at 0 0 0)
			(layer "B.Fab")
			(hide yes)
			(effects
				(font
					(size 1 1)
					(thickness 0.15)
				)
				(justify mirror)
			)
		)
		(property "MPN" "68715014522"
			(at 0 0 0)
			(layer "B.Fab")
			(hide yes)
			(effects
				(font
					(size 1 1)
					(thickness 0.15)
				)
				(justify mirror)
			)
		)
		(property "Manufacturer" "Würth Elektronik"
			(at 0 0 0)
			(layer "B.Fab")
			(hide yes)
			(effects
				(font
					(size 1 1)
					(thickness 0.15)
				)
				(justify mirror)
			)
		)
		(sheetname "CSI")
		(sheetfile "csi.kicad_sch")
		(attr smd)
		(fp_line
			(start -15.85 -2.7)
			(end 15.85 -2.7)
			(stroke
				(width 0.15)
				(type solid)
			)
			(layer "B.SilkS")
		)
		(fp_line
			(start -15.85 2.15)
			(end -15.85 -2.7)
			(stroke
				(width 0.15)
				(type solid)
			)
			(layer "B.SilkS")
		)
		(fp_line
			(start -12.5 2.15)
			(end -15.85 2.15)
			(stroke
				(width 0.15)
				(type solid)
			)
			(layer "B.SilkS")
		)
		(fp_line
			(start -12.5 2.976)
			(end -12.5 2.15)
			(stroke
				(width 0.15)
				(type solid)
			)
			(layer "B.SilkS")
		)
		(fp_line
			(start 12.499 2.15)
			(end 15.85 2.15)
			(stroke
				(width 0.15)
				(type solid)
			)
			(layer "B.SilkS")
		)
		(fp_line
			(start 12.499 2.976)
			(end -12.5 2.976)
			(stroke
				(width 0.15)
				(type solid)
			)
			(layer "B.SilkS")
		)
		(fp_line
			(start 12.499 2.976)
			(end 12.499 2.15)
			(stroke
				(width 0.15)
				(type solid)
			)
			(layer "B.SilkS")
		)
		(fp_line
			(start 15.85 2.15)
			(end 15.85 -2.7)
			(stroke
				(width 0.15)
				(type solid)
			)
			(layer "B.SilkS")
		)
		(fp_circle
			(center -12.9 2.9)
			(end -12.85 2.85)
			(stroke
				(width 0.15)
				(type solid)
			)
			(fill solid)
			(layer "B.SilkS")
		)
		(fp_rect
			(start -16.2 3.25)
			(end 16.2 -3.55)
			(stroke
				(width 0.05)
				(type solid)
			)
			(fill none)
			(layer "B.CrtYd")
		)
		(fp_text user "${REFERENCE}"
			(at -16.2 -8.9 180)
			(layer "B.Fab")
			(hide yes)
			(effects
				(font
					(size 0.7 0.7)
					(thickness 0.15)
				)
				(justify left bottom mirror)
			)
		)
		(fp_text user "License: Apache-2.0"
			(at -16.2 -7.7 180)
			(layer "B.Fab")
			(hide yes)
			(effects
				(font
					(size 0.7 0.7)
					(thickness 0.15)
				)
				(justify left bottom mirror)
			)
		)
		(fp_text user "Author: Antmicro"
			(at -16.2 -6.499 180)
			(layer "B.Fab")
			(hide yes)
			(effects
				(font
					(size 0.7 0.7)
					(thickness 0.15)
				)
				(justify left bottom mirror)
			)
		)
		(pad "1" smd roundrect
			(at -12.25 2.15)
			(size 0.3 1.2)
			(layers "B.Cu" "B.Paste" "B.Mask")
			(roundrect_rratio 0.25)
			(net 381 "unconnected-(J8-Pad1)")
			(pintype "passive+no_connect")
		)
		(pad "2" smd roundrect
			(at -11.75 2.15)
			(size 0.3 1.2)
			(layers "B.Cu" "B.Paste" "B.Mask")
			(roundrect_rratio 0.25)
			(net 382 "unconnected-(J8-Pad2)")
			(pintype "passive+no_connect")
		)
		(pad "3" smd roundrect
			(at -11.25 2.15)
			(size 0.3 1.2)
			(layers "B.Cu" "B.Paste" "B.Mask")
			(roundrect_rratio 0.25)
			(net 383 "unconnected-(J8-Pad3)")
			(pintype "passive+no_connect")
		)
		(pad "4" smd roundrect
			(at -10.75 2.15)
			(size 0.3 1.2)
			(layers "B.Cu" "B.Paste" "B.Mask")
			(roundrect_rratio 0.25)
			(net 384 "unconnected-(J8-Pad4)")
			(pintype "passive+no_connect")
		)
		(pad "5" smd roundrect
			(at -10.25 2.15)
			(size 0.3 1.2)
			(layers "B.Cu" "B.Paste" "B.Mask")
			(roundrect_rratio 0.25)
			(net 236 "/CSI/CSI1_1_D1_N")
			(pintype "passive")
		)
		(pad "6" smd roundrect
			(at -9.75 2.15)
			(size 0.3 1.2)
			(layers "B.Cu" "B.Paste" "B.Mask")
			(roundrect_rratio 0.25)
			(net 237 "/CSI/CSI1_1_D1_P")
			(pintype "passive")
		)
		(pad "7" smd roundrect
			(at -9.25 2.15)
			(size 0.3 1.2)
			(layers "B.Cu" "B.Paste" "B.Mask")
			(roundrect_rratio 0.25)
			(net 234 "/CSI/CSI1_1_D0_N")
			(pintype "passive")
		)
		(pad "8" smd roundrect
			(at -8.75 2.15)
			(size 0.3 1.2)
			(layers "B.Cu" "B.Paste" "B.Mask")
			(roundrect_rratio 0.25)
			(net 235 "/CSI/CSI1_1_D0_P")
			(pintype "passive")
		)
		(pad "9" smd roundrect
			(at -8.25 2.15)
			(size 0.3 1.2)
			(layers "B.Cu" "B.Paste" "B.Mask")
			(roundrect_rratio 0.25)
			(net 1 "GND")
			(pintype "passive")
		)
		(pad "10" smd roundrect
			(at -7.75 2.15)
			(size 0.3 1.2)
			(layers "B.Cu" "B.Paste" "B.Mask")
			(roundrect_rratio 0.25)
			(net 6 "CSI1_CLK_N")
			(pintype "passive")
		)
		(pad "11" smd roundrect
			(at -7.25 2.15)
			(size 0.3 1.2)
			(layers "B.Cu" "B.Paste" "B.Mask")
			(roundrect_rratio 0.25)
			(net 8 "CSI1_CLK_P")
			(pintype "passive")
		)
		(pad "12" smd roundrect
			(at -6.75 2.15)
			(size 0.3 1.2)
			(layers "B.Cu" "B.Paste" "B.Mask")
			(roundrect_rratio 0.25)
			(net 1 "GND")
			(pintype "passive")
		)
		(pad "13" smd roundrect
			(at -6.25 2.15)
			(size 0.3 1.2)
			(layers "B.Cu" "B.Paste" "B.Mask")
			(roundrect_rratio 0.25)
			(net 385 "unconnected-(J8-Pad13)")
			(pintype "passive+no_connect")
		)
		(pad "14" smd roundrect
			(at -5.75 2.15)
			(size 0.3 1.2)
			(layers "B.Cu" "B.Paste" "B.Mask")
			(roundrect_rratio 0.25)
			(net 386 "unconnected-(J8-Pad14)")
			(pintype "passive+no_connect")
		)
		(pad "15" smd roundrect
			(at -5.25 2.15)
			(size 0.3 1.2)
			(layers "B.Cu" "B.Paste" "B.Mask")
			(roundrect_rratio 0.25)
			(net 1 "GND")
			(pintype "passive")
		)
		(pad "16" smd roundrect
			(at -4.75 2.15)
			(size 0.3 1.2)
			(layers "B.Cu" "B.Paste" "B.Mask")
			(roundrect_rratio 0.25)
			(net 387 "unconnected-(J8-Pad16)")
			(pintype "passive+no_connect")
		)
		(pad "17" smd roundrect
			(at -4.25 2.15)
			(size 0.3 1.2)
			(layers "B.Cu" "B.Paste" "B.Mask")
			(roundrect_rratio 0.25)
			(net 388 "unconnected-(J8-Pad17)")
			(pintype "passive+no_connect")
		)
		(pad "18" smd roundrect
			(at -3.75 2.15)
			(size 0.3 1.2)
			(layers "B.Cu" "B.Paste" "B.Mask")
			(roundrect_rratio 0.25)
			(net 1 "GND")
			(pintype "passive")
		)
		(pad "19" smd roundrect
			(at -3.25 2.15)
			(size 0.3 1.2)
			(layers "B.Cu" "B.Paste" "B.Mask")
			(roundrect_rratio 0.25)
			(net 389 "unconnected-(J8-Pad19)")
			(pintype "passive+no_connect")
		)
		(pad "20" smd roundrect
			(at -2.75 2.15)
			(size 0.3 1.2)
			(layers "B.Cu" "B.Paste" "B.Mask")
			(roundrect_rratio 0.25)
			(net 392 "unconnected-(J8-Pad20)")
			(pintype "passive+no_connect")
		)
		(pad "21" smd roundrect
			(at -2.25 2.15)
			(size 0.3 1.2)
			(layers "B.Cu" "B.Paste" "B.Mask")
			(roundrect_rratio 0.25)
			(net 399 "unconnected-(J8-Pad21)")
			(pintype "passive+no_connect")
		)
		(pad "22" smd roundrect
			(at -1.75 2.15)
			(size 0.3 1.2)
			(layers "B.Cu" "B.Paste" "B.Mask")
			(roundrect_rratio 0.25)
			(net 400 "unconnected-(J8-Pad22)")
			(pintype "passive+no_connect")
		)
		(pad "23" smd roundrect
			(at -1.25 2.15)
			(size 0.3 1.2)
			(layers "B.Cu" "B.Paste" "B.Mask")
			(roundrect_rratio 0.25)
			(net 238 "/CSI/CSI3_1_D1_N")
			(pintype "passive")
		)
		(pad "24" smd roundrect
			(at -0.75 2.15)
			(size 0.3 1.2)
			(layers "B.Cu" "B.Paste" "B.Mask")
			(roundrect_rratio 0.25)
			(net 239 "/CSI/CSI3_1_D1_P")
			(pintype "passive")
		)
		(pad "25" smd roundrect
			(at -0.25 2.15)
			(size 0.3 1.2)
			(layers "B.Cu" "B.Paste" "B.Mask")
			(roundrect_rratio 0.25)
			(net 240 "/CSI/CSI3_1_D0_N")
			(pintype "passive")
		)
		(pad "26" smd roundrect
			(at 0.248 2.15)
			(size 0.3 1.2)
			(layers "B.Cu" "B.Paste" "B.Mask")
			(roundrect_rratio 0.25)
			(net 241 "/CSI/CSI3_1_D0_P")
			(pintype "passive")
		)
		(pad "27" smd roundrect
			(at 0.748 2.15)
			(size 0.3 1.2)
			(layers "B.Cu" "B.Paste" "B.Mask")
			(roundrect_rratio 0.25)
			(net 1 "GND")
			(pintype "passive")
		)
		(pad "28" smd roundrect
			(at 1.249 2.15)
			(size 0.3 1.2)
			(layers "B.Cu" "B.Paste" "B.Mask")
			(roundrect_rratio 0.25)
			(net 18 "CSI3_CLK_N")
			(pintype "passive")
		)
		(pad "29" smd roundrect
			(at 1.749 2.15)
			(size 0.3 1.2)
			(layers "B.Cu" "B.Paste" "B.Mask")
			(roundrect_rratio 0.25)
			(net 20 "CSI3_CLK_P")
			(pintype "passive")
		)
		(pad "30" smd roundrect
			(at 2.249 2.15)
			(size 0.3 1.2)
			(layers "B.Cu" "B.Paste" "B.Mask")
			(roundrect_rratio 0.25)
			(net 1 "GND")
			(pintype "passive")
		)
		(pad "31" smd roundrect
			(at 2.749 2.15)
			(size 0.3 1.2)
			(layers "B.Cu" "B.Paste" "B.Mask")
			(roundrect_rratio 0.25)
			(net 401 "unconnected-(J8-Pad31)")
			(pintype "passive+no_connect")
		)
		(pad "32" smd roundrect
			(at 3.249 2.15)
			(size 0.3 1.2)
			(layers "B.Cu" "B.Paste" "B.Mask")
			(roundrect_rratio 0.25)
			(net 406 "/CSI/VSYNC_CAM2_3V3")
			(pintype "passive")
		)
		(pad "33" smd roundrect
			(at 3.749 2.15)
			(size 0.3 1.2)
			(layers "B.Cu" "B.Paste" "B.Mask")
			(roundrect_rratio 0.25)
			(net 405 "unconnected-(J8-Pad33)")
			(pintype "passive+no_connect")
		)
		(pad "34" smd roundrect
			(at 4.248 2.15)
			(size 0.3 1.2)
			(layers "B.Cu" "B.Paste" "B.Mask")
			(roundrect_rratio 0.25)
			(net 402 "/CSI/VSYNC_CAM3_3V3")
			(pintype "passive")
		)
		(pad "35" smd roundrect
			(at 4.748 2.15)
			(size 0.3 1.2)
			(layers "B.Cu" "B.Paste" "B.Mask")
			(roundrect_rratio 0.25)
			(net 407 "unconnected-(J8-Pad35)")
			(pintype "passive+no_connect")
		)
		(pad "36" smd roundrect
			(at 5.248 2.15)
			(size 0.3 1.2)
			(layers "B.Cu" "B.Paste" "B.Mask")
			(roundrect_rratio 0.25)
			(net 408 "unconnected-(J8-Pad36)")
			(pintype "passive+no_connect")
		)
		(pad "37" smd roundrect
			(at 5.749 2.15)
			(size 0.3 1.2)
			(layers "B.Cu" "B.Paste" "B.Mask")
			(roundrect_rratio 0.25)
			(net 409 "unconnected-(J8-Pad37)")
			(pintype "passive+no_connect")
		)
		(pad "38" smd roundrect
			(at 6.249 2.15)
			(size 0.3 1.2)
			(layers "B.Cu" "B.Paste" "B.Mask")
			(roundrect_rratio 0.25)
			(net 410 "unconnected-(J8-Pad38)")
			(pintype "passive+no_connect")
		)
		(pad "39" smd roundrect
			(at 6.749 2.15)
			(size 0.3 1.2)
			(layers "B.Cu" "B.Paste" "B.Mask")
			(roundrect_rratio 0.25)
			(net 575 "Net-(R51-R1.2)")
			(pintype "passive")
		)
		(pad "40" smd roundrect
			(at 7.249 2.15)
			(size 0.3 1.2)
			(layers "B.Cu" "B.Paste" "B.Mask")
			(roundrect_rratio 0.25)
			(net 577 "Net-(R51-R2.2)")
			(pintype "passive")
		)
		(pad "41" smd roundrect
			(at 7.749 2.15)
			(size 0.3 1.2)
			(layers "B.Cu" "B.Paste" "B.Mask")
			(roundrect_rratio 0.25)
			(net 602 "Net-(R51-R3.2)")
			(pintype "passive")
		)
		(pad "42" smd roundrect
			(at 8.249 2.15)
			(size 0.3 1.2)
			(layers "B.Cu" "B.Paste" "B.Mask")
			(roundrect_rratio 0.25)
			(net 603 "Net-(R51-R4.2)")
			(pintype "passive")
		)
		(pad "43" smd roundrect
			(at 8.749 2.15)
			(size 0.3 1.2)
			(layers "B.Cu" "B.Paste" "B.Mask")
			(roundrect_rratio 0.25)
			(net 421 "unconnected-(J8-Pad43)")
			(pintype "passive+no_connect")
		)
		(pad "44" smd roundrect
			(at 9.249 2.15)
			(size 0.3 1.2)
			(layers "B.Cu" "B.Paste" "B.Mask")
			(roundrect_rratio 0.25)
			(net 423 "unconnected-(J8-Pad44)")
			(pintype "passive+no_connect")
		)
		(pad "45" smd roundrect
			(at 9.749 2.15)
			(size 0.3 1.2)
			(layers "B.Cu" "B.Paste" "B.Mask")
			(roundrect_rratio 0.25)
			(net 425 "unconnected-(J8-Pad45)")
			(pintype "passive+no_connect")
		)
		(pad "46" smd roundrect
			(at 10.249 2.15)
			(size 0.3 1.2)
			(layers "B.Cu" "B.Paste" "B.Mask")
			(roundrect_rratio 0.25)
			(net 426 "unconnected-(J8-Pad46)")
			(pintype "passive+no_connect")
		)
		(pad "47" smd roundrect
			(at 10.749 2.15)
			(size 0.3 1.2)
			(layers "B.Cu" "B.Paste" "B.Mask")
			(roundrect_rratio 0.25)
			(net 110 "/CSI/CSIB_3V3")
			(pintype "passive")
		)
		(pad "48" smd roundrect
			(at 11.249 2.15)
			(size 0.3 1.2)
			(layers "B.Cu" "B.Paste" "B.Mask")
			(roundrect_rratio 0.25)
			(net 110 "/CSI/CSIB_3V3")
			(pintype "passive")
		)
		(pad "49" smd roundrect
			(at 11.749 2.15)
			(size 0.3 1.2)
			(layers "B.Cu" "B.Paste" "B.Mask")
			(roundrect_rratio 0.25)
			(net 111 "/CSI/CSIB_5V")
			(pintype "passive")
		)
		(pad "50" smd roundrect
			(at 12.249 2.15)
			(size 0.3 1.2)
			(layers "B.Cu" "B.Paste" "B.Mask")
			(roundrect_rratio 0.25)
			(net 111 "/CSI/CSIB_5V")
			(pintype "passive")
		)
		(pad "MP1" smd roundrect
			(at -14.198 0.3)
			(size 2.7 3)
			(layers "B.Cu" "B.Paste" "B.Mask")
			(roundrect_rratio 0.05)
			(net 1 "GND")
			(pinfunction "MP")
			(pintype "passive")
		)
		(pad "MP2" smd roundrect
			(at 14.198 0.3)
			(size 2.7 3)
			(layers "B.Cu" "B.Paste" "B.Mask")
			(roundrect_rratio 0.05)
			(net 1 "GND")
			(pinfunction "MP")
			(pintype "passive")
		)
	)
	(footprint "antmicro-footprints:R_0603_1608Metric"
		(layer "B.Cu")
		(at 71.6 111.4 180)
		(descr "Resistor SMD 0603")
		(tags "resistor SMD 0603")
		(property "Reference" "R253"
			(at -0.67 -1.425 0)
			(layer "B.SilkS")
			(effects
				(font
					(size 0.7 0.7)
					(thickness 0.15)
				)
				(justify left bottom mirror)
			)
		)
		(property "Value" "R_0R_22.4A_0603"
			(at 0 -1.6 0)
			(layer "B.Fab")
			(effects
				(font
					(size 0.7 0.7)
					(thickness 0.15)
				)
				(justify left bottom mirror)
			)
		)
		(property "Footprint" "antmicro-footprints:R_0603_1608Metric"
			(at 0 0 180)
			(layer "F.Fab")
			(hide yes)
			(effects
				(font
					(size 1.27 1.27)
					(thickness 0.15)
				)
			)
		)
		(property "Datasheet" "https://fscdn.rohm.com/en/products/databook/datasheet/passive/resistor/chip_resistor/pmr-jpw-e.pdf"
			(at 0 0 180)
			(layer "F.Fab")
			(hide yes)
			(effects
				(font
					(size 1.27 1.27)
					(thickness 0.15)
				)
			)
		)
		(property "Author" "Antmicro"
			(at 143.2 222.8 0)
			(layer "B.Fab")
			(hide yes)
			(effects
				(font
					(size 1 1)
					(thickness 0.15)
				)
				(justify mirror)
			)
		)
		(property "License" "Apache-2.0"
			(at 143.2 222.8 0)
			(layer "B.Fab")
			(hide yes)
			(effects
				(font
					(size 1 1)
					(thickness 0.15)
				)
				(justify mirror)
			)
		)
		(property "MPN" "PMR03EZPJ000"
			(at 143.2 222.8 0)
			(layer "B.Fab")
			(hide yes)
			(effects
				(font
					(size 1 1)
					(thickness 0.15)
				)
				(justify mirror)
			)
		)
		(property "Manufacturer" "ROHM Semiconductor"
			(at 143.2 222.8 0)
			(layer "B.Fab")
			(hide yes)
			(effects
				(font
					(size 1 1)
					(thickness 0.15)
				)
				(justify mirror)
			)
		)
		(property "Max. Curr." "22.4A"
			(at 143.2 222.8 0)
			(layer "B.Fab")
			(hide yes)
			(effects
				(font
					(size 1 1)
					(thickness 0.15)
				)
				(justify mirror)
			)
		)
		(property "Tolerance" "template_tolerance"
			(at 143.2 222.8 0)
			(layer "B.Fab")
			(hide yes)
			(effects
				(font
					(size 1 1)
					(thickness 0.15)
				)
				(justify mirror)
			)
		)
		(property "Val" "0R"
			(at 143.2 222.8 0)
			(layer "B.Fab")
			(hide yes)
			(effects
				(font
					(size 1 1)
					(thickness 0.15)
				)
				(justify mirror)
			)
		)
		(sheetname "Supply")
		(sheetfile "supply.kicad_sch")
		(attr smd)
		(fp_line
			(start 0.15 0.4)
			(end -0.15 0.4)
			(stroke
				(width 0.15)
				(type solid)
			)
			(layer "B.SilkS")
		)
		(fp_line
			(start 0.15 -0.4)
			(end -0.15 -0.4)
			(stroke
				(width 0.15)
				(type solid)
			)
			(layer "B.SilkS")
		)
		(fp_rect
			(start -1.25 0.65)
			(end 1.25 -0.65)
			(stroke
				(width 0.05)
				(type solid)
			)
			(fill none)
			(layer "B.CrtYd")
		)
		(fp_rect
			(start -0.8 0.4)
			(end 0.8 -0.4)
			(stroke
				(width 0.15)
				(type solid)
			)
			(fill none)
			(layer "B.Fab")
		)
		(fp_text user "License: Apache-2.0"
			(at -1.25 -5.9 0)
			(layer "B.Fab")
			(hide yes)
			(effects
				(font
					(size 0.7 0.7)
					(thickness 0.15)
				)
				(justify left bottom mirror)
			)
		)
		(fp_text user "${REFERENCE}"
			(at -1.25 -3.898 0)
			(layer "B.Fab")
			(hide yes)
			(effects
				(font
					(size 0.7 0.7)
					(thickness 0.15)
				)
				(justify left bottom mirror)
			)
		)
		(fp_text user "Author: Antmicro"
			(at -1.25 -4.9 0)
			(layer "B.Fab")
			(hide yes)
			(effects
				(font
					(size 0.7 0.7)
					(thickness 0.15)
				)
				(justify left bottom mirror)
			)
		)
		(pad "1" smd roundrect
			(at -0.7 0 180)
			(size 0.8 1)
			(layers "B.Cu" "B.Paste" "B.Mask")
			(roundrect_rratio 0.2)
			(net 481 "USBPD2_HV")
			(pintype "passive")
		)
		(pad "2" smd roundrect
			(at 0.7 0 180)
			(size 0.8 1)
			(layers "B.Cu" "B.Paste" "B.Mask")
			(roundrect_rratio 0.2)
			(net 328 "/Supply/VCC_IN")
			(pintype "passive")
		)
	)
	(footprint "antmicro-footprints:R_0402_1005Metric"
		(layer "B.Cu")
		(at 46.54 74.475 180)
		(descr "Resistor SMD 0402")
		(tags "resistor SMD 0402")
		(property "Reference" "R255"
			(at -1.36 -2.225 0)
			(layer "B.SilkS")
			(effects
				(font
					(size 0.7 0.7)
					(thickness 0.15)
				)
				(justify left bottom mirror)
			)
		)
		(property "Value" "R_10k_0402"
			(at 0 -1.4 0)
			(layer "B.Fab")
			(effects
				(font
					(size 0.7 0.7)
					(thickness 0.15)
				)
				(justify left bottom mirror)
			)
		)
		(property "Footprint" "antmicro-footprints:R_0402_1005Metric"
			(at 0 0 180)
			(layer "F.Fab")
			(hide yes)
			(effects
				(font
					(size 1.27 1.27)
					(thickness 0.15)
				)
			)
		)
		(property "Datasheet" "https://www.bourns.com/docs/product-datasheets/cr.pdf"
			(at 0 0 180)
			(layer "F.Fab")
			(hide yes)
			(effects
				(font
					(size 1.27 1.27)
					(thickness 0.15)
				)
			)
		)
		(property "Author" "Antmicro"
			(at 93.8 148.8 0)
			(layer "B.Fab")
			(hide yes)
			(effects
				(font
					(size 1 1)
					(thickness 0.15)
				)
				(justify mirror)
			)
		)
		(property "License" "Apache-2.0"
			(at 93.8 148.8 0)
			(layer "B.Fab")
			(hide yes)
			(effects
				(font
					(size 1 1)
					(thickness 0.15)
				)
				(justify mirror)
			)
		)
		(property "MPN" "CR0402-FX-1002GLF"
			(at 93.8 148.8 0)
			(layer "B.Fab")
			(hide yes)
			(effects
				(font
					(size 1 1)
					(thickness 0.15)
				)
				(justify mirror)
			)
		)
		(property "Manufacturer" "Bourns"
			(at 93.8 148.8 0)
			(layer "B.Fab")
			(hide yes)
			(effects
				(font
					(size 1 1)
					(thickness 0.15)
				)
				(justify mirror)
			)
		)
		(property "Tolerance" "1%"
			(at 93.8 148.8 0)
			(layer "B.Fab")
			(hide yes)
			(effects
				(font
					(size 1 1)
					(thickness 0.15)
				)
				(justify mirror)
			)
		)
		(property "Val" "10k"
			(at 93.8 148.8 0)
			(layer "B.Fab")
			(hide yes)
			(effects
				(font
					(size 1 1)
					(thickness 0.15)
				)
				(justify mirror)
			)
		)
		(sheetname "Supply")
		(sheetfile "supply.kicad_sch")
		(attr smd)
		(fp_rect
			(start -0.925 0.47)
			(end 0.925 -0.47)
			(stroke
				(width 0.05)
				(type default)
			)
			(fill none)
			(layer "B.CrtYd")
		)
		(fp_rect
			(start -0.5 0.25)
			(end 0.5 -0.25)
			(stroke
				(width 0.15)
				(type solid)
			)
			(fill none)
			(layer "B.Fab")
		)
		(fp_text user "Author: Antmicro"
			(at -0.95 -4.169 0)
			(layer "B.Fab")
			(hide yes)
			(effects
				(font
					(size 0.7 0.7)
					(thickness 0.15)
				)
				(justify left bottom mirror)
			)
		)
		(fp_text user "License: Apache-2.0"
			(at -0.95 -5.169 0)
			(layer "B.Fab")
			(hide yes)
			(effects
				(font
					(size 0.7 0.7)
					(thickness 0.15)
				)
				(justify left bottom mirror)
			)
		)
		(fp_text user "${REFERENCE}"
			(at -0.95 -3.168 0)
			(layer "B.Fab")
			(hide yes)
			(effects
				(font
					(size 0.7 0.7)
					(thickness 0.15)
				)
				(justify left bottom mirror)
			)
		)
		(pad "1" smd roundrect
			(at -0.48 0 180)
			(size 0.59 0.64)
			(layers "B.Cu" "B.Paste" "B.Mask")
			(roundrect_rratio 0.25)
			(net 1 "GND")
			(pintype "passive")
		)
		(pad "2" smd roundrect
			(at 0.48 0 180)
			(size 0.59 0.64)
			(layers "B.Cu" "B.Paste" "B.Mask")
			(roundrect_rratio 0.25)
			(net 631 "Net-(Q16-G)")
			(pintype "passive")
		)
	)
	(footprint "antmicro-footprints:R_0402_1005Metric"
		(layer "B.Cu")
		(at 90 112.6 90)
		(descr "Resistor SMD 0402")
		(tags "resistor SMD 0402")
		(property "Reference" "R1"
			(at 0.965 -3.57 -90)
			(layer "B.SilkS")
			(effects
				(font
					(size 0.7 0.7)
					(thickness 0.15)
				)
				(justify left bottom mirror)
			)
		)
		(property "Value" "R_0R_0402"
			(at 0 -1.4 -90)
			(layer "B.Fab")
			(effects
				(font
					(size 0.7 0.7)
					(thickness 0.15)
				)
				(justify left bottom mirror)
			)
		)
		(property "Footprint" "antmicro-footprints:R_0402_1005Metric"
			(at 0 0 90)
			(layer "F.Fab")
			(hide yes)
			(effects
				(font
					(size 1.27 1.27)
					(thickness 0.15)
				)
			)
		)
		(property "Datasheet" "https://industrial.panasonic.com/cdbs/www-data/pdf/RDA0000/AOA0000C301.pdf"
			(at 0 0 90)
			(layer "F.Fab")
			(hide yes)
			(effects
				(font
					(size 1.27 1.27)
					(thickness 0.15)
				)
			)
		)
		(property "Author" "Antmicro"
			(at 202.6 22.6 0)
			(layer "B.Fab")
			(hide yes)
			(effects
				(font
					(size 1 1)
					(thickness 0.15)
				)
				(justify mirror)
			)
		)
		(property "Current" "1A"
			(at 202.6 22.6 0)
			(layer "B.Fab")
			(hide yes)
			(effects
				(font
					(size 1 1)
					(thickness 0.15)
				)
				(justify mirror)
			)
		)
		(property "License" "Apache-2.0"
			(at 202.6 22.6 0)
			(layer "B.Fab")
			(hide yes)
			(effects
				(font
					(size 1 1)
					(thickness 0.15)
				)
				(justify mirror)
			)
		)
		(property "MPN" "ERJ2GE0R00X"
			(at 202.6 22.6 0)
			(layer "B.Fab")
			(hide yes)
			(effects
				(font
					(size 1 1)
					(thickness 0.15)
				)
				(justify mirror)
			)
		)
		(property "Manufacturer" "Panasonic"
			(at 202.6 22.6 0)
			(layer "B.Fab")
			(hide yes)
			(effects
				(font
					(size 1 1)
					(thickness 0.15)
				)
				(justify mirror)
			)
		)
		(property "Tolerance" ""
			(at 202.6 22.6 0)
			(layer "B.Fab")
			(hide yes)
			(effects
				(font
					(size 1 1)
					(thickness 0.15)
				)
				(justify mirror)
			)
		)
		(property "Val" "0R"
			(at 202.6 22.6 0)
			(layer "B.Fab")
			(hide yes)
			(effects
				(font
					(size 1 1)
					(thickness 0.15)
				)
				(justify mirror)
			)
		)
		(sheetname "SoM")
		(sheetfile "som.kicad_sch")
		(attr smd)
		(fp_rect
			(start -0.925 0.47)
			(end 0.925 -0.47)
			(stroke
				(width 0.05)
				(type default)
			)
			(fill none)
			(layer "B.CrtYd")
		)
		(fp_rect
			(start -0.5 0.25)
			(end 0.5 -0.25)
			(stroke
				(width 0.15)
				(type solid)
			)
			(fill none)
			(layer "B.Fab")
		)
		(fp_text user "${REFERENCE}"
			(at -0.95 -3.168 -90)
			(layer "B.Fab")
			(hide yes)
			(effects
				(font
					(size 0.7 0.7)
					(thickness 0.15)
				)
				(justify left bottom mirror)
			)
		)
		(fp_text user "License: Apache-2.0"
			(at -0.95 -5.169 -90)
			(layer "B.Fab")
			(hide yes)
			(effects
				(font
					(size 0.7 0.7)
					(thickness 0.15)
				)
				(justify left bottom mirror)
			)
		)
		(fp_text user "Author: Antmicro"
			(at -0.95 -4.169 -90)
			(layer "B.Fab")
			(hide yes)
			(effects
				(font
					(size 0.7 0.7)
					(thickness 0.15)
				)
				(justify left bottom mirror)
			)
		)
		(pad "1" smd roundrect
			(at -0.48 0 90)
			(size 0.59 0.64)
			(layers "B.Cu" "B.Paste" "B.Mask")
			(roundrect_rratio 0.25)
			(net 747 "Net-(J15H-GPIO02)")
			(pintype "passive")
		)
		(pad "2" smd roundrect
			(at 0.48 0 90)
			(size 0.59 0.64)
			(layers "B.Cu" "B.Paste" "B.Mask")
			(roundrect_rratio 0.25)
			(net 281 "~{GPIO_INT}")
			(pintype "passive")
		)
	)
	(footprint "antmicro-footprints:C_0402_1005Metric"
		(layer "B.Cu")
		(at 55.25 82.75 90)
		(descr "Capacitor SMD 0402")
		(tags "capacitor SMD 0402")
		(property "Reference" "C160"
			(at -1.95 1.45 90)
			(layer "B.SilkS")
			(effects
				(font
					(size 0.7 0.7)
					(thickness 0.15)
				)
				(justify right top mirror)
			)
		)
		(property "Value" "C_1n_0402"
			(at -1.022927 -2.155213 90)
			(layer "B.Fab")
			(effects
				(font
					(size 0.7 0.7)
					(thickness 0.15)
				)
				(justify right top mirror)
			)
		)
		(property "Footprint" "antmicro-footprints:C_0402_1005Metric"
			(at 0 0 90)
			(layer "B.Fab")
			(hide yes)
			(effects
				(font
					(size 1.27 1.27)
					(thickness 0.15)
				)
				(justify mirror)
			)
		)
		(property "Datasheet" "https://www.murata.com/products/productdetail?partno=GRM1555C1H102JA01%23"
			(at 0 0 90)
			(layer "B.Fab")
			(hide yes)
			(effects
				(font
					(size 1.27 1.27)
					(thickness 0.15)
				)
				(justify mirror)
			)
		)
		(property "Description" "SMD Multilayer Ceramic Capacitor, 1000 pF, 50 V, 0402 [1005 Metric], ± 5%, C0G / NP0, GRM Series"
			(at 0 0 90)
			(layer "B.Fab")
			(hide yes)
			(effects
				(font
					(size 1.27 1.27)
					(thickness 0.15)
				)
				(justify mirror)
			)
		)
		(property "MPN" "GRM1555C1H102JA01D"
			(at 0 0 -90)
			(unlocked yes)
			(layer "B.Fab")
			(hide yes)
			(effects
				(font
					(size 1 1)
					(thickness 0.15)
				)
				(justify mirror)
			)
		)
		(property "Manufacturer" "Murata"
			(at 0 0 -90)
			(unlocked yes)
			(layer "B.Fab")
			(hide yes)
			(effects
				(font
					(size 1 1)
					(thickness 0.15)
				)
				(justify mirror)
			)
		)
		(property "License" "Apache-2.0"
			(at 0 0 -90)
			(unlocked yes)
			(layer "B.Fab")
			(hide yes)
			(effects
				(font
					(size 1 1)
					(thickness 0.15)
				)
				(justify mirror)
			)
		)
		(property "Author" "Antmicro"
			(at 0 0 -90)
			(unlocked yes)
			(layer "B.Fab")
			(hide yes)
			(effects
				(font
					(size 1 1)
					(thickness 0.15)
				)
				(justify mirror)
			)
		)
		(property "Val" "1n"
			(at 0 0 -90)
			(unlocked yes)
			(layer "B.Fab")
			(hide yes)
			(effects
				(font
					(size 1 1)
					(thickness 0.15)
				)
				(justify mirror)
			)
		)
		(property "Voltage" "50V"
			(at 0 0 -90)
			(unlocked yes)
			(layer "B.Fab")
			(hide yes)
			(effects
				(font
					(size 1 1)
					(thickness 0.15)
				)
				(justify mirror)
			)
		)
		(property "Dielectric" "C0G"
			(at 0 0 -90)
			(unlocked yes)
			(layer "B.Fab")
			(hide yes)
			(effects
				(font
					(size 1 1)
					(thickness 0.15)
				)
				(justify mirror)
			)
		)
		(sheetname "Supply")
		(sheetfile "supply.kicad_sch")
		(attr smd)
		(fp_rect
			(start -0.925 0.47)
			(end 0.925 -0.47)
			(stroke
				(width 0.05)
				(type default)
			)
			(fill none)
			(layer "B.CrtYd")
		)
		(fp_line
			(start 0.504 -0.248)
			(end 0.504 0.25)
			(stroke
				(width 0.15)
				(type solid)
			)
			(layer "B.Fab")
		)
		(fp_line
			(start -0.494 -0.248)
			(end 0.504 -0.248)
			(stroke
				(width 0.15)
				(type solid)
			)
			(layer "B.Fab")
		)
		(fp_line
			(start 0.504 0.25)
			(end -0.494 0.25)
			(stroke
				(width 0.15)
				(type solid)
			)
			(layer "B.Fab")
		)
		(fp_line
			(start -0.494 0.25)
			(end -0.494 -0.248)
			(stroke
				(width 0.15)
				(type solid)
			)
			(layer "B.Fab")
		)
		(fp_text user "${REFERENCE}"
			(at -0.939 -4.599 90)
			(layer "B.Fab")
			(hide yes)
			(effects
				(font
					(size 0.7 0.7)
					(thickness 0.15)
				)
				(justify right top mirror)
			)
		)
		(fp_text user "Author: Antmicro"
			(at -0.939 -3.399 90)
			(layer "B.Fab")
			(hide yes)
			(effects
				(font
					(size 0.7 0.7)
					(thickness 0.15)
				)
				(justify right top mirror)
			)
		)
		(fp_text user "License: Apache-2.0"
			(at -0.939 -5.799 90)
			(layer "B.Fab")
			(hide yes)
			(effects
				(font
					(size 0.7 0.7)
					(thickness 0.15)
				)
				(justify right top mirror)
			)
		)
		(pad "1" smd roundrect
			(at -0.48 0 90)
			(size 0.59 0.64)
			(layers "B.Cu" "B.Paste" "B.Mask")
			(roundrect_rratio 0.25)
			(net 1 "GND")
			(pintype "passive")
		)
		(pad "2" smd roundrect
			(at 0.48 0 90)
			(size 0.59 0.64)
			(layers "B.Cu" "B.Paste" "B.Mask")
			(roundrect_rratio 0.25)
			(net 644 "Net-(U48-DVDT)")
			(pintype "passive")
		)
	)
	(footprint "antmicro-footprints:R_0402_1005Metric"
		(layer "B.Cu")
		(at 38.608 117.856 90)
		(descr "Resistor SMD 0402")
		(tags "resistor SMD 0402")
		(property "Reference" "R147"
			(at 1.206 -1.458 -90)
			(layer "B.SilkS")
			(effects
				(font
					(size 0.7 0.7)
					(thickness 0.15)
				)
				(justify left bottom mirror)
			)
		)
		(property "Value" "R_200R_0402"
			(at 0 -1.4 -90)
			(layer "B.Fab")
			(effects
				(font
					(size 0.7 0.7)
					(thickness 0.15)
				)
				(justify left bottom mirror)
			)
		)
		(property "Footprint" "antmicro-footprints:R_0402_1005Metric"
			(at 0 0 90)
			(layer "F.Fab")
			(hide yes)
			(effects
				(font
					(size 1.27 1.27)
					(thickness 0.15)
				)
			)
		)
		(property "Datasheet" "https://www.bourns.com/docs/product-datasheets/cr.pdf"
			(at 0 0 90)
			(layer "F.Fab")
			(hide yes)
			(effects
				(font
					(size 1.27 1.27)
					(thickness 0.15)
				)
			)
		)
		(property "Author" "Antmicro"
			(at 156.464 79.248 0)
			(layer "B.Fab")
			(hide yes)
			(effects
				(font
					(size 1 1)
					(thickness 0.15)
				)
				(justify mirror)
			)
		)
		(property "License" "Apache-2.0"
			(at 156.464 79.248 0)
			(layer "B.Fab")
			(hide yes)
			(effects
				(font
					(size 1 1)
					(thickness 0.15)
				)
				(justify mirror)
			)
		)
		(property "MPN" "CR0402-FX-2000GLF"
			(at 156.464 79.248 0)
			(layer "B.Fab")
			(hide yes)
			(effects
				(font
					(size 1 1)
					(thickness 0.15)
				)
				(justify mirror)
			)
		)
		(property "Manufacturer" "Bourns"
			(at 156.464 79.248 0)
			(layer "B.Fab")
			(hide yes)
			(effects
				(font
					(size 1 1)
					(thickness 0.15)
				)
				(justify mirror)
			)
		)
		(property "Tolerance" "1%"
			(at 156.464 79.248 0)
			(layer "B.Fab")
			(hide yes)
			(effects
				(font
					(size 1 1)
					(thickness 0.15)
				)
				(justify mirror)
			)
		)
		(property "Val" "200R"
			(at 156.464 79.248 0)
			(layer "B.Fab")
			(hide yes)
			(effects
				(font
					(size 1 1)
					(thickness 0.15)
				)
				(justify mirror)
			)
		)
		(sheetname "Ethernet")
		(sheetfile "ethernet.kicad_sch")
		(attr smd)
		(fp_rect
			(start -0.925 0.47)
			(end 0.925 -0.47)
			(stroke
				(width 0.05)
				(type default)
			)
			(fill none)
			(layer "B.CrtYd")
		)
		(fp_rect
			(start -0.5 0.25)
			(end 0.5 -0.25)
			(stroke
				(width 0.15)
				(type solid)
			)
			(fill none)
			(layer "B.Fab")
		)
		(fp_text user "${REFERENCE}"
			(at -0.95 -3.168 -90)
			(layer "B.Fab")
			(hide yes)
			(effects
				(font
					(size 0.7 0.7)
					(thickness 0.15)
				)
				(justify left bottom mirror)
			)
		)
		(fp_text user "Author: Antmicro"
			(at -0.95 -4.169 -90)
			(layer "B.Fab")
			(hide yes)
			(effects
				(font
					(size 0.7 0.7)
					(thickness 0.15)
				)
				(justify left bottom mirror)
			)
		)
		(fp_text user "License: Apache-2.0"
			(at -0.95 -5.169 -90)
			(layer "B.Fab")
			(hide yes)
			(effects
				(font
					(size 0.7 0.7)
					(thickness 0.15)
				)
				(justify left bottom mirror)
			)
		)
		(pad "1" smd roundrect
			(at -0.48 0 90)
			(size 0.59 0.64)
			(layers "B.Cu" "B.Paste" "B.Mask")
			(roundrect_rratio 0.25)
			(net 1 "GND")
			(pintype "passive")
		)
		(pad "2" smd roundrect
			(at 0.48 0 90)
			(size 0.59 0.64)
			(layers "B.Cu" "B.Paste" "B.Mask")
			(roundrect_rratio 0.25)
			(net 715 "Net-(C78-Pad1)")
			(pintype "passive")
		)
	)
	(footprint "antmicro-footprints:XSON-8_1x1.95mm_P0.5mm"
		(layer "B.Cu")
		(at 139 98.8025 90)
		(property "Reference" "U31"
			(at 0.8625 2.2 -90)
			(layer "B.SilkS")
			(effects
				(font
					(size 0.7 0.7)
					(thickness 0.15)
				)
				(justify left bottom mirror)
			)
		)
		(property "Value" "NTS0102_XSON"
			(at 0 -2.2 -90)
			(layer "B.Fab")
			(effects
				(font
					(size 0.7 0.7)
					(thickness 0.15)
				)
				(justify left bottom mirror)
			)
		)
		(property "Footprint" "antmicro-footprints:XSON-8_1x1.95mm_P0.5mm"
			(at 0 0 90)
			(layer "F.Fab")
			(hide yes)
			(effects
				(font
					(size 1.27 1.27)
					(thickness 0.15)
				)
			)
		)
		(property "Datasheet" "http://www.farnell.com/datasheets/1760723.pdf"
			(at 0 0 90)
			(layer "F.Fab")
			(hide yes)
			(effects
				(font
					(size 1.27 1.27)
					(thickness 0.15)
				)
			)
		)
		(property "Author" "Antmicro"
			(at 237.8025 -40.1975 0)
			(layer "B.Fab")
			(hide yes)
			(effects
				(font
					(size 1 1)
					(thickness 0.15)
				)
				(justify mirror)
			)
		)
		(property "License" "Apache-2.0"
			(at 237.8025 -40.1975 0)
			(layer "B.Fab")
			(hide yes)
			(effects
				(font
					(size 1 1)
					(thickness 0.15)
				)
				(justify mirror)
			)
		)
		(property "MPN" "NTS0102GT"
			(at 237.8025 -40.1975 0)
			(layer "B.Fab")
			(hide yes)
			(effects
				(font
					(size 1 1)
					(thickness 0.15)
				)
				(justify mirror)
			)
		)
		(property "Manufacturer" "NXP"
			(at 237.8025 -40.1975 0)
			(layer "B.Fab")
			(hide yes)
			(effects
				(font
					(size 1 1)
					(thickness 0.15)
				)
				(justify mirror)
			)
		)
		(sheetname "CSI")
		(sheetfile "csi.kicad_sch")
		(attr smd)
		(fp_line
			(start -0.5 -1.1)
			(end 0.5 -1.1)
			(stroke
				(width 0.15)
				(type solid)
			)
			(layer "B.SilkS")
		)
		(fp_line
			(start 0.5 1.1)
			(end -0.5 1.1)
			(stroke
				(width 0.15)
				(type solid)
			)
			(layer "B.SilkS")
		)
		(fp_circle
			(center -0.75 1.1)
			(end -0.701 1.1)
			(stroke
				(width 0.15)
				(type solid)
			)
			(fill none)
			(layer "B.SilkS")
		)
		(fp_rect
			(start -0.8 1.2)
			(end 0.8 -1.2)
			(stroke
				(width 0.05)
				(type solid)
			)
			(fill none)
			(layer "B.CrtYd")
		)
		(fp_line
			(start 0.5305 -1)
			(end 0.5305 1.001)
			(stroke
				(width 0.15)
				(type solid)
			)
			(layer "B.Fab")
		)
		(fp_line
			(start -0.5305 -1)
			(end 0.5305 -1)
			(stroke
				(width 0.15)
				(type solid)
			)
			(layer "B.Fab")
		)
		(fp_line
			(start 0.5305 1.001)
			(end -0.5305 1.001)
			(stroke
				(width 0.15)
				(type solid)
			)
			(layer "B.Fab")
		)
		(fp_line
			(start -0.5305 1.001)
			(end -0.5305 -1)
			(stroke
				(width 0.15)
				(type solid)
			)
			(layer "B.Fab")
		)
		(fp_text user "License: Apache-2.0"
			(at -0.527 -8.306 -90)
			(layer "B.Fab")
			(hide yes)
			(effects
				(font
					(size 0.7 0.7)
					(thickness 0.15)
				)
				(justify left bottom mirror)
			)
		)
		(fp_text user "${REFERENCE}"
			(at -0.527 -5.905 -90)
			(layer "B.Fab")
			(hide yes)
			(effects
				(font
					(size 0.7 0.7)
					(thickness 0.15)
				)
				(justify left bottom mirror)
			)
		)
		(fp_text user "Author: Antmicro"
			(at -0.527 -7.105 -90)
			(layer "B.Fab")
			(hide yes)
			(effects
				(font
					(size 0.7 0.7)
					(thickness 0.15)
				)
				(justify left bottom mirror)
			)
		)
		(pad "1" smd roundrect
			(at -0.45 0.75 270)
			(size 0.6 0.3)
			(layers "B.Cu" "B.Paste" "B.Mask")
			(roundrect_rratio 0.25)
			(net 371 "/CSI/VSYNC_CAM1_3V3")
			(pinfunction "B_{2}")
			(pintype "bidirectional")
		)
		(pad "2" smd roundrect
			(at -0.45 0.25 270)
			(size 0.6 0.25)
			(layers "B.Cu" "B.Paste" "B.Mask")
			(roundrect_rratio 0.25)
			(net 1 "GND")
			(pinfunction "GND")
			(pintype "power_in")
		)
		(pad "3" smd roundrect
			(at -0.45 -0.25 270)
			(size 0.6 0.25)
			(layers "B.Cu" "B.Paste" "B.Mask")
			(roundrect_rratio 0.25)
			(net 112 "+1V8")
			(pinfunction "VCC_{A}")
			(pintype "power_in")
		)
		(pad "4" smd roundrect
			(at -0.45 -0.75 270)
			(size 0.6 0.3)
			(layers "B.Cu" "B.Paste" "B.Mask")
			(roundrect_rratio 0.25)
			(net 219 "VSYNC_CAM1")
			(pinfunction "A_{2}")
			(pintype "bidirectional")
		)
		(pad "5" smd roundrect
			(at 0.45 -0.75 270)
			(size 0.6 0.3)
			(layers "B.Cu" "B.Paste" "B.Mask")
			(roundrect_rratio 0.25)
			(net 217 "VSYNC_CAM0")
			(pinfunction "A_{1}")
			(pintype "bidirectional")
		)
		(pad "6" smd roundrect
			(at 0.45 -0.25 270)
			(size 0.6 0.25)
			(layers "B.Cu" "B.Paste" "B.Mask")
			(roundrect_rratio 0.25)
			(net 112 "+1V8")
			(pinfunction "OE")
			(pintype "input")
		)
		(pad "7" smd roundrect
			(at 0.45 0.25 270)
			(size 0.6 0.25)
			(layers "B.Cu" "B.Paste" "B.Mask")
			(roundrect_rratio 0.25)
			(net 87 "+3V3")
			(pinfunction "VCC_{B}")
			(pintype "power_in")
		)
		(pad "8" smd roundrect
			(at 0.45 0.75 270)
			(size 0.6 0.3)
			(layers "B.Cu" "B.Paste" "B.Mask")
			(roundrect_rratio 0.25)
			(net 360 "/CSI/VSYNC_CAM0_3V3")
			(pinfunction "B_{1}")
			(pintype "bidirectional")
		)
	)
	(footprint "antmicro-footprints:R_0402_1005Metric"
		(layer "B.Cu")
		(at 46.9 87.6375)
		(descr "Resistor SMD 0402")
		(tags "resistor SMD 0402")
		(property "Reference" "R123"
			(at 0.335 -3.4775 180)
			(layer "B.SilkS")
			(effects
				(font
					(size 0.7 0.7)
					(thickness 0.15)
				)
				(justify left bottom mirror)
			)
		)
		(property "Value" "R_1k3_0402"
			(at 0 -1.4 180)
			(layer "B.Fab")
			(effects
				(font
					(size 0.7 0.7)
					(thickness 0.15)
				)
				(justify left bottom mirror)
			)
		)
		(property "Footprint" "antmicro-footprints:R_0402_1005Metric"
			(at 0 0 0)
			(layer "F.Fab")
			(hide yes)
			(effects
				(font
					(size 1.27 1.27)
					(thickness 0.15)
				)
			)
		)
		(property "Datasheet" "https://www.bourns.com/docs/product-datasheets/cr.pdf"
			(at 0 0 0)
			(layer "F.Fab")
			(hide yes)
			(effects
				(font
					(size 1.27 1.27)
					(thickness 0.15)
				)
			)
		)
		(property "Author" "Antmicro"
			(at 0 0 0)
			(layer "B.Fab")
			(hide yes)
			(effects
				(font
					(size 1 1)
					(thickness 0.15)
				)
				(justify mirror)
			)
		)
		(property "License" "Apache-2.0"
			(at 0 0 0)
			(layer "B.Fab")
			(hide yes)
			(effects
				(font
					(size 1 1)
					(thickness 0.15)
				)
				(justify mirror)
			)
		)
		(property "MPN" "CR0402-FX-1301GLF"
			(at 0 0 0)
			(layer "B.Fab")
			(hide yes)
			(effects
				(font
					(size 1 1)
					(thickness 0.15)
				)
				(justify mirror)
			)
		)
		(property "Manufacturer" "Bourns"
			(at 0 0 0)
			(layer "B.Fab")
			(hide yes)
			(effects
				(font
					(size 1 1)
					(thickness 0.15)
				)
				(justify mirror)
			)
		)
		(property "Tolerance" "1%"
			(at 0 0 0)
			(layer "B.Fab")
			(hide yes)
			(effects
				(font
					(size 1 1)
					(thickness 0.15)
				)
				(justify mirror)
			)
		)
		(property "Val" "1k3"
			(at 0 0 0)
			(layer "B.Fab")
			(hide yes)
			(effects
				(font
					(size 1 1)
					(thickness 0.15)
				)
				(justify mirror)
			)
		)
		(sheetname "Ethernet")
		(sheetfile "ethernet.kicad_sch")
		(attr smd)
		(fp_rect
			(start -0.925 0.47)
			(end 0.925 -0.47)
			(stroke
				(width 0.05)
				(type default)
			)
			(fill none)
			(layer "B.CrtYd")
		)
		(fp_rect
			(start -0.5 0.25)
			(end 0.5 -0.25)
			(stroke
				(width 0.15)
				(type solid)
			)
			(fill none)
			(layer "B.Fab")
		)
		(fp_text user "Author: Antmicro"
			(at -0.95 -4.169 180)
			(layer "B.Fab")
			(hide yes)
			(effects
				(font
					(size 0.7 0.7)
					(thickness 0.15)
				)
				(justify left bottom mirror)
			)
		)
		(fp_text user "${REFERENCE}"
			(at -0.95 -3.168 180)
			(layer "B.Fab")
			(hide yes)
			(effects
				(font
					(size 0.7 0.7)
					(thickness 0.15)
				)
				(justify left bottom mirror)
			)
		)
		(fp_text user "License: Apache-2.0"
			(at -0.95 -5.169 180)
			(layer "B.Fab")
			(hide yes)
			(effects
				(font
					(size 0.7 0.7)
					(thickness 0.15)
				)
				(justify left bottom mirror)
			)
		)
		(pad "1" smd roundrect
			(at -0.48 0)
			(size 0.59 0.64)
			(layers "B.Cu" "B.Paste" "B.Mask")
			(roundrect_rratio 0.25)
			(net 499 "/Ethernet/VSS")
			(pintype "passive")
		)
		(pad "2" smd roundrect
			(at 0.48 0)
			(size 0.59 0.64)
			(layers "B.Cu" "B.Paste" "B.Mask")
			(roundrect_rratio 0.25)
			(net 565 "/Ethernet/AMPS_CTL")
			(pintype "passive")
		)
	)
	(footprint "antmicro-footprints:R_0402_1005Metric"
		(layer "B.Cu")
		(at 56.55 107.26)
		(descr "Resistor SMD 0402")
		(tags "resistor SMD 0402")
		(property "Reference" "R156"
			(at 0.97 1.31 180)
			(layer "B.SilkS")
			(effects
				(font
					(size 0.7 0.7)
					(thickness 0.15)
				)
				(justify left bottom mirror)
			)
		)
		(property "Value" "R_1k_0402"
			(at 0 -1.4 180)
			(layer "B.Fab")
			(effects
				(font
					(size 0.7 0.7)
					(thickness 0.15)
				)
				(justify left bottom mirror)
			)
		)
		(property "Footprint" "antmicro-footprints:R_0402_1005Metric"
			(at 0 0 0)
			(layer "F.Fab")
			(hide yes)
			(effects
				(font
					(size 1.27 1.27)
					(thickness 0.15)
				)
			)
		)
		(property "Datasheet" "https://www.bourns.com/docs/product-datasheets/cr.pdf"
			(at 0 0 0)
			(layer "F.Fab")
			(hide yes)
			(effects
				(font
					(size 1.27 1.27)
					(thickness 0.15)
				)
			)
		)
		(property "Author" "Antmicro"
			(at 0 0 0)
			(layer "B.Fab")
			(hide yes)
			(effects
				(font
					(size 1 1)
					(thickness 0.15)
				)
				(justify mirror)
			)
		)
		(property "License" "Apache-2.0"
			(at 0 0 0)
			(layer "B.Fab")
			(hide yes)
			(effects
				(font
					(size 1 1)
					(thickness 0.15)
				)
				(justify mirror)
			)
		)
		(property "MPN" "CR0402-FX-1001GLF"
			(at 0 0 0)
			(layer "B.Fab")
			(hide yes)
			(effects
				(font
					(size 1 1)
					(thickness 0.15)
				)
				(justify mirror)
			)
		)
		(property "Manufacturer" "Bourns"
			(at 0 0 0)
			(layer "B.Fab")
			(hide yes)
			(effects
				(font
					(size 1 1)
					(thickness 0.15)
				)
				(justify mirror)
			)
		)
		(property "Tolerance" "1%"
			(at 0 0 0)
			(layer "B.Fab")
			(hide yes)
			(effects
				(font
					(size 1 1)
					(thickness 0.15)
				)
				(justify mirror)
			)
		)
		(property "Val" "1k"
			(at 0 0 0)
			(layer "B.Fab")
			(hide yes)
			(effects
				(font
					(size 1 1)
					(thickness 0.15)
				)
				(justify mirror)
			)
		)
		(sheetname "Ethernet")
		(sheetfile "ethernet.kicad_sch")
		(attr smd)
		(fp_rect
			(start -0.925 0.47)
			(end 0.925 -0.47)
			(stroke
				(width 0.05)
				(type default)
			)
			(fill none)
			(layer "B.CrtYd")
		)
		(fp_rect
			(start -0.5 0.25)
			(end 0.5 -0.25)
			(stroke
				(width 0.15)
				(type solid)
			)
			(fill none)
			(layer "B.Fab")
		)
		(fp_text user "License: Apache-2.0"
			(at -0.95 -5.169 180)
			(layer "B.Fab")
			(hide yes)
			(effects
				(font
					(size 0.7 0.7)
					(thickness 0.15)
				)
				(justify left bottom mirror)
			)
		)
		(fp_text user "Author: Antmicro"
			(at -0.95 -4.169 180)
			(layer "B.Fab")
			(hide yes)
			(effects
				(font
					(size 0.7 0.7)
					(thickness 0.15)
				)
				(justify left bottom mirror)
			)
		)
		(fp_text user "${REFERENCE}"
			(at -0.95 -3.168 180)
			(layer "B.Fab")
			(hide yes)
			(effects
				(font
					(size 0.7 0.7)
					(thickness 0.15)
				)
				(justify left bottom mirror)
			)
		)
		(pad "1" smd roundrect
			(at -0.48 0)
			(size 0.59 0.64)
			(layers "B.Cu" "B.Paste" "B.Mask")
			(roundrect_rratio 0.25)
			(net 731 "Net-(R156-Pad1)")
			(pintype "passive")
		)
		(pad "2" smd roundrect
			(at 0.48 0)
			(size 0.59 0.64)
			(layers "B.Cu" "B.Paste" "B.Mask")
			(roundrect_rratio 0.25)
			(net 1 "GND")
			(pintype "passive")
		)
	)
	(footprint "antmicro-footprints:R_0402_1005Metric"
		(layer "B.Cu")
		(at 65.3 77.5 180)
		(descr "Resistor SMD 0402")
		(tags "resistor SMD 0402")
		(property "Reference" "R260"
			(at -16.94 -3.47 0)
			(layer "B.SilkS")
			(effects
				(font
					(size 0.7 0.7)
					(thickness 0.15)
				)
				(justify left bottom mirror)
			)
		)
		(property "Value" "R_0R_0402"
			(at 0 -1.4 0)
			(layer "B.Fab")
			(effects
				(font
					(size 0.7 0.7)
					(thickness 0.15)
				)
				(justify left bottom mirror)
			)
		)
		(property "Footprint" "antmicro-footprints:R_0402_1005Metric"
			(at 0 0 180)
			(layer "F.Fab")
			(hide yes)
			(effects
				(font
					(size 1.27 1.27)
					(thickness 0.15)
				)
			)
		)
		(property "Datasheet" "https://industrial.panasonic.com/cdbs/www-data/pdf/RDA0000/AOA0000C301.pdf"
			(at 0 0 180)
			(layer "F.Fab")
			(hide yes)
			(effects
				(font
					(size 1.27 1.27)
					(thickness 0.15)
				)
			)
		)
		(property "Author" "Antmicro"
			(at 130.6 155 0)
			(layer "B.Fab")
			(hide yes)
			(effects
				(font
					(size 1 1)
					(thickness 0.15)
				)
				(justify mirror)
			)
		)
		(property "Current" "1A"
			(at 130.6 155 0)
			(layer "B.Fab")
			(hide yes)
			(effects
				(font
					(size 1 1)
					(thickness 0.15)
				)
				(justify mirror)
			)
		)
		(property "License" "Apache-2.0"
			(at 130.6 155 0)
			(layer "B.Fab")
			(hide yes)
			(effects
				(font
					(size 1 1)
					(thickness 0.15)
				)
				(justify mirror)
			)
		)
		(property "MPN" "ERJ2GE0R00X"
			(at 130.6 155 0)
			(layer "B.Fab")
			(hide yes)
			(effects
				(font
					(size 1 1)
					(thickness 0.15)
				)
				(justify mirror)
			)
		)
		(property "Manufacturer" "Panasonic"
			(at 130.6 155 0)
			(layer "B.Fab")
			(hide yes)
			(effects
				(font
					(size 1 1)
					(thickness 0.15)
				)
				(justify mirror)
			)
		)
		(property "Tolerance" ""
			(at 130.6 155 0)
			(layer "B.Fab")
			(hide yes)
			(effects
				(font
					(size 1 1)
					(thickness 0.15)
				)
				(justify mirror)
			)
		)
		(property "Val" "0R"
			(at 130.6 155 0)
			(layer "B.Fab")
			(hide yes)
			(effects
				(font
					(size 1 1)
					(thickness 0.15)
				)
				(justify mirror)
			)
		)
		(sheetname "Supply")
		(sheetfile "supply.kicad_sch")
		(attr smd)
		(fp_rect
			(start -0.925 0.47)
			(end 0.925 -0.47)
			(stroke
				(width 0.05)
				(type default)
			)
			(fill none)
			(layer "B.CrtYd")
		)
		(fp_rect
			(start -0.5 0.25)
			(end 0.5 -0.25)
			(stroke
				(width 0.15)
				(type solid)
			)
			(fill none)
			(layer "B.Fab")
		)
		(fp_text user "Author: Antmicro"
			(at -0.95 -4.169 0)
			(layer "B.Fab")
			(hide yes)
			(effects
				(font
					(size 0.7 0.7)
					(thickness 0.15)
				)
				(justify left bottom mirror)
			)
		)
		(fp_text user "${REFERENCE}"
			(at -0.95 -3.168 0)
			(layer "B.Fab")
			(hide yes)
			(effects
				(font
					(size 0.7 0.7)
					(thickness 0.15)
				)
				(justify left bottom mirror)
			)
		)
		(fp_text user "License: Apache-2.0"
			(at -0.95 -5.169 0)
			(layer "B.Fab")
			(hide yes)
			(effects
				(font
					(size 0.7 0.7)
					(thickness 0.15)
				)
				(justify left bottom mirror)
			)
		)
		(pad "1" smd roundrect
			(at -0.48 0 180)
			(size 0.59 0.64)
			(layers "B.Cu" "B.Paste" "B.Mask")
			(roundrect_rratio 0.25)
			(net 689 "Net-(U38-Q)")
			(pintype "passive")
		)
		(pad "2" smd roundrect
			(at 0.48 0 180)
			(size 0.59 0.64)
			(layers "B.Cu" "B.Paste" "B.Mask")
			(roundrect_rratio 0.25)
			(net 476 "POWER_EN")
			(pintype "passive")
		)
	)
	(footprint "antmicro-footprints:R_0603_1608Metric"
		(layer "B.Cu")
		(at 43.575 69.8 180)
		(descr "Resistor SMD 0603")
		(tags "resistor SMD 0603")
		(property "Reference" "R157"
			(at -4.065 -0.34 0)
			(layer "B.SilkS")
			(effects
				(font
					(size 0.7 0.7)
					(thickness 0.15)
				)
				(justify left bottom mirror)
			)
		)
		(property "Value" "R_0R_0603"
			(at 0 -1.6 0)
			(layer "B.Fab")
			(effects
				(font
					(size 0.7 0.7)
					(thickness 0.15)
				)
				(justify left bottom mirror)
			)
		)
		(property "Footprint" "antmicro-footprints:R_0603_1608Metric"
			(at 0 0 180)
			(layer "F.Fab")
			(hide yes)
			(effects
				(font
					(size 1.27 1.27)
					(thickness 0.15)
				)
			)
		)
		(property "Datasheet" "https://www.bourns.com/docs/product-datasheets/cr.pdf?sfvrsn=574d41f6_14"
			(at 0 0 180)
			(layer "F.Fab")
			(hide yes)
			(effects
				(font
					(size 1.27 1.27)
					(thickness 0.15)
				)
			)
		)
		(property "Author" "Antmicro"
			(at 87.15 139.6 0)
			(layer "B.Fab")
			(hide yes)
			(effects
				(font
					(size 1 1)
					(thickness 0.15)
				)
				(justify mirror)
			)
		)
		(property "Current" "1A"
			(at 87.15 139.6 0)
			(layer "B.Fab")
			(hide yes)
			(effects
				(font
					(size 1 1)
					(thickness 0.15)
				)
				(justify mirror)
			)
		)
		(property "License" "Apache-2.0"
			(at 87.15 139.6 0)
			(layer "B.Fab")
			(hide yes)
			(effects
				(font
					(size 1 1)
					(thickness 0.15)
				)
				(justify mirror)
			)
		)
		(property "MPN" "CR0603-J/-000ELF"
			(at 87.15 139.6 0)
			(layer "B.Fab")
			(hide yes)
			(effects
				(font
					(size 1 1)
					(thickness 0.15)
				)
				(justify mirror)
			)
		)
		(property "Manufacturer" "Bourns"
			(at 87.15 139.6 0)
			(layer "B.Fab")
			(hide yes)
			(effects
				(font
					(size 1 1)
					(thickness 0.15)
				)
				(justify mirror)
			)
		)
		(property "Tolerance" ""
			(at 87.15 139.6 0)
			(layer "B.Fab")
			(hide yes)
			(effects
				(font
					(size 1 1)
					(thickness 0.15)
				)
				(justify mirror)
			)
		)
		(property "Val" "0R"
			(at 87.15 139.6 0)
			(layer "B.Fab")
			(hide yes)
			(effects
				(font
					(size 1 1)
					(thickness 0.15)
				)
				(justify mirror)
			)
		)
		(sheetname "Ethernet")
		(sheetfile "ethernet.kicad_sch")
		(attr smd exclude_from_pos_files exclude_from_bom dnp)
		(fp_line
			(start 0.15 0.4)
			(end -0.15 0.4)
			(stroke
				(width 0.15)
				(type solid)
			)
			(layer "B.SilkS")
		)
		(fp_line
			(start 0.15 -0.4)
			(end -0.15 -0.4)
			(stroke
				(width 0.15)
				(type solid)
			)
			(layer "B.SilkS")
		)
		(fp_rect
			(start -1.25 0.65)
			(end 1.25 -0.65)
			(stroke
				(width 0.05)
				(type solid)
			)
			(fill none)
			(layer "B.CrtYd")
		)
		(fp_rect
			(start -0.8 0.4)
			(end 0.8 -0.4)
			(stroke
				(width 0.15)
				(type solid)
			)
			(fill none)
			(layer "B.Fab")
		)
		(fp_text user "${REFERENCE}"
			(at -1.25 -3.898 0)
			(layer "B.Fab")
			(hide yes)
			(effects
				(font
					(size 0.7 0.7)
					(thickness 0.15)
				)
				(justify left bottom mirror)
			)
		)
		(fp_text user "Author: Antmicro"
			(at -1.25 -4.9 0)
			(layer "B.Fab")
			(hide yes)
			(effects
				(font
					(size 0.7 0.7)
					(thickness 0.15)
				)
				(justify left bottom mirror)
			)
		)
		(fp_text user "License: Apache-2.0"
			(at -1.25 -5.9 0)
			(layer "B.Fab")
			(hide yes)
			(effects
				(font
					(size 0.7 0.7)
					(thickness 0.15)
				)
				(justify left bottom mirror)
			)
		)
		(pad "1" smd roundrect
			(at -0.7 0 180)
			(size 0.8 1)
			(layers "B.Cu" "B.Paste" "B.Mask")
			(roundrect_rratio 0.2)
			(net 1 "GND")
			(pintype "passive")
		)
		(pad "2" smd roundrect
			(at 0.7 0 180)
			(size 0.8 1)
			(layers "B.Cu" "B.Paste" "B.Mask")
			(roundrect_rratio 0.2)
			(net 683 "Net-(U23-TRIM)")
			(pintype "passive")
		)
	)
	(footprint "antmicro-footprints:MS621FE-FL11E"
		(layer "B.Cu")
		(at 136.098313 72.77 -90)
		(property "Reference" "BT1"
			(at 0 5.25 90)
			(layer "B.SilkS")
			(effects
				(font
					(size 0.7 0.7)
					(thickness 0.15)
				)
				(justify left bottom mirror)
			)
		)
		(property "Value" "Battery_Holder_MS621FE-FL11E"
			(at -0.001 -6.2 90)
			(layer "B.Fab")
			(effects
				(font
					(size 0.7 0.7)
					(thickness 0.15)
				)
				(justify left bottom mirror)
			)
		)
		(property "Footprint" "antmicro-footprints:MS621FE-FL11E"
			(at 0 0 -90)
			(layer "F.Fab")
			(hide yes)
			(effects
				(font
					(size 1.27 1.27)
					(thickness 0.15)
				)
			)
		)
		(property "Datasheet" "https://www.sii.co.jp/en/me/datasheets/ms-rechargeable/ms621fe/"
			(at 0 0 -90)
			(layer "F.Fab")
			(hide yes)
			(effects
				(font
					(size 1.27 1.27)
					(thickness 0.15)
				)
			)
		)
		(property "Author" "Antmicro"
			(at 63.328313 208.868313 0)
			(layer "B.Fab")
			(hide yes)
			(effects
				(font
					(size 1 1)
					(thickness 0.15)
				)
				(justify mirror)
			)
		)
		(property "License" "Apache-2.0"
			(at 63.328313 208.868313 0)
			(layer "B.Fab")
			(hide yes)
			(effects
				(font
					(size 1 1)
					(thickness 0.15)
				)
				(justify mirror)
			)
		)
		(property "MPN" "MS621FE-FL11E"
			(at 63.328313 208.868313 0)
			(layer "B.Fab")
			(hide yes)
			(effects
				(font
					(size 1 1)
					(thickness 0.15)
				)
				(justify mirror)
			)
		)
		(property "Manufacturer" "Seiko Instruments"
			(at 63.328313 208.868313 0)
			(layer "B.Fab")
			(hide yes)
			(effects
				(font
					(size 1 1)
					(thickness 0.15)
				)
				(justify mirror)
			)
		)
		(sheetname "SoM")
		(sheetfile "som.kicad_sch")
		(attr smd)
		(fp_arc
			(start -1.2 2.15)
			(mid 0 -4.834)
			(end 1.2 2.15)
			(stroke
				(width 0.15)
				(type solid)
			)
			(layer "B.SilkS")
		)
		(fp_line
			(start -1.275 5.2)
			(end 1.275 5.2)
			(stroke
				(width 0.05)
				(type solid)
			)
			(layer "B.CrtYd")
		)
		(fp_line
			(start -1.275 2.425)
			(end -1.275 5.2)
			(stroke
				(width 0.05)
				(type solid)
			)
			(layer "B.CrtYd")
		)
		(fp_line
			(start 1.275 2.425)
			(end 1.275 5.2)
			(stroke
				(width 0.05)
				(type solid)
			)
			(layer "B.CrtYd")
		)
		(fp_arc
			(start -1.275 2.425)
			(mid 0 -5.143374)
			(end 1.275 2.425)
			(stroke
				(width 0.05)
				(type solid)
			)
			(layer "B.CrtYd")
		)
		(fp_line
			(start -0.8 5.05)
			(end 1.2 5.05)
			(stroke
				(width 0.15)
				(type solid)
			)
			(layer "B.Fab")
		)
		(fp_line
			(start -1.2 4.65)
			(end -0.8 5.05)
			(stroke
				(width 0.15)
				(type solid)
			)
			(layer "B.Fab")
		)
		(fp_line
			(start -1.2 2.04)
			(end -1.2 4.65)
			(stroke
				(width 0.15)
				(type solid)
			)
			(layer "B.Fab")
		)
		(fp_line
			(start 1.2 2.04)
			(end 1.2 5.05)
			(stroke
				(width 0.15)
				(type solid)
			)
			(layer "B.Fab")
		)
		(fp_circle
			(center -0.001 -1.25)
			(end -0.001 2.25)
			(stroke
				(width 0.15)
				(type solid)
			)
			(fill none)
			(layer "B.Fab")
		)
		(fp_text user "Author: Antmicro"
			(at -3.501 -9.4 90)
			(layer "B.Fab")
			(hide yes)
			(effects
				(font
					(size 0.7 0.7)
					(thickness 0.15)
				)
				(justify left bottom mirror)
			)
		)
		(fp_text user "${REFERENCE}"
			(at -3.501 -11.8 90)
			(layer "B.Fab")
			(hide yes)
			(effects
				(font
					(size 0.7 0.7)
					(thickness 0.15)
				)
				(justify left bottom mirror)
			)
		)
		(fp_text user "COPPER KEEPOUT"
			(at -0.2 3.14 180)
			(unlocked yes)
			(layer "B.Fab")
			(effects
				(font
					(size 0.4 0.4)
					(thickness 0.1)
				)
				(justify left bottom mirror)
			)
		)
		(fp_text user "License: Apache-2.0"
			(at -3.501 -8.2 90)
			(layer "B.Fab")
			(hide yes)
			(effects
				(font
					(size 0.7 0.7)
					(thickness 0.15)
				)
				(justify left bottom mirror)
			)
		)
		(pad "1" smd rect
			(at -0.75 4.05)
			(size 1.8 0.75)
			(layers "B.Cu" "B.Paste" "B.Mask")
			(net 732 "Net-(BT1-+)")
			(pinfunction "+")
			(pintype "passive")
		)
		(pad "2" smd rect
			(at 0.75 4.05)
			(size 1.8 0.75)
			(layers "B.Cu" "B.Paste" "B.Mask")
			(net 1 "GND")
			(pinfunction "-")
			(pintype "passive")
		)
		(zone
			(net 0)
			(net_name "")
			(layers "B.Cu" "B.CrtYd")
			(hatch edge 0.508)
			(connect_pads
				(clearance 0)
			)
			(min_thickness 0.254)
			(filled_areas_thickness no)
			(keepout
				(tracks allowed)
				(vias not_allowed)
				(pads not_allowed)
				(copperpour not_allowed)
				(footprints allowed)
			)
			(fill
				(thermal_gap 0.508)
				(thermal_bridge_width 0.508)
			)
			(polygon
				(pts
					(xy 138.598313 71.61) (xy 132.958313 71.61) (xy 132.958313 73.93) (xy 138.598313 73.93)
				)
			)
		)
	)
	(footprint "antmicro-footprints:TP_SMD_0.75mm"
		(layer "B.Cu")
		(at 108.065 115.435)
		(property "Reference" "TP31"
			(at 0.42 0.385 90)
			(layer "B.SilkS")
			(effects
				(font
					(size 0.7 0.7)
					(thickness 0.15)
				)
				(justify left bottom mirror)
			)
		)
		(property "Value" "TP_0.75mm_SMD"
			(at 0 -1.2 0)
			(layer "B.Fab")
			(effects
				(font
					(size 0.7 0.7)
					(thickness 0.15)
				)
				(justify right bottom mirror)
			)
		)
		(property "Footprint" "antmicro-footprints:TP_SMD_0.75mm"
			(at 0 0 0)
			(layer "F.Fab")
			(hide yes)
			(effects
				(font
					(size 1.27 1.27)
					(thickness 0.15)
				)
			)
		)
		(property "Author" "Antmicro"
			(at 0 0 0)
			(layer "B.Fab")
			(hide yes)
			(effects
				(font
					(size 1 1)
					(thickness 0.15)
				)
				(justify mirror)
			)
		)
		(property "License" "Apache-2.0"
			(at 0 0 0)
			(layer "B.Fab")
			(hide yes)
			(effects
				(font
					(size 1 1)
					(thickness 0.15)
				)
				(justify mirror)
			)
		)
		(property "MPN" ""
			(at 0 0 0)
			(layer "B.Fab")
			(hide yes)
			(effects
				(font
					(size 1 1)
					(thickness 0.15)
				)
				(justify mirror)
			)
		)
		(property "Manufacturer" ""
			(at 0 0 0)
			(layer "B.Fab")
			(hide yes)
			(effects
				(font
					(size 1 1)
					(thickness 0.15)
				)
				(justify mirror)
			)
		)
		(sheetname "USB3")
		(sheetfile "usb3.kicad_sch")
		(attr exclude_from_pos_files exclude_from_bom)
		(fp_circle
			(center 0 0)
			(end 0.475 0)
			(stroke
				(width 0.05)
				(type default)
			)
			(fill none)
			(layer "B.CrtYd")
		)
		(fp_text user "License: Apache-2.0"
			(at -0.4 -5.101 0)
			(layer "B.Fab")
			(hide yes)
			(effects
				(font
					(size 0.7 0.7)
					(thickness 0.15)
				)
				(justify right bottom mirror)
			)
		)
		(fp_text user "Author: Antmicro"
			(at -0.4 -3.901 0)
			(layer "B.Fab")
			(hide yes)
			(effects
				(font
					(size 0.7 0.7)
					(thickness 0.15)
				)
				(justify right bottom mirror)
			)
		)
		(fp_text user "${REFERENCE}"
			(at -0.4 -2.7 0)
			(layer "B.Fab")
			(hide yes)
			(effects
				(font
					(size 0.7 0.7)
					(thickness 0.15)
				)
				(justify right bottom mirror)
			)
		)
		(pad "1" smd circle
			(at 0 0)
			(size 0.75 0.75)
			(layers "B.Cu" "B.Mask")
			(net 284 "/USB3/USBC1_ID")
			(pinfunction "1")
			(pintype "passive")
		)
	)
	(footprint "antmicro-footprints:C_0402_1005Metric"
		(layer "B.Cu")
		(at 71.8 101.9)
		(descr "Capacitor SMD 0402")
		(tags "capacitor SMD 0402")
		(property "Reference" "C59"
			(at 0.77 -1.5 180)
			(layer "B.SilkS")
			(effects
				(font
					(size 0.7 0.7)
					(thickness 0.15)
				)
				(justify left bottom mirror)
			)
		)
		(property "Value" "C_10u_0402"
			(at -1.022927 -2.155213 180)
			(layer "B.Fab")
			(effects
				(font
					(size 0.7 0.7)
					(thickness 0.15)
				)
				(justify left bottom mirror)
			)
		)
		(property "Footprint" "antmicro-footprints:C_0402_1005Metric"
			(at 0 0 0)
			(layer "F.Fab")
			(hide yes)
			(effects
				(font
					(size 1.27 1.27)
					(thickness 0.15)
				)
			)
		)
		(property "Datasheet" "https://www.yageo.com/en/Chart/Download/pdf/CC0402MRX5R5BB106"
			(at 0 0 0)
			(layer "F.Fab")
			(hide yes)
			(effects
				(font
					(size 1.27 1.27)
					(thickness 0.15)
				)
			)
		)
		(property "Author" "Antmicro"
			(at 0 0 0)
			(layer "B.Fab")
			(hide yes)
			(effects
				(font
					(size 1 1)
					(thickness 0.15)
				)
				(justify mirror)
			)
		)
		(property "Dielectric" ""
			(at 0 0 0)
			(layer "B.Fab")
			(hide yes)
			(effects
				(font
					(size 1 1)
					(thickness 0.15)
				)
				(justify mirror)
			)
		)
		(property "License" "Apache-2.0"
			(at 0 0 0)
			(layer "B.Fab")
			(hide yes)
			(effects
				(font
					(size 1 1)
					(thickness 0.15)
				)
				(justify mirror)
			)
		)
		(property "MPN" "CC0402MRX5R5BB106"
			(at 0 0 0)
			(layer "B.Fab")
			(hide yes)
			(effects
				(font
					(size 1 1)
					(thickness 0.15)
				)
				(justify mirror)
			)
		)
		(property "Manufacturer" "YAGEO"
			(at 0 0 0)
			(layer "B.Fab")
			(hide yes)
			(effects
				(font
					(size 1 1)
					(thickness 0.15)
				)
				(justify mirror)
			)
		)
		(property "Val" "10u"
			(at 0 0 0)
			(layer "B.Fab")
			(hide yes)
			(effects
				(font
					(size 1 1)
					(thickness 0.15)
				)
				(justify mirror)
			)
		)
		(property "Voltage" ""
			(at 0 0 0)
			(layer "B.Fab")
			(hide yes)
			(effects
				(font
					(size 1 1)
					(thickness 0.15)
				)
				(justify mirror)
			)
		)
		(sheetname "USB Debug, DP")
		(sheetfile "usb.kicad_sch")
		(attr smd)
		(fp_rect
			(start -0.925 0.47)
			(end 0.925 -0.47)
			(stroke
				(width 0.05)
				(type default)
			)
			(fill none)
			(layer "B.CrtYd")
		)
		(fp_line
			(start -0.494 -0.248)
			(end 0.504 -0.248)
			(stroke
				(width 0.15)
				(type solid)
			)
			(layer "B.Fab")
		)
		(fp_line
			(start -0.494 0.25)
			(end -0.494 -0.248)
			(stroke
				(width 0.15)
				(type solid)
			)
			(layer "B.Fab")
		)
		(fp_line
			(start 0.504 -0.248)
			(end 0.504 0.25)
			(stroke
				(width 0.15)
				(type solid)
			)
			(layer "B.Fab")
		)
		(fp_line
			(start 0.504 0.25)
			(end -0.494 0.25)
			(stroke
				(width 0.15)
				(type solid)
			)
			(layer "B.Fab")
		)
		(fp_text user "Author: Antmicro"
			(at -0.939 -3.399 180)
			(layer "B.Fab")
			(hide yes)
			(effects
				(font
					(size 0.7 0.7)
					(thickness 0.15)
				)
				(justify left bottom mirror)
			)
		)
		(fp_text user "${REFERENCE}"
			(at -0.939 -4.599 180)
			(layer "B.Fab")
			(hide yes)
			(effects
				(font
					(size 0.7 0.7)
					(thickness 0.15)
				)
				(justify left bottom mirror)
			)
		)
		(fp_text user "License: Apache-2.0"
			(at -0.939 -5.799 180)
			(layer "B.Fab")
			(hide yes)
			(effects
				(font
					(size 0.7 0.7)
					(thickness 0.15)
				)
				(justify left bottom mirror)
			)
		)
		(pad "1" smd roundrect
			(at -0.48 0)
			(size 0.59 0.64)
			(layers "B.Cu" "B.Paste" "B.Mask")
			(roundrect_rratio 0.25)
			(net 99 "+5V")
			(pintype "passive")
		)
		(pad "2" smd roundrect
			(at 0.48 0)
			(size 0.59 0.64)
			(layers "B.Cu" "B.Paste" "B.Mask")
			(roundrect_rratio 0.25)
			(net 1 "GND")
			(pintype "passive")
		)
	)
	(footprint "antmicro-footprints:C_0402_1005Metric"
		(layer "B.Cu")
		(at 57.55 111.45)
		(descr "Capacitor SMD 0402")
		(tags "capacitor SMD 0402")
		(property "Reference" "C29"
			(at 3.01 0.31 180)
			(layer "B.SilkS")
			(effects
				(font
					(size 0.7 0.7)
					(thickness 0.15)
				)
				(justify left bottom mirror)
			)
		)
		(property "Value" "C_100n_0402"
			(at 0 -1.4 180)
			(layer "B.Fab")
			(effects
				(font
					(size 0.7 0.7)
					(thickness 0.15)
				)
				(justify left bottom mirror)
			)
		)
		(property "Footprint" "antmicro-footprints:C_0402_1005Metric"
			(at 0 0 0)
			(layer "F.Fab")
			(hide yes)
			(effects
				(font
					(size 1.27 1.27)
					(thickness 0.15)
				)
			)
		)
		(property "Datasheet" "https://www.murata.com/products/productdetail?partno=GRM155R61H104KE14%23"
			(at 0 0 0)
			(layer "F.Fab")
			(hide yes)
			(effects
				(font
					(size 1.27 1.27)
					(thickness 0.15)
				)
			)
		)
		(property "Author" "Antmicro"
			(at 0 0 0)
			(layer "B.Fab")
			(hide yes)
			(effects
				(font
					(size 1 1)
					(thickness 0.15)
				)
				(justify mirror)
			)
		)
		(property "Dielectric" "X5R"
			(at 0 0 0)
			(layer "B.Fab")
			(hide yes)
			(effects
				(font
					(size 1 1)
					(thickness 0.15)
				)
				(justify mirror)
			)
		)
		(property "License" "Apache-2.0"
			(at 0 0 0)
			(layer "B.Fab")
			(hide yes)
			(effects
				(font
					(size 1 1)
					(thickness 0.15)
				)
				(justify mirror)
			)
		)
		(property "MPN" "GRM155R61H104KE14D"
			(at 0 0 0)
			(layer "B.Fab")
			(hide yes)
			(effects
				(font
					(size 1 1)
					(thickness 0.15)
				)
				(justify mirror)
			)
		)
		(property "Manufacturer" "Murata"
			(at 0 0 0)
			(layer "B.Fab")
			(hide yes)
			(effects
				(font
					(size 1 1)
					(thickness 0.15)
				)
				(justify mirror)
			)
		)
		(property "Val" "100n"
			(at 0 0 0)
			(layer "B.Fab")
			(hide yes)
			(effects
				(font
					(size 1 1)
					(thickness 0.15)
				)
				(justify mirror)
			)
		)
		(property "Voltage" "50V"
			(at 0 0 0)
			(layer "B.Fab")
			(hide yes)
			(effects
				(font
					(size 1 1)
					(thickness 0.15)
				)
				(justify mirror)
			)
		)
		(sheetname "USB Debug, DP")
		(sheetfile "usb.kicad_sch")
		(attr smd)
		(fp_rect
			(start -0.925 0.47)
			(end 0.925 -0.47)
			(stroke
				(width 0.05)
				(type default)
			)
			(fill none)
			(layer "B.CrtYd")
		)
		(fp_line
			(start -0.494 -0.248)
			(end 0.504 -0.248)
			(stroke
				(width 0.15)
				(type solid)
			)
			(layer "B.Fab")
		)
		(fp_line
			(start -0.494 0.25)
			(end -0.494 -0.248)
			(stroke
				(width 0.15)
				(type solid)
			)
			(layer "B.Fab")
		)
		(fp_line
			(start 0.504 -0.248)
			(end 0.504 0.25)
			(stroke
				(width 0.15)
				(type solid)
			)
			(layer "B.Fab")
		)
		(fp_line
			(start 0.504 0.25)
			(end -0.494 0.25)
			(stroke
				(width 0.15)
				(type solid)
			)
			(layer "B.Fab")
		)
		(fp_text user "${REFERENCE}"
			(at -0.932 -3.168 180)
			(layer "B.Fab")
			(hide yes)
			(effects
				(font
					(size 0.7 0.7)
					(thickness 0.15)
				)
				(justify left bottom mirror)
			)
		)
		(fp_text user "License: Apache-2.0"
			(at -0.932 -5.17 180)
			(layer "B.Fab")
			(hide yes)
			(effects
				(font
					(size 0.7 0.7)
					(thickness 0.15)
				)
				(justify left bottom mirror)
			)
		)
		(fp_text user "Author: Antmicro"
			(at -0.932 -4.17 180)
			(layer "B.Fab")
			(hide yes)
			(effects
				(font
					(size 0.7 0.7)
					(thickness 0.15)
				)
				(justify left bottom mirror)
			)
		)
		(pad "1" smd roundrect
			(at -0.48 0)
			(size 0.59 0.64)
			(layers "B.Cu" "B.Paste" "B.Mask")
			(roundrect_rratio 0.25)
			(net 185 "/USB Debug, DP/FTDI_3V3")
			(pintype "passive")
		)
		(pad "2" smd roundrect
			(at 0.48 0)
			(size 0.59 0.64)
			(layers "B.Cu" "B.Paste" "B.Mask")
			(roundrect_rratio 0.25)
			(net 1 "GND")
			(pintype "passive")
		)
	)
	(footprint "antmicro-footprints:R_0402_1005Metric"
		(layer "B.Cu")
		(at 60.14 98.62 90)
		(descr "Resistor SMD 0402")
		(tags "resistor SMD 0402")
		(property "Reference" "R71"
			(at -3.03 0.48 90)
			(layer "B.SilkS")
			(effects
				(font
					(size 0.7 0.7)
					(thickness 0.15)
				)
				(justify right bottom mirror)
			)
		)
		(property "Value" "R_0R_0402"
			(at 0 -1.4 90)
			(layer "B.Fab")
			(effects
				(font
					(size 0.7 0.7)
					(thickness 0.15)
				)
				(justify right bottom mirror)
			)
		)
		(property "Footprint" "antmicro-footprints:R_0402_1005Metric"
			(at 0 0 90)
			(layer "F.Fab")
			(hide yes)
			(effects
				(font
					(size 1.27 1.27)
					(thickness 0.15)
				)
			)
		)
		(property "Datasheet" "https://industrial.panasonic.com/cdbs/www-data/pdf/RDA0000/AOA0000C301.pdf"
			(at 0 0 90)
			(layer "F.Fab")
			(hide yes)
			(effects
				(font
					(size 1.27 1.27)
					(thickness 0.15)
				)
			)
		)
		(property "Author" "Antmicro"
			(at 158.76 38.48 0)
			(layer "B.Fab")
			(hide yes)
			(effects
				(font
					(size 1 1)
					(thickness 0.15)
				)
				(justify mirror)
			)
		)
		(property "Current" "1A"
			(at 158.76 38.48 0)
			(layer "B.Fab")
			(hide yes)
			(effects
				(font
					(size 1 1)
					(thickness 0.15)
				)
				(justify mirror)
			)
		)
		(property "License" "Apache-2.0"
			(at 158.76 38.48 0)
			(layer "B.Fab")
			(hide yes)
			(effects
				(font
					(size 1 1)
					(thickness 0.15)
				)
				(justify mirror)
			)
		)
		(property "MPN" "ERJ2GE0R00X"
			(at 158.76 38.48 0)
			(layer "B.Fab")
			(hide yes)
			(effects
				(font
					(size 1 1)
					(thickness 0.15)
				)
				(justify mirror)
			)
		)
		(property "Manufacturer" "Panasonic"
			(at 158.76 38.48 0)
			(layer "B.Fab")
			(hide yes)
			(effects
				(font
					(size 1 1)
					(thickness 0.15)
				)
				(justify mirror)
			)
		)
		(property "Tolerance" ""
			(at 158.76 38.48 0)
			(layer "B.Fab")
			(hide yes)
			(effects
				(font
					(size 1 1)
					(thickness 0.15)
				)
				(justify mirror)
			)
		)
		(property "Val" "0R"
			(at 158.76 38.48 0)
			(layer "B.Fab")
			(hide yes)
			(effects
				(font
					(size 1 1)
					(thickness 0.15)
				)
				(justify mirror)
			)
		)
		(sheetname "USB Debug, DP")
		(sheetfile "usb.kicad_sch")
		(attr smd)
		(fp_rect
			(start -0.925 0.47)
			(end 0.925 -0.47)
			(stroke
				(width 0.05)
				(type default)
			)
			(fill none)
			(layer "B.CrtYd")
		)
		(fp_rect
			(start -0.5 0.25)
			(end 0.5 -0.25)
			(stroke
				(width 0.15)
				(type solid)
			)
			(fill none)
			(layer "B.Fab")
		)
		(fp_text user "Author: Antmicro"
			(at -0.95 -4.169 90)
			(layer "B.Fab")
			(hide yes)
			(effects
				(font
					(size 0.7 0.7)
					(thickness 0.15)
				)
				(justify right bottom mirror)
			)
		)
		(fp_text user "${REFERENCE}"
			(at -0.95 -3.168 90)
			(layer "B.Fab")
			(hide yes)
			(effects
				(font
					(size 0.7 0.7)
					(thickness 0.15)
				)
				(justify right bottom mirror)
			)
		)
		(fp_text user "License: Apache-2.0"
			(at -0.95 -5.169 90)
			(layer "B.Fab")
			(hide yes)
			(effects
				(font
					(size 0.7 0.7)
					(thickness 0.15)
				)
				(justify right bottom mirror)
			)
		)
		(pad "1" smd roundrect
			(at -0.48 0 90)
			(size 0.59 0.64)
			(layers "B.Cu" "B.Paste" "B.Mask")
			(roundrect_rratio 0.25)
			(net 251 "SYS_SDA")
			(pintype "passive")
		)
		(pad "2" smd roundrect
			(at 0.48 0 90)
			(size 0.59 0.64)
			(layers "B.Cu" "B.Paste" "B.Mask")
			(roundrect_rratio 0.25)
			(net 303 "/USB Debug, DP/PDC_I2C1_SDA")
			(pintype "passive")
		)
	)
	(footprint "antmicro-footprints:C_0402_1005Metric"
		(layer "B.Cu")
		(at 126.735 87.75)
		(descr "Capacitor SMD 0402")
		(tags "capacitor SMD 0402")
		(property "Reference" "C18"
			(at 2.965 0.4 180)
			(layer "B.SilkS")
			(effects
				(font
					(size 0.7 0.7)
					(thickness 0.15)
				)
				(justify left bottom mirror)
			)
		)
		(property "Value" "C_220n_0402"
			(at 0 -1.4 180)
			(layer "B.Fab")
			(effects
				(font
					(size 0.7 0.7)
					(thickness 0.15)
				)
				(justify left bottom mirror)
			)
		)
		(property "Footprint" "antmicro-footprints:C_0402_1005Metric"
			(at 0 0 0)
			(layer "F.Fab")
			(hide yes)
			(effects
				(font
					(size 1.27 1.27)
					(thickness 0.15)
				)
			)
		)
		(property "Datasheet" "https://www.yageo.com/en/Chart/Download/pdf/CC0402KRX5R6BB224"
			(at 0 0 0)
			(layer "F.Fab")
			(hide yes)
			(effects
				(font
					(size 1.27 1.27)
					(thickness 0.15)
				)
			)
		)
		(property "Author" "Antmicro"
			(at 0 0 0)
			(layer "B.Fab")
			(hide yes)
			(effects
				(font
					(size 1 1)
					(thickness 0.15)
				)
				(justify mirror)
			)
		)
		(property "Dielectric" ""
			(at 0 0 0)
			(layer "B.Fab")
			(hide yes)
			(effects
				(font
					(size 1 1)
					(thickness 0.15)
				)
				(justify mirror)
			)
		)
		(property "License" "Apache-2.0"
			(at 0 0 0)
			(layer "B.Fab")
			(hide yes)
			(effects
				(font
					(size 1 1)
					(thickness 0.15)
				)
				(justify mirror)
			)
		)
		(property "MPN" "CC0402KRX5R6BB224"
			(at 0 0 0)
			(layer "B.Fab")
			(hide yes)
			(effects
				(font
					(size 1 1)
					(thickness 0.15)
				)
				(justify mirror)
			)
		)
		(property "Manufacturer" "YAGEO"
			(at 0 0 0)
			(layer "B.Fab")
			(hide yes)
			(effects
				(font
					(size 1 1)
					(thickness 0.15)
				)
				(justify mirror)
			)
		)
		(property "Val" "220n"
			(at 0 0 0)
			(layer "B.Fab")
			(hide yes)
			(effects
				(font
					(size 1 1)
					(thickness 0.15)
				)
				(justify mirror)
			)
		)
		(property "Voltage" ""
			(at 0 0 0)
			(layer "B.Fab")
			(hide yes)
			(effects
				(font
					(size 1 1)
					(thickness 0.15)
				)
				(justify mirror)
			)
		)
		(sheetname "M.2")
		(sheetfile "m-2.kicad_sch")
		(attr smd)
		(fp_rect
			(start -0.925 0.47)
			(end 0.925 -0.47)
			(stroke
				(width 0.05)
				(type default)
			)
			(fill none)
			(layer "B.CrtYd")
		)
		(fp_line
			(start -0.494 -0.248)
			(end 0.504 -0.248)
			(stroke
				(width 0.15)
				(type solid)
			)
			(layer "B.Fab")
		)
		(fp_line
			(start -0.494 0.25)
			(end -0.494 -0.248)
			(stroke
				(width 0.15)
				(type solid)
			)
			(layer "B.Fab")
		)
		(fp_line
			(start 0.504 -0.248)
			(end 0.504 0.25)
			(stroke
				(width 0.15)
				(type solid)
			)
			(layer "B.Fab")
		)
		(fp_line
			(start 0.504 0.25)
			(end -0.494 0.25)
			(stroke
				(width 0.15)
				(type solid)
			)
			(layer "B.Fab")
		)
		(fp_text user "Author: Antmicro"
			(at -0.932 -4.17 180)
			(layer "B.Fab")
			(hide yes)
			(effects
				(font
					(size 0.7 0.7)
					(thickness 0.15)
				)
				(justify left bottom mirror)
			)
		)
		(fp_text user "License: Apache-2.0"
			(at -0.932 -5.17 180)
			(layer "B.Fab")
			(hide yes)
			(effects
				(font
					(size 0.7 0.7)
					(thickness 0.15)
				)
				(justify left bottom mirror)
			)
		)
		(fp_text user "${REFERENCE}"
			(at -0.932 -3.168 180)
			(layer "B.Fab")
			(hide yes)
			(effects
				(font
					(size 0.7 0.7)
					(thickness 0.15)
				)
				(justify left bottom mirror)
			)
		)
		(pad "1" smd roundrect
			(at -0.48 0)
			(size 0.59 0.64)
			(layers "B.Cu" "B.Paste" "B.Mask")
			(roundrect_rratio 0.25)
			(net 91 "/M.2/C_PCIE0_TX1_N")
			(pintype "passive")
		)
		(pad "2" smd roundrect
			(at 0.48 0)
			(size 0.59 0.64)
			(layers "B.Cu" "B.Paste" "B.Mask")
			(roundrect_rratio 0.25)
			(net 443 "PCIE0_TX1_N")
			(pintype "passive")
		)
	)
	(footprint "antmicro-footprints:R_0402_1005Metric"
		(layer "B.Cu")
		(at 96.2 110.9 -90)
		(descr "Resistor SMD 0402")
		(tags "resistor SMD 0402")
		(property "Reference" "R166"
			(at -1.31 -1.3 90)
			(layer "B.SilkS")
			(effects
				(font
					(size 0.7 0.7)
					(thickness 0.15)
				)
				(justify left bottom mirror)
			)
		)
		(property "Value" "R_0R_0402"
			(at 0 -1.4 90)
			(layer "B.Fab")
			(effects
				(font
					(size 0.7 0.7)
					(thickness 0.15)
				)
				(justify left bottom mirror)
			)
		)
		(property "Footprint" "antmicro-footprints:R_0402_1005Metric"
			(at 0 0 -90)
			(layer "F.Fab")
			(hide yes)
			(effects
				(font
					(size 1.27 1.27)
					(thickness 0.15)
				)
			)
		)
		(property "Datasheet" "https://industrial.panasonic.com/cdbs/www-data/pdf/RDA0000/AOA0000C301.pdf"
			(at 0 0 -90)
			(layer "F.Fab")
			(hide yes)
			(effects
				(font
					(size 1.27 1.27)
					(thickness 0.15)
				)
			)
		)
		(property "Author" "Antmicro"
			(at -14.7 207.1 0)
			(layer "B.Fab")
			(hide yes)
			(effects
				(font
					(size 1 1)
					(thickness 0.15)
				)
				(justify mirror)
			)
		)
		(property "Current" "1A"
			(at -14.7 207.1 0)
			(layer "B.Fab")
			(hide yes)
			(effects
				(font
					(size 1 1)
					(thickness 0.15)
				)
				(justify mirror)
			)
		)
		(property "License" "Apache-2.0"
			(at -14.7 207.1 0)
			(layer "B.Fab")
			(hide yes)
			(effects
				(font
					(size 1 1)
					(thickness 0.15)
				)
				(justify mirror)
			)
		)
		(property "MPN" "ERJ2GE0R00X"
			(at -14.7 207.1 0)
			(layer "B.Fab")
			(hide yes)
			(effects
				(font
					(size 1 1)
					(thickness 0.15)
				)
				(justify mirror)
			)
		)
		(property "Manufacturer" "Panasonic"
			(at -14.7 207.1 0)
			(layer "B.Fab")
			(hide yes)
			(effects
				(font
					(size 1 1)
					(thickness 0.15)
				)
				(justify mirror)
			)
		)
		(property "Tolerance" ""
			(at -14.7 207.1 0)
			(layer "B.Fab")
			(hide yes)
			(effects
				(font
					(size 1 1)
					(thickness 0.15)
				)
				(justify mirror)
			)
		)
		(property "Val" "0R"
			(at -14.7 207.1 0)
			(layer "B.Fab")
			(hide yes)
			(effects
				(font
					(size 1 1)
					(thickness 0.15)
				)
				(justify mirror)
			)
		)
		(sheetname "CSI")
		(sheetfile "csi.kicad_sch")
		(attr smd)
		(fp_rect
			(start -0.925 0.47)
			(end 0.925 -0.47)
			(stroke
				(width 0.05)
				(type default)
			)
			(fill none)
			(layer "B.CrtYd")
		)
		(fp_rect
			(start -0.5 0.25)
			(end 0.5 -0.25)
			(stroke
				(width 0.15)
				(type solid)
			)
			(fill none)
			(layer "B.Fab")
		)
		(fp_text user "Author: Antmicro"
			(at -0.95 -4.169 90)
			(layer "B.Fab")
			(hide yes)
			(effects
				(font
					(size 0.7 0.7)
					(thickness 0.15)
				)
				(justify left bottom mirror)
			)
		)
		(fp_text user "License: Apache-2.0"
			(at -0.95 -5.169 90)
			(layer "B.Fab")
			(hide yes)
			(effects
				(font
					(size 0.7 0.7)
					(thickness 0.15)
				)
				(justify left bottom mirror)
			)
		)
		(fp_text user "${REFERENCE}"
			(at -0.95 -3.168 90)
			(layer "B.Fab")
			(hide yes)
			(effects
				(font
					(size 0.7 0.7)
					(thickness 0.15)
				)
				(justify left bottom mirror)
			)
		)
		(pad "1" smd roundrect
			(at -0.48 0 270)
			(size 0.59 0.64)
			(layers "B.Cu" "B.Paste" "B.Mask")
			(roundrect_rratio 0.25)
			(net 321 "/CSI/CSIA_I2C_VCC")
			(pintype "passive")
		)
		(pad "2" smd roundrect
			(at 0.48 0 270)
			(size 0.59 0.64)
			(layers "B.Cu" "B.Paste" "B.Mask")
			(roundrect_rratio 0.25)
			(net 87 "+3V3")
			(pintype "passive")
		)
	)
	(footprint "antmicro-footprints:R_0402_1005Metric"
		(layer "B.Cu")
		(at 91.3 98.45 90)
		(descr "Resistor SMD 0402")
		(tags "resistor SMD 0402")
		(property "Reference" "R225"
			(at 1.57 -0.45 -90)
			(layer "B.SilkS")
			(effects
				(font
					(size 0.7 0.7)
					(thickness 0.15)
				)
				(justify left bottom mirror)
			)
		)
		(property "Value" "R_0R_0402"
			(at 0 -1.4 -90)
			(layer "B.Fab")
			(effects
				(font
					(size 0.7 0.7)
					(thickness 0.15)
				)
				(justify left bottom mirror)
			)
		)
		(property "Footprint" "antmicro-footprints:R_0402_1005Metric"
			(at 0 0 90)
			(layer "F.Fab")
			(hide yes)
			(effects
				(font
					(size 1.27 1.27)
					(thickness 0.15)
				)
			)
		)
		(property "Datasheet" "https://industrial.panasonic.com/cdbs/www-data/pdf/RDA0000/AOA0000C301.pdf"
			(at 0 0 90)
			(layer "F.Fab")
			(hide yes)
			(effects
				(font
					(size 1.27 1.27)
					(thickness 0.15)
				)
			)
		)
		(property "Author" "Antmicro"
			(at 189.75 7.15 0)
			(layer "B.Fab")
			(hide yes)
			(effects
				(font
					(size 1 1)
					(thickness 0.15)
				)
				(justify mirror)
			)
		)
		(property "Current" "1A"
			(at 189.75 7.15 0)
			(layer "B.Fab")
			(hide yes)
			(effects
				(font
					(size 1 1)
					(thickness 0.15)
				)
				(justify mirror)
			)
		)
		(property "License" "Apache-2.0"
			(at 189.75 7.15 0)
			(layer "B.Fab")
			(hide yes)
			(effects
				(font
					(size 1 1)
					(thickness 0.15)
				)
				(justify mirror)
			)
		)
		(property "MPN" "ERJ2GE0R00X"
			(at 189.75 7.15 0)
			(layer "B.Fab")
			(hide yes)
			(effects
				(font
					(size 1 1)
					(thickness 0.15)
				)
				(justify mirror)
			)
		)
		(property "Manufacturer" "Panasonic"
			(at 189.75 7.15 0)
			(layer "B.Fab")
			(hide yes)
			(effects
				(font
					(size 1 1)
					(thickness 0.15)
				)
				(justify mirror)
			)
		)
		(property "Tolerance" ""
			(at 189.75 7.15 0)
			(layer "B.Fab")
			(hide yes)
			(effects
				(font
					(size 1 1)
					(thickness 0.15)
				)
				(justify mirror)
			)
		)
		(property "Val" "0R"
			(at 189.75 7.15 0)
			(layer "B.Fab")
			(hide yes)
			(effects
				(font
					(size 1 1)
					(thickness 0.15)
				)
				(justify mirror)
			)
		)
		(sheetname "HDMI")
		(sheetfile "hdmi.kicad_sch")
		(attr smd)
		(fp_rect
			(start -0.925 0.47)
			(end 0.925 -0.47)
			(stroke
				(width 0.05)
				(type default)
			)
			(fill none)
			(layer "B.CrtYd")
		)
		(fp_rect
			(start -0.5 0.25)
			(end 0.5 -0.25)
			(stroke
				(width 0.15)
				(type solid)
			)
			(fill none)
			(layer "B.Fab")
		)
		(fp_text user "Author: Antmicro"
			(at -0.95 -4.169 -90)
			(layer "B.Fab")
			(hide yes)
			(effects
				(font
					(size 0.7 0.7)
					(thickness 0.15)
				)
				(justify left bottom mirror)
			)
		)
		(fp_text user "License: Apache-2.0"
			(at -0.95 -5.169 -90)
			(layer "B.Fab")
			(hide yes)
			(effects
				(font
					(size 0.7 0.7)
					(thickness 0.15)
				)
				(justify left bottom mirror)
			)
		)
		(fp_text user "${REFERENCE}"
			(at -0.95 -3.168 -90)
			(layer "B.Fab")
			(hide yes)
			(effects
				(font
					(size 0.7 0.7)
					(thickness 0.15)
				)
				(justify left bottom mirror)
			)
		)
		(pad "1" smd roundrect
			(at -0.48 0 90)
			(size 0.59 0.64)
			(layers "B.Cu" "B.Paste" "B.Mask")
			(roundrect_rratio 0.25)
			(net 703 "/HDMI/HDMI_HPD")
			(pintype "passive")
		)
		(pad "2" smd roundrect
			(at 0.48 0 90)
			(size 0.59 0.64)
			(layers "B.Cu" "B.Paste" "B.Mask")
			(roundrect_rratio 0.25)
			(net 624 "Net-(Q3-D)")
			(pintype "passive")
		)
	)
	(footprint "antmicro-footprints:C_0402_1005Metric"
		(layer "B.Cu")
		(at 126.75 93.75)
		(descr "Capacitor SMD 0402")
		(tags "capacitor SMD 0402")
		(property "Reference" "C20"
			(at -1.15 1.3 0)
			(layer "B.SilkS")
			(effects
				(font
					(size 0.7 0.7)
					(thickness 0.15)
				)
				(justify right bottom mirror)
			)
		)
		(property "Value" "C_220n_0402"
			(at 0 -1.4 0)
			(layer "B.Fab")
			(effects
				(font
					(size 0.7 0.7)
					(thickness 0.15)
				)
				(justify right bottom mirror)
			)
		)
		(property "Footprint" "antmicro-footprints:C_0402_1005Metric"
			(at 0 0 0)
			(layer "F.Fab")
			(hide yes)
			(effects
				(font
					(size 1.27 1.27)
					(thickness 0.15)
				)
			)
		)
		(property "Datasheet" "https://www.yageo.com/en/Chart/Download/pdf/CC0402KRX5R6BB224"
			(at 0 0 0)
			(layer "F.Fab")
			(hide yes)
			(effects
				(font
					(size 1.27 1.27)
					(thickness 0.15)
				)
			)
		)
		(property "Author" "Antmicro"
			(at 0 0 0)
			(layer "B.Fab")
			(hide yes)
			(effects
				(font
					(size 1 1)
					(thickness 0.15)
				)
				(justify mirror)
			)
		)
		(property "Dielectric" ""
			(at 0 0 0)
			(layer "B.Fab")
			(hide yes)
			(effects
				(font
					(size 1 1)
					(thickness 0.15)
				)
				(justify mirror)
			)
		)
		(property "License" "Apache-2.0"
			(at 0 0 0)
			(layer "B.Fab")
			(hide yes)
			(effects
				(font
					(size 1 1)
					(thickness 0.15)
				)
				(justify mirror)
			)
		)
		(property "MPN" "CC0402KRX5R6BB224"
			(at 0 0 0)
			(layer "B.Fab")
			(hide yes)
			(effects
				(font
					(size 1 1)
					(thickness 0.15)
				)
				(justify mirror)
			)
		)
		(property "Manufacturer" "YAGEO"
			(at 0 0 0)
			(layer "B.Fab")
			(hide yes)
			(effects
				(font
					(size 1 1)
					(thickness 0.15)
				)
				(justify mirror)
			)
		)
		(property "Val" "220n"
			(at 0 0 0)
			(layer "B.Fab")
			(hide yes)
			(effects
				(font
					(size 1 1)
					(thickness 0.15)
				)
				(justify mirror)
			)
		)
		(property "Voltage" ""
			(at 0 0 0)
			(layer "B.Fab")
			(hide yes)
			(effects
				(font
					(size 1 1)
					(thickness 0.15)
				)
				(justify mirror)
			)
		)
		(sheetname "M.2")
		(sheetfile "m-2.kicad_sch")
		(attr smd)
		(fp_rect
			(start -0.925 0.47)
			(end 0.925 -0.47)
			(stroke
				(width 0.05)
				(type default)
			)
			(fill none)
			(layer "B.CrtYd")
		)
		(fp_line
			(start -0.494 -0.248)
			(end 0.504 -0.248)
			(stroke
				(width 0.15)
				(type solid)
			)
			(layer "B.Fab")
		)
		(fp_line
			(start -0.494 0.25)
			(end -0.494 -0.248)
			(stroke
				(width 0.15)
				(type solid)
			)
			(layer "B.Fab")
		)
		(fp_line
			(start 0.504 -0.248)
			(end 0.504 0.25)
			(stroke
				(width 0.15)
				(type solid)
			)
			(layer "B.Fab")
		)
		(fp_line
			(start 0.504 0.25)
			(end -0.494 0.25)
			(stroke
				(width 0.15)
				(type solid)
			)
			(layer "B.Fab")
		)
		(fp_text user "${REFERENCE}"
			(at -0.932 -3.168 0)
			(layer "B.Fab")
			(hide yes)
			(effects
				(font
					(size 0.7 0.7)
					(thickness 0.15)
				)
				(justify right bottom mirror)
			)
		)
		(fp_text user "Author: Antmicro"
			(at -0.932 -4.17 0)
			(layer "B.Fab")
			(hide yes)
			(effects
				(font
					(size 0.7 0.7)
					(thickness 0.15)
				)
				(justify right bottom mirror)
			)
		)
		(fp_text user "License: Apache-2.0"
			(at -0.932 -5.17 0)
			(layer "B.Fab")
			(hide yes)
			(effects
				(font
					(size 0.7 0.7)
					(thickness 0.15)
				)
				(justify right bottom mirror)
			)
		)
		(pad "1" smd roundrect
			(at -0.48 0)
			(size 0.59 0.64)
			(layers "B.Cu" "B.Paste" "B.Mask")
			(roundrect_rratio 0.25)
			(net 95 "/M.2/C_PCIE0_TX3_N")
			(pintype "passive")
		)
		(pad "2" smd roundrect
			(at 0.48 0)
			(size 0.59 0.64)
			(layers "B.Cu" "B.Paste" "B.Mask")
			(roundrect_rratio 0.25)
			(net 447 "PCIE0_TX3_N")
			(pintype "passive")
		)
	)
	(footprint "antmicro-footprints:LED_0603_1608Metric_G"
		(layer "B.Cu")
		(at 144.5 112.5 180)
		(descr "LED SMD 0603 Green")
		(tags "LED SMD 0603 Green")
		(property "Reference" "D20"
			(at -1.05 0.6 180)
			(layer "B.SilkS")
			(effects
				(font
					(size 0.7 0.7)
					(thickness 0.15)
				)
				(justify left bottom mirror)
			)
		)
		(property "Value" "LED_G_0603_LTST-C190GKT"
			(at -0.001 -1.599 0)
			(layer "B.Fab")
			(effects
				(font
					(size 0.7 0.7)
					(thickness 0.15)
				)
				(justify left bottom mirror)
			)
		)
		(property "Footprint" "antmicro-footprints:LED_0603_1608Metric_G"
			(at 0 0 180)
			(layer "F.Fab")
			(hide yes)
			(effects
				(font
					(size 1.27 1.27)
					(thickness 0.15)
				)
			)
		)
		(property "Datasheet" "https://media.digikey.com/pdf/Data%20Sheets/Lite-On%20PDFs/LTST-C190GKT.pdf"
			(at 0 0 180)
			(layer "F.Fab")
			(hide yes)
			(effects
				(font
					(size 1.27 1.27)
					(thickness 0.15)
				)
			)
		)
		(property "Author" "Antmicro"
			(at 289 225 0)
			(layer "B.Fab")
			(hide yes)
			(effects
				(font
					(size 1 1)
					(thickness 0.15)
				)
				(justify mirror)
			)
		)
		(property "Color" "Green"
			(at 289 225 0)
			(layer "B.Fab")
			(hide yes)
			(effects
				(font
					(size 1 1)
					(thickness 0.15)
				)
				(justify mirror)
			)
		)
		(property "License" "Apache-2.0"
			(at 289 225 0)
			(layer "B.Fab")
			(hide yes)
			(effects
				(font
					(size 1 1)
					(thickness 0.15)
				)
				(justify mirror)
			)
		)
		(property "MPN" "LTST-C190GKT"
			(at 289 225 0)
			(layer "B.Fab")
			(hide yes)
			(effects
				(font
					(size 1 1)
					(thickness 0.15)
				)
				(justify mirror)
			)
		)
		(property "Manufacturer" "Lite-On"
			(at 289 225 0)
			(layer "B.Fab")
			(hide yes)
			(effects
				(font
					(size 1 1)
					(thickness 0.15)
				)
				(justify mirror)
			)
		)
		(sheetname "CSI")
		(sheetfile "csi.kicad_sch")
		(attr smd)
		(fp_line
			(start 0.24 -0.001)
			(end 0.105328 -0.001008)
			(stroke
				(width 0.1)
				(type solid)
			)
			(layer "B.SilkS")
		)
		(fp_line
			(start 0.105328 0.198992)
			(end 0.105328 -0.201008)
			(stroke
				(width 0.1)
				(type solid)
			)
			(layer "B.SilkS")
		)
		(fp_line
			(start 0.105328 0.198992)
			(end -0.094672 -0.001008)
			(stroke
				(width 0.1)
				(type solid)
			)
			(layer "B.SilkS")
		)
		(fp_line
			(start -0.094672 0.198992)
			(end -0.094672 -0.201008)
			(stroke
				(width 0.1)
				(type solid)
			)
			(layer "B.SilkS")
		)
		(fp_line
			(start -0.094672 -0.001008)
			(end 0.105328 -0.201008)
			(stroke
				(width 0.1)
				(type solid)
			)
			(layer "B.SilkS")
		)
		(fp_line
			(start -0.22 0.35)
			(end 0.22 0.35)
			(stroke
				(width 0.15)
				(type solid)
			)
			(layer "B.SilkS")
		)
		(fp_line
			(start -0.22 -0.35)
			(end 0.22 -0.35)
			(stroke
				(width 0.15)
				(type solid)
			)
			(layer "B.SilkS")
		)
		(fp_line
			(start -0.24 -0.001008)
			(end -0.094672 -0.001008)
			(stroke
				(width 0.1)
				(type solid)
			)
			(layer "B.SilkS")
		)
		(fp_line
			(start -1.18 -0.321)
			(end -1.18 0.319)
			(stroke
				(width 0.15)
				(type solid)
			)
			(layer "B.SilkS")
		)
		(fp_rect
			(start 1.25 -0.65)
			(end -1.25 0.65)
			(stroke
				(width 0.05)
				(type solid)
			)
			(fill none)
			(layer "B.CrtYd")
		)
		(fp_line
			(start 0.201 0.202)
			(end 0.201 0)
			(stroke
				(width 0.15)
				(type solid)
			)
			(layer "B.Fab")
		)
		(fp_line
			(start 0.201 0)
			(end 0.599 0)
			(stroke
				(width 0.15)
				(type solid)
			)
			(layer "B.Fab")
		)
		(fp_line
			(start 0.201 0)
			(end 0.201 -0.2)
			(stroke
				(width 0.15)
				(type solid)
			)
			(layer "B.Fab")
		)
		(fp_line
			(start 0.201 -0.2)
			(end -0.101 0)
			(stroke
				(width 0.15)
				(type solid)
			)
			(layer "B.Fab")
		)
		(fp_line
			(start -0.101 0)
			(end 0.201 0.202)
			(stroke
				(width 0.15)
				(type solid)
			)
			(layer "B.Fab")
		)
		(fp_line
			(start -0.199 -0.1)
			(end -0.199 0.202)
			(stroke
				(width 0.15)
				(type solid)
			)
			(layer "B.Fab")
		)
		(fp_line
			(start -0.199 -0.1)
			(end -0.199 -0.2)
			(stroke
				(width 0.15)
				(type solid)
			)
			(layer "B.Fab")
		)
		(fp_line
			(start -0.597 0)
			(end -0.199 0)
			(stroke
				(width 0.15)
				(type solid)
			)
			(layer "B.Fab")
		)
		(fp_rect
			(start 0.848 -0.4)
			(end -0.85 0.402)
			(stroke
				(width 0.15)
				(type solid)
			)
			(fill none)
			(layer "B.Fab")
		)
		(fp_text user "License: Apache-2.0"
			(at -1.4224 -3.599 0)
			(layer "B.Fab")
			(hide yes)
			(effects
				(font
					(size 0.7 0.7)
					(thickness 0.15)
				)
				(justify left bottom mirror)
			)
		)
		(fp_text user "${REFERENCE}"
			(at -1.4224 -5.999 0)
			(layer "B.Fab")
			(hide yes)
			(effects
				(font
					(size 0.7 0.7)
					(thickness 0.15)
				)
				(justify left bottom mirror)
			)
		)
		(fp_text user "Author: Antmicro"
			(at -1.4224 -4.799 0)
			(layer "B.Fab")
			(hide yes)
			(effects
				(font
					(size 0.7 0.7)
					(thickness 0.15)
				)
				(justify left bottom mirror)
			)
		)
		(pad "1" smd roundrect
			(at -0.7 0)
			(size 0.8 1)
			(layers "B.Cu" "B.Paste" "B.Mask")
			(roundrect_rratio 0.2)
			(net 1 "GND")
			(pinfunction "C")
			(pintype "passive")
		)
		(pad "2" smd roundrect
			(at 0.7 0)
			(size 0.8 1)
			(layers "B.Cu" "B.Paste" "B.Mask")
			(roundrect_rratio 0.2)
			(net 160 "Net-(D20-A)")
			(pinfunction "A")
			(pintype "passive")
		)
	)
	(footprint "antmicro-footprints:C_0402_1005Metric"
		(layer "B.Cu")
		(at 66.075 98.05 -90)
		(descr "Capacitor SMD 0402")
		(tags "capacitor SMD 0402")
		(property "Reference" "C28"
			(at -1.11 -1.495 90)
			(layer "B.SilkS")
			(effects
				(font
					(size 0.7 0.7)
					(thickness 0.15)
				)
				(justify left bottom mirror)
			)
		)
		(property "Value" "C_10u_0402"
			(at -1.022927 -2.155213 90)
			(layer "B.Fab")
			(effects
				(font
					(size 0.7 0.7)
					(thickness 0.15)
				)
				(justify left bottom mirror)
			)
		)
		(property "Footprint" "antmicro-footprints:C_0402_1005Metric"
			(at 0 0 -90)
			(layer "F.Fab")
			(hide yes)
			(effects
				(font
					(size 1.27 1.27)
					(thickness 0.15)
				)
			)
		)
		(property "Datasheet" "https://www.yageo.com/en/Chart/Download/pdf/CC0402MRX5R5BB106"
			(at 0 0 -90)
			(layer "F.Fab")
			(hide yes)
			(effects
				(font
					(size 1.27 1.27)
					(thickness 0.15)
				)
			)
		)
		(property "Author" "Antmicro"
			(at -31.975 164.125 0)
			(layer "B.Fab")
			(hide yes)
			(effects
				(font
					(size 1 1)
					(thickness 0.15)
				)
				(justify mirror)
			)
		)
		(property "Dielectric" ""
			(at -31.975 164.125 0)
			(layer "B.Fab")
			(hide yes)
			(effects
				(font
					(size 1 1)
					(thickness 0.15)
				)
				(justify mirror)
			)
		)
		(property "License" "Apache-2.0"
			(at -31.975 164.125 0)
			(layer "B.Fab")
			(hide yes)
			(effects
				(font
					(size 1 1)
					(thickness 0.15)
				)
				(justify mirror)
			)
		)
		(property "MPN" "CC0402MRX5R5BB106"
			(at -31.975 164.125 0)
			(layer "B.Fab")
			(hide yes)
			(effects
				(font
					(size 1 1)
					(thickness 0.15)
				)
				(justify mirror)
			)
		)
		(property "Manufacturer" "YAGEO"
			(at -31.975 164.125 0)
			(layer "B.Fab")
			(hide yes)
			(effects
				(font
					(size 1 1)
					(thickness 0.15)
				)
				(justify mirror)
			)
		)
		(property "Val" "10u"
			(at -31.975 164.125 0)
			(layer "B.Fab")
			(hide yes)
			(effects
				(font
					(size 1 1)
					(thickness 0.15)
				)
				(justify mirror)
			)
		)
		(property "Voltage" ""
			(at -31.975 164.125 0)
			(layer "B.Fab")
			(hide yes)
			(effects
				(font
					(size 1 1)
					(thickness 0.15)
				)
				(justify mirror)
			)
		)
		(sheetname "USB Debug, DP")
		(sheetfile "usb.kicad_sch")
		(attr smd)
		(fp_rect
			(start -0.925 0.47)
			(end 0.925 -0.47)
			(stroke
				(width 0.05)
				(type default)
			)
			(fill none)
			(layer "B.CrtYd")
		)
		(fp_line
			(start -0.494 0.25)
			(end -0.494 -0.248)
			(stroke
				(width 0.15)
				(type solid)
			)
			(layer "B.Fab")
		)
		(fp_line
			(start 0.504 0.25)
			(end -0.494 0.25)
			(stroke
				(width 0.15)
				(type solid)
			)
			(layer "B.Fab")
		)
		(fp_line
			(start -0.494 -0.248)
			(end 0.504 -0.248)
			(stroke
				(width 0.15)
				(type solid)
			)
			(layer "B.Fab")
		)
		(fp_line
			(start 0.504 -0.248)
			(end 0.504 0.25)
			(stroke
				(width 0.15)
				(type solid)
			)
			(layer "B.Fab")
		)
		(fp_text user "${REFERENCE}"
			(at -0.939 -4.599 90)
			(layer "B.Fab")
			(hide yes)
			(effects
				(font
					(size 0.7 0.7)
					(thickness 0.15)
				)
				(justify left bottom mirror)
			)
		)
		(fp_text user "Author: Antmicro"
			(at -0.939 -3.399 90)
			(layer "B.Fab")
			(hide yes)
			(effects
				(font
					(size 0.7 0.7)
					(thickness 0.15)
				)
				(justify left bottom mirror)
			)
		)
		(fp_text user "License: Apache-2.0"
			(at -0.939 -5.799 90)
			(layer "B.Fab")
			(hide yes)
			(effects
				(font
					(size 0.7 0.7)
					(thickness 0.15)
				)
				(justify left bottom mirror)
			)
		)
		(pad "1" smd roundrect
			(at -0.48 0 270)
			(size 0.59 0.64)
			(layers "B.Cu" "B.Paste" "B.Mask")
			(roundrect_rratio 0.25)
			(net 1 "GND")
			(pintype "passive")
		)
		(pad "2" smd roundrect
			(at 0.48 0 270)
			(size 0.59 0.64)
			(layers "B.Cu" "B.Paste" "B.Mask")
			(roundrect_rratio 0.25)
			(net 133 "/USB Debug, DP/PDC_LDO_1V8")
			(pintype "passive")
		)
	)
	(footprint "antmicro-footprints:R_0402_1005Metric"
		(layer "B.Cu")
		(at 90.39 104.31 45)
		(descr "Resistor SMD 0402")
		(tags "resistor SMD 0402")
		(property "Reference" "R224"
			(at 2.135462 1.414214 -135)
			(layer "B.SilkS")
			(effects
				(font
					(size 0.7 0.7)
					(thickness 0.15)
				)
				(justify left bottom mirror)
			)
		)
		(property "Value" "R_499R_0402"
			(at -1.011843 -1.772046 -135)
			(layer "B.Fab")
			(effects
				(font
					(size 0.7 0.7)
					(thickness 0.15)
				)
				(justify left bottom mirror)
			)
		)
		(property "Footprint" "antmicro-footprints:R_0402_1005Metric"
			(at 0 0 45)
			(layer "F.Fab")
			(hide yes)
			(effects
				(font
					(size 1.27 1.27)
					(thickness 0.15)
				)
			)
		)
		(property "Datasheet" "https://www.mouser.com/datasheet/2/54/cr-1858361.pdf"
			(at 0 0 45)
			(layer "F.Fab")
			(hide yes)
			(effects
				(font
					(size 1.27 1.27)
					(thickness 0.15)
				)
			)
		)
		(property "Author" "Antmicro"
			(at 100.232926 -33.363691 0)
			(layer "B.Fab")
			(hide yes)
			(effects
				(font
					(size 1 1)
					(thickness 0.15)
				)
				(justify mirror)
			)
		)
		(property "License" "Apache-2.0"
			(at 100.232926 -33.363691 0)
			(layer "B.Fab")
			(hide yes)
			(effects
				(font
					(size 1 1)
					(thickness 0.15)
				)
				(justify mirror)
			)
		)
		(property "MPN" "CR0402-FX-4990GLF"
			(at 100.232926 -33.363691 0)
			(layer "B.Fab")
			(hide yes)
			(effects
				(font
					(size 1 1)
					(thickness 0.15)
				)
				(justify mirror)
			)
		)
		(property "Manufacturer" "Bourns"
			(at 100.232926 -33.363691 0)
			(layer "B.Fab")
			(hide yes)
			(effects
				(font
					(size 1 1)
					(thickness 0.15)
				)
				(justify mirror)
			)
		)
		(property "Tolerance" "1%"
			(at 100.232926 -33.363691 0)
			(layer "B.Fab")
			(hide yes)
			(effects
				(font
					(size 1 1)
					(thickness 0.15)
				)
				(justify mirror)
			)
		)
		(property "Val" "499R"
			(at 100.232926 -33.363691 0)
			(layer "B.Fab")
			(hide yes)
			(effects
				(font
					(size 1 1)
					(thickness 0.15)
				)
				(justify mirror)
			)
		)
		(sheetname "HDMI")
		(sheetfile "hdmi.kicad_sch")
		(attr smd)
		(fp_poly
			(pts
				(xy -0.925 0.47) (xy 0.925 0.47) (xy 0.925 -0.47) (xy -0.925 -0.47)
			)
			(stroke
				(width 0.05)
				(type default)
			)
			(fill none)
			(layer "B.CrtYd")
		)
		(fp_poly
			(pts
				(xy -0.5 0.25) (xy 0.5 0.25) (xy 0.5 -0.25) (xy -0.5 -0.25)
			)
			(stroke
				(width 0.15)
				(type solid)
			)
			(fill none)
			(layer "B.Fab")
		)
		(fp_text user "${REFERENCE}"
			(at -0.95 -3.168 -135)
			(layer "B.Fab")
			(hide yes)
			(effects
				(font
					(size 0.7 0.7)
					(thickness 0.15)
				)
				(justify left bottom mirror)
			)
		)
		(fp_text user "License: Apache-2.0"
			(at -0.949999 -5.169 -135)
			(layer "B.Fab")
			(hide yes)
			(effects
				(font
					(size 0.7 0.7)
					(thickness 0.15)
				)
				(justify left bottom mirror)
			)
		)
		(fp_text user "Author: Antmicro"
			(at -0.95 -4.169 -135)
			(layer "B.Fab")
			(hide yes)
			(effects
				(font
					(size 0.7 0.7)
					(thickness 0.15)
				)
				(justify left bottom mirror)
			)
		)
		(pad "1" smd roundrect
			(at -0.48 0 45)
			(size 0.59 0.64)
			(layers "B.Cu" "B.Paste" "B.Mask")
			(roundrect_rratio 0.25)
			(net 623 "Net-(Q2-D)")
			(pintype "passive")
		)
		(pad "2" smd roundrect
			(at 0.48 0 45)
			(size 0.59 0.64)
			(layers "B.Cu" "B.Paste" "B.Mask")
			(roundrect_rratio 0.25)
			(net 495 "/HDMI/HDMI_CLK_P")
			(pintype "passive")
		)
	)
	(footprint "antmicro-footprints:R_0402_1005Metric"
		(layer "B.Cu")
		(at 75.23 116 90)
		(descr "Resistor SMD 0402")
		(tags "resistor SMD 0402")
		(property "Reference" "R109"
			(at 1.4 1.27 -90)
			(layer "B.SilkS")
			(effects
				(font
					(size 0.7 0.7)
					(thickness 0.15)
				)
				(justify left bottom mirror)
			)
		)
		(property "Value" "R_2M_0402"
			(at 0 -1.4 -90)
			(layer "B.Fab")
			(effects
				(font
					(size 0.7 0.7)
					(thickness 0.15)
				)
				(justify left bottom mirror)
			)
		)
		(property "Footprint" "antmicro-footprints:R_0402_1005Metric"
			(at 0 0 90)
			(layer "F.Fab")
			(hide yes)
			(effects
				(font
					(size 1.27 1.27)
					(thickness 0.15)
				)
			)
		)
		(property "Datasheet" "https://www.mouser.com/datasheet/2/447/YAGEO_PYu_RC_Group_51_RoHS_L_12-3313492.pdf"
			(at 0 0 90)
			(layer "F.Fab")
			(hide yes)
			(effects
				(font
					(size 1.27 1.27)
					(thickness 0.15)
				)
			)
		)
		(property "Description" "SMD Chip Resistor, 2 Mohm, ± 1%, 62.5 mW, 0402 [1005 Metric], Thick Film, General Purpose"
			(at 0 0 90)
			(layer "F.Fab")
			(hide yes)
			(effects
				(font
					(size 1.27 1.27)
					(thickness 0.15)
				)
			)
		)
		(property "Author" "Antmicro"
			(at 191.23 40.77 0)
			(layer "B.Fab")
			(hide yes)
			(effects
				(font
					(size 1 1)
					(thickness 0.15)
				)
				(justify mirror)
			)
		)
		(property "License" "Apache-2.0"
			(at 191.23 40.77 0)
			(layer "B.Fab")
			(hide yes)
			(effects
				(font
					(size 1 1)
					(thickness 0.15)
				)
				(justify mirror)
			)
		)
		(property "MPN" "RC0402FR-072ML"
			(at 191.23 40.77 0)
			(layer "B.Fab")
			(hide yes)
			(effects
				(font
					(size 1 1)
					(thickness 0.15)
				)
				(justify mirror)
			)
		)
		(property "Manufacturer" "YAGEO"
			(at 191.23 40.77 0)
			(layer "B.Fab")
			(hide yes)
			(effects
				(font
					(size 1 1)
					(thickness 0.15)
				)
				(justify mirror)
			)
		)
		(property "Tolerance" "1%"
			(at 191.23 40.77 0)
			(layer "B.Fab")
			(hide yes)
			(effects
				(font
					(size 1 1)
					(thickness 0.15)
				)
				(justify mirror)
			)
		)
		(property "Val" "2M"
			(at 191.23 40.77 0)
			(layer "B.Fab")
			(hide yes)
			(effects
				(font
					(size 1 1)
					(thickness 0.15)
				)
				(justify mirror)
			)
		)
		(sheetname "USB Debug, DP")
		(sheetfile "usb.kicad_sch")
		(attr smd)
		(fp_rect
			(start -0.925 0.47)
			(end 0.925 -0.47)
			(stroke
				(width 0.05)
				(type default)
			)
			(fill none)
			(layer "B.CrtYd")
		)
		(fp_rect
			(start -0.5 0.25)
			(end 0.5 -0.25)
			(stroke
				(width 0.15)
				(type solid)
			)
			(fill none)
			(layer "B.Fab")
		)
		(fp_text user "${REFERENCE}"
			(at -0.95 -3.168 -90)
			(layer "B.Fab")
			(hide yes)
			(effects
				(font
					(size 0.7 0.7)
					(thickness 0.15)
				)
				(justify left bottom mirror)
			)
		)
		(fp_text user "License: Apache-2.0"
			(at -0.95 -5.169 -90)
			(layer "B.Fab")
			(hide yes)
			(effects
				(font
					(size 0.7 0.7)
					(thickness 0.15)
				)
				(justify left bottom mirror)
			)
		)
		(fp_text user "Author: Antmicro"
			(at -0.95 -4.169 -90)
			(layer "B.Fab")
			(hide yes)
			(effects
				(font
					(size 0.7 0.7)
					(thickness 0.15)
				)
				(justify left bottom mirror)
			)
		)
		(pad "1" smd roundrect
			(at -0.48 0 90)
			(size 0.59 0.64)
			(layers "B.Cu" "B.Paste" "B.Mask")
			(roundrect_rratio 0.25)
			(net 615 "/USB Debug, DP/USBC0_SBU_N")
			(pintype "passive")
		)
		(pad "2" smd roundrect
			(at 0.48 0 90)
			(size 0.59 0.64)
			(layers "B.Cu" "B.Paste" "B.Mask")
			(roundrect_rratio 0.25)
			(net 1 "GND")
			(pintype "passive")
		)
	)
	(footprint "antmicro-footprints:R_0402_1005Metric"
		(layer "B.Cu")
		(at 95.975 87.15)
		(descr "Resistor SMD 0402")
		(tags "resistor SMD 0402")
		(property "Reference" "R160"
			(at 3.765 0.43 180)
			(layer "B.SilkS")
			(effects
				(font
					(size 0.7 0.7)
					(thickness 0.15)
				)
				(justify left bottom mirror)
			)
		)
		(property "Value" "R_10k_0402"
			(at 0 -1.4 180)
			(layer "B.Fab")
			(effects
				(font
					(size 0.7 0.7)
					(thickness 0.15)
				)
				(justify left bottom mirror)
			)
		)
		(property "Footprint" "antmicro-footprints:R_0402_1005Metric"
			(at 0 0 0)
			(layer "F.Fab")
			(hide yes)
			(effects
				(font
					(size 1.27 1.27)
					(thickness 0.15)
				)
			)
		)
		(property "Datasheet" "https://www.bourns.com/docs/product-datasheets/cr.pdf"
			(at 0 0 0)
			(layer "F.Fab")
			(hide yes)
			(effects
				(font
					(size 1.27 1.27)
					(thickness 0.15)
				)
			)
		)
		(property "Author" "Antmicro"
			(at 0 0 0)
			(layer "B.Fab")
			(hide yes)
			(effects
				(font
					(size 1 1)
					(thickness 0.15)
				)
				(justify mirror)
			)
		)
		(property "License" "Apache-2.0"
			(at 0 0 0)
			(layer "B.Fab")
			(hide yes)
			(effects
				(font
					(size 1 1)
					(thickness 0.15)
				)
				(justify mirror)
			)
		)
		(property "MPN" "CR0402-FX-1002GLF"
			(at 0 0 0)
			(layer "B.Fab")
			(hide yes)
			(effects
				(font
					(size 1 1)
					(thickness 0.15)
				)
				(justify mirror)
			)
		)
		(property "Manufacturer" "Bourns"
			(at 0 0 0)
			(layer "B.Fab")
			(hide yes)
			(effects
				(font
					(size 1 1)
					(thickness 0.15)
				)
				(justify mirror)
			)
		)
		(property "Tolerance" "1%"
			(at 0 0 0)
			(layer "B.Fab")
			(hide yes)
			(effects
				(font
					(size 1 1)
					(thickness 0.15)
				)
				(justify mirror)
			)
		)
		(property "Val" "10k"
			(at 0 0 0)
			(layer "B.Fab")
			(hide yes)
			(effects
				(font
					(size 1 1)
					(thickness 0.15)
				)
				(justify mirror)
			)
		)
		(sheetname "HDMI")
		(sheetfile "hdmi.kicad_sch")
		(attr smd)
		(fp_rect
			(start -0.925 0.47)
			(end 0.925 -0.47)
			(stroke
				(width 0.05)
				(type default)
			)
			(fill none)
			(layer "B.CrtYd")
		)
		(fp_rect
			(start -0.5 0.25)
			(end 0.5 -0.25)
			(stroke
				(width 0.15)
				(type solid)
			)
			(fill none)
			(layer "B.Fab")
		)
		(fp_text user "${REFERENCE}"
			(at -0.95 -3.168 180)
			(layer "B.Fab")
			(hide yes)
			(effects
				(font
					(size 0.7 0.7)
					(thickness 0.15)
				)
				(justify left bottom mirror)
			)
		)
		(fp_text user "License: Apache-2.0"
			(at -0.95 -5.169 180)
			(layer "B.Fab")
			(hide yes)
			(effects
				(font
					(size 0.7 0.7)
					(thickness 0.15)
				)
				(justify left bottom mirror)
			)
		)
		(fp_text user "Author: Antmicro"
			(at -0.95 -4.169 180)
			(layer "B.Fab")
			(hide yes)
			(effects
				(font
					(size 0.7 0.7)
					(thickness 0.15)
				)
				(justify left bottom mirror)
			)
		)
		(pad "1" smd roundrect
			(at -0.48 0)
			(size 0.59 0.64)
			(layers "B.Cu" "B.Paste" "B.Mask")
			(roundrect_rratio 0.25)
			(net 678 "/HDMI/DP_MUX_EN")
			(pintype "passive")
		)
		(pad "2" smd roundrect
			(at 0.48 0)
			(size 0.59 0.64)
			(layers "B.Cu" "B.Paste" "B.Mask")
			(roundrect_rratio 0.25)
			(net 87 "+3V3")
			(pintype "passive")
		)
	)
	(footprint "antmicro-footprints:FB_0805_2012Metric"
		(layer "B.Cu")
		(at 54.5 93.6875 90)
		(descr "FERRITE BEAD 0805")
		(tags "FERRITE BEAD 0805")
		(property "Reference" "FB2"
			(at 1.1175 1.77 -90)
			(layer "B.SilkS")
			(effects
				(font
					(size 0.7 0.7)
					(thickness 0.15)
				)
				(justify left bottom mirror)
			)
		)
		(property "Value" "FB_220Z_2A_Murata-BLM21PG_0805"
			(at 0 -1.8 -90)
			(layer "B.Fab")
			(effects
				(font
					(size 0.7 0.7)
					(thickness 0.15)
				)
				(justify left bottom mirror)
			)
		)
		(property "Footprint" "antmicro-footprints:FB_0805_2012Metric"
			(at 0 0 90)
			(layer "F.Fab")
			(hide yes)
			(effects
				(font
					(size 1.27 1.27)
					(thickness 0.15)
				)
			)
		)
		(property "Datasheet" "https://www.murata.com/products/productdata/8796738977822/ENFA0005.pdf?1653276712000"
			(at 0 0 90)
			(layer "F.Fab")
			(hide yes)
			(effects
				(font
					(size 1.27 1.27)
					(thickness 0.15)
				)
			)
		)
		(property "Author" "Antmicro"
			(at 148.1875 39.1875 0)
			(layer "B.Fab")
			(hide yes)
			(effects
				(font
					(size 1 1)
					(thickness 0.15)
				)
				(justify mirror)
			)
		)
		(property "Current" ""
			(at 148.1875 39.1875 0)
			(layer "B.Fab")
			(hide yes)
			(effects
				(font
					(size 1 1)
					(thickness 0.15)
				)
				(justify mirror)
			)
		)
		(property "License" "Apache-2.0"
			(at 148.1875 39.1875 0)
			(layer "B.Fab")
			(hide yes)
			(effects
				(font
					(size 1 1)
					(thickness 0.15)
				)
				(justify mirror)
			)
		)
		(property "MPN" "BLM21PG221SN1D"
			(at 148.1875 39.1875 0)
			(layer "B.Fab")
			(hide yes)
			(effects
				(font
					(size 1 1)
					(thickness 0.15)
				)
				(justify mirror)
			)
		)
		(property "Manufacturer" "Murata"
			(at 148.1875 39.1875 0)
			(layer "B.Fab")
			(hide yes)
			(effects
				(font
					(size 1 1)
					(thickness 0.15)
				)
				(justify mirror)
			)
		)
		(property "Val" "220Z/2A"
			(at 148.1875 39.1875 0)
			(layer "B.Fab")
			(hide yes)
			(effects
				(font
					(size 1 1)
					(thickness 0.15)
				)
				(justify mirror)
			)
		)
		(sheetname "Ethernet")
		(sheetfile "ethernet.kicad_sch")
		(attr smd)
		(fp_line
			(start 0.281 -0.698)
			(end -0.319 -0.698)
			(stroke
				(width 0.15)
				(type solid)
			)
			(layer "B.SilkS")
		)
		(fp_line
			(start 0.299 0.698)
			(end -0.299 0.698)
			(stroke
				(width 0.15)
				(type solid)
			)
			(layer "B.SilkS")
		)
		(fp_rect
			(start 1.95 0.9)
			(end -1.95 -0.9)
			(stroke
				(width 0.05)
				(type default)
			)
			(fill none)
			(layer "B.CrtYd")
		)
		(fp_line
			(start 0.948 -0.681)
			(end -0.948 -0.681)
			(stroke
				(width 0.15)
				(type solid)
			)
			(layer "B.Fab")
		)
		(fp_line
			(start 0.948 -0.676)
			(end 0.948 0.676)
			(stroke
				(width 0.15)
				(type solid)
			)
			(layer "B.Fab")
		)
		(fp_line
			(start -0.948 -0.676)
			(end -0.948 0.676)
			(stroke
				(width 0.15)
				(type solid)
			)
			(layer "B.Fab")
		)
		(fp_line
			(start 0.948 0.681)
			(end -0.948 0.681)
			(stroke
				(width 0.15)
				(type solid)
			)
			(layer "B.Fab")
		)
		(fp_text user "License: Apache-2.0"
			(at -1.9 -5.75 -90)
			(layer "B.Fab")
			(hide yes)
			(effects
				(font
					(size 0.7 0.7)
					(thickness 0.15)
				)
				(justify left bottom mirror)
			)
		)
		(fp_text user "Author: Antmicro"
			(at -1.9 -4.4 -90)
			(layer "B.Fab")
			(hide yes)
			(effects
				(font
					(size 0.7 0.7)
					(thickness 0.15)
				)
				(justify left bottom mirror)
			)
		)
		(fp_text user "${REFERENCE}"
			(at -1.9 -3.1 -90)
			(layer "B.Fab")
			(hide yes)
			(effects
				(font
					(size 0.7 0.7)
					(thickness 0.15)
				)
				(justify left bottom mirror)
			)
		)
		(pad "1" smd roundrect
			(at -1.1 0 90)
			(size 1.2 1.3)
			(layers "B.Cu" "B.Paste" "B.Mask")
			(roundrect_rratio 0.25)
			(net 149 "Net-(D12-Pad2)")
			(pintype "passive")
		)
		(pad "2" smd roundrect
			(at 1.1 0 90)
			(size 1.2 1.3)
			(layers "B.Cu" "B.Paste" "B.Mask")
			(roundrect_rratio 0.25)
			(net 105 "/Ethernet/VDD")
			(pintype "passive")
		)
	)
	(footprint "antmicro-footprints:R_0402_1005Metric"
		(layer "B.Cu")
		(at 49.975 116 180)
		(descr "Resistor SMD 0402")
		(tags "resistor SMD 0402")
		(property "Reference" "R46"
			(at 13.375 -9.296666 0)
			(layer "B.SilkS")
			(effects
				(font
					(size 0.7 0.7)
					(thickness 0.15)
				)
				(justify left bottom mirror)
			)
		)
		(property "Value" "R_10k_0402"
			(at 0 -1.4 0)
			(layer "B.Fab")
			(effects
				(font
					(size 0.7 0.7)
					(thickness 0.15)
				)
				(justify left bottom mirror)
			)
		)
		(property "Footprint" "antmicro-footprints:R_0402_1005Metric"
			(at 0 0 180)
			(layer "F.Fab")
			(hide yes)
			(effects
				(font
					(size 1.27 1.27)
					(thickness 0.15)
				)
			)
		)
		(property "Datasheet" "https://www.bourns.com/docs/product-datasheets/cr.pdf"
			(at 0 0 180)
			(layer "F.Fab")
			(hide yes)
			(effects
				(font
					(size 1.27 1.27)
					(thickness 0.15)
				)
			)
		)
		(property "Author" "Antmicro"
			(at 99.95 232 0)
			(layer "B.Fab")
			(hide yes)
			(effects
				(font
					(size 1 1)
					(thickness 0.15)
				)
				(justify mirror)
			)
		)
		(property "License" "Apache-2.0"
			(at 99.95 232 0)
			(layer "B.Fab")
			(hide yes)
			(effects
				(font
					(size 1 1)
					(thickness 0.15)
				)
				(justify mirror)
			)
		)
		(property "MPN" "CR0402-FX-1002GLF"
			(at 99.95 232 0)
			(layer "B.Fab")
			(hide yes)
			(effects
				(font
					(size 1 1)
					(thickness 0.15)
				)
				(justify mirror)
			)
		)
		(property "Manufacturer" "Bourns"
			(at 99.95 232 0)
			(layer "B.Fab")
			(hide yes)
			(effects
				(font
					(size 1 1)
					(thickness 0.15)
				)
				(justify mirror)
			)
		)
		(property "Tolerance" "1%"
			(at 99.95 232 0)
			(layer "B.Fab")
			(hide yes)
			(effects
				(font
					(size 1 1)
					(thickness 0.15)
				)
				(justify mirror)
			)
		)
		(property "Val" "10k"
			(at 99.95 232 0)
			(layer "B.Fab")
			(hide yes)
			(effects
				(font
					(size 1 1)
					(thickness 0.15)
				)
				(justify mirror)
			)
		)
		(sheetname "USB Debug, DP")
		(sheetfile "usb.kicad_sch")
		(attr smd)
		(fp_rect
			(start -0.925 0.47)
			(end 0.925 -0.47)
			(stroke
				(width 0.05)
				(type default)
			)
			(fill none)
			(layer "B.CrtYd")
		)
		(fp_rect
			(start -0.5 0.25)
			(end 0.5 -0.25)
			(stroke
				(width 0.15)
				(type solid)
			)
			(fill none)
			(layer "B.Fab")
		)
		(fp_text user "License: Apache-2.0"
			(at -0.95 -5.169 0)
			(layer "B.Fab")
			(hide yes)
			(effects
				(font
					(size 0.7 0.7)
					(thickness 0.15)
				)
				(justify left bottom mirror)
			)
		)
		(fp_text user "${REFERENCE}"
			(at -0.95 -3.168 0)
			(layer "B.Fab")
			(hide yes)
			(effects
				(font
					(size 0.7 0.7)
					(thickness 0.15)
				)
				(justify left bottom mirror)
			)
		)
		(fp_text user "Author: Antmicro"
			(at -0.95 -4.169 0)
			(layer "B.Fab")
			(hide yes)
			(effects
				(font
					(size 0.7 0.7)
					(thickness 0.15)
				)
				(justify left bottom mirror)
			)
		)
		(pad "1" smd roundrect
			(at -0.48 0 180)
			(size 0.59 0.64)
			(layers "B.Cu" "B.Paste" "B.Mask")
			(roundrect_rratio 0.25)
			(net 185 "/USB Debug, DP/FTDI_3V3")
			(pintype "passive")
		)
		(pad "2" smd roundrect
			(at 0.48 0 180)
			(size 0.59 0.64)
			(layers "B.Cu" "B.Paste" "B.Mask")
			(roundrect_rratio 0.25)
			(net 126 "Net-(U5-~{RESET})")
			(pintype "passive")
		)
	)
	(footprint "antmicro-footprints:SOT-23-6"
		(layer "B.Cu")
		(at 62.05 76.6 90)
		(property "Reference" "U37"
			(at 1.58 1.8 0)
			(layer "B.SilkS")
			(effects
				(font
					(size 0.7 0.7)
					(thickness 0.15)
				)
				(justify left bottom mirror)
			)
		)
		(property "Value" "74LVC2G14_SOT457"
			(at -1.75 -2.75 -90)
			(layer "B.Fab")
			(effects
				(font
					(size 0.7 0.7)
					(thickness 0.15)
				)
				(justify left bottom mirror)
			)
		)
		(property "Footprint" "antmicro-footprints:SOT-23-6"
			(at 0 0 90)
			(layer "B.Fab")
			(hide yes)
			(effects
				(font
					(size 1.27 1.27)
					(thickness 0.15)
				)
			)
		)
		(property "Datasheet" "https://assets.nexperia.com/documents/data-sheet/74LVC2G14.pdf"
			(at 0 0 90)
			(layer "B.Fab")
			(hide yes)
			(effects
				(font
					(size 1.27 1.27)
					(thickness 0.15)
				)
			)
		)
		(property "MPN" "74LVC2G14GV,125"
			(at 0 0 90)
			(unlocked yes)
			(layer "B.Fab")
			(hide yes)
			(effects
				(font
					(size 1 1)
					(thickness 0.15)
				)
				(justify mirror)
			)
		)
		(property "Manufacturer" "Nexperia"
			(at 0 0 90)
			(unlocked yes)
			(layer "B.Fab")
			(hide yes)
			(effects
				(font
					(size 1 1)
					(thickness 0.15)
				)
				(justify mirror)
			)
		)
		(property "Author" "Antmicro"
			(at 0 0 90)
			(unlocked yes)
			(layer "B.Fab")
			(hide yes)
			(effects
				(font
					(size 1 1)
					(thickness 0.15)
				)
				(justify mirror)
			)
		)
		(property "License" "Apache-2.0"
			(at 0 0 90)
			(unlocked yes)
			(layer "B.Fab")
			(hide yes)
			(effects
				(font
					(size 1 1)
					(thickness 0.15)
				)
				(justify mirror)
			)
		)
		(sheetname "Supply")
		(sheetfile "supply.kicad_sch")
		(attr smd)
		(fp_line
			(start 1.45 -0.643)
			(end 1.3 -0.643)
			(stroke
				(width 0.12)
				(type solid)
			)
			(layer "B.SilkS")
		)
		(fp_line
			(start 1.45 -0.343)
			(end 1.45 -0.643)
			(stroke
				(width 0.12)
				(type solid)
			)
			(layer "B.SilkS")
		)
		(fp_line
			(start -1.45 -0.343)
			(end -1.45 -0.643)
			(stroke
				(width 0.12)
				(type solid)
			)
			(layer "B.SilkS")
		)
		(fp_line
			(start 1.45 0.457)
			(end 1.45 0.757)
			(stroke
				(width 0.12)
				(type solid)
			)
			(layer "B.SilkS")
		)
		(fp_line
			(start -1.45 0.457)
			(end -1.45 0.757)
			(stroke
				(width 0.12)
				(type solid)
			)
			(layer "B.SilkS")
		)
		(fp_line
			(start 1.45 0.757)
			(end 1.3 0.757)
			(stroke
				(width 0.12)
				(type solid)
			)
			(layer "B.SilkS")
		)
		(fp_line
			(start -1.45 0.757)
			(end -1.3 0.757)
			(stroke
				(width 0.12)
				(type solid)
			)
			(layer "B.SilkS")
		)
		(fp_rect
			(start -1.55 1.85)
			(end 1.55 -1.75)
			(stroke
				(width 0.05)
				(type solid)
			)
			(fill none)
			(layer "B.CrtYd")
		)
		(fp_line
			(start 1.5 -0.643)
			(end 1.5 0.757)
			(stroke
				(width 0.1)
				(type solid)
			)
			(layer "B.Fab")
		)
		(fp_line
			(start -1.5 -0.643)
			(end 1.5 -0.643)
			(stroke
				(width 0.1)
				(type solid)
			)
			(layer "B.Fab")
		)
		(fp_line
			(start 1.5 0.757)
			(end -1.5 0.757)
			(stroke
				(width 0.1)
				(type solid)
			)
			(layer "B.Fab")
		)
		(fp_line
			(start -1.5 0.757)
			(end -1.5 -0.643)
			(stroke
				(width 0.1)
				(type solid)
			)
			(layer "B.Fab")
		)
		(fp_text user "."
			(at -1.62 -1.34 -90)
			(layer "B.SilkS")
			(effects
				(font
					(size 1 1)
					(thickness 0.15)
				)
				(justify mirror)
			)
		)
		(fp_text user "Author: Antmicro"
			(at -1.829 -5.25 -90)
			(layer "B.Fab")
			(hide yes)
			(effects
				(font
					(size 0.7 0.7)
					(thickness 0.15)
				)
				(justify left bottom mirror)
			)
		)
		(fp_text user "${REFERENCE}"
			(at -1.75 -4 -90)
			(layer "B.Fab")
			(hide yes)
			(effects
				(font
					(size 0.7 0.7)
					(thickness 0.15)
				)
				(justify left bottom mirror)
			)
		)
		(fp_text user "License: Apache-2.0"
			(at -1.75 -6.5 -90)
			(layer "B.Fab")
			(hide yes)
			(effects
				(font
					(size 0.7 0.7)
					(thickness 0.15)
				)
				(justify left bottom mirror)
			)
		)
		(pad "1" smd roundrect
			(at -0.954 -1.1 90)
			(size 0.55 1)
			(layers "B.Cu" "B.Paste" "B.Mask")
			(roundrect_rratio 0.15)
			(net 137 "Net-(D36-A)")
			(pintype "input")
		)
		(pad "2" smd roundrect
			(at -0.003 -1.1 90)
			(size 0.55 1)
			(layers "B.Cu" "B.Paste" "B.Mask")
			(roundrect_rratio 0.15)
			(net 1 "GND")
			(pinfunction "GND")
			(pintype "power_in")
		)
		(pad "3" smd roundrect
			(at 0.947 -1.1 90)
			(size 0.55 1)
			(layers "B.Cu" "B.Paste" "B.Mask")
			(roundrect_rratio 0.15)
			(net 174 "Net-(D36-C)")
			(pintype "input")
		)
		(pad "4" smd roundrect
			(at 0.947 1.214 90)
			(size 0.55 1)
			(layers "B.Cu" "B.Paste" "B.Mask")
			(roundrect_rratio 0.15)
			(net 628 "Net-(Q11-G)")
			(pintype "output")
		)
		(pad "5" smd roundrect
			(at -0.003 1.214 90)
			(size 0.55 1)
			(layers "B.Cu" "B.Paste" "B.Mask")
			(roundrect_rratio 0.15)
			(net 117 "3V3_STDB")
			(pinfunction "VCC")
			(pintype "power_in")
		)
		(pad "6" smd roundrect
			(at -0.954 1.214 90)
			(size 0.55 1)
			(layers "B.Cu" "B.Paste" "B.Mask")
			(roundrect_rratio 0.15)
			(net 688 "Net-(U38-CLK)")
			(pintype "output")
		)
	)
	(footprint "antmicro-footprints:XDFN-2_1x0.60mm"
		(layer "B.Cu")
		(at 115.7 71.1 180)
		(property "Reference" "D17"
			(at 1.67 -1.4 0)
			(layer "B.SilkS")
			(effects
				(font
					(size 0.7 0.7)
					(thickness 0.15)
				)
				(justify right bottom mirror)
			)
		)
		(property "Value" "TPD1E0B04_XDFN-2"
			(at 0 -1.5 0)
			(layer "B.Fab")
			(effects
				(font
					(size 0.7 0.7)
					(thickness 0.15)
				)
				(justify left bottom mirror)
			)
		)
		(property "Footprint" "antmicro-footprints:XDFN-2_1x0.60mm"
			(at 0 0 180)
			(layer "F.Fab")
			(hide yes)
			(effects
				(font
					(size 1.27 1.27)
					(thickness 0.15)
				)
			)
		)
		(property "Datasheet" "https://www.ti.com/general/docs/suppproductinfo.tsp?distId=26&gotoUrl=https://www.ti.com/lit/gpn/tpd1e0b04"
			(at 0 0 180)
			(layer "F.Fab")
			(hide yes)
			(effects
				(font
					(size 1.27 1.27)
					(thickness 0.15)
				)
			)
		)
		(property "MPN" "TPD1E0B04DPYR"
			(at 231.4 142.2 0)
			(layer "B.Fab")
			(hide yes)
			(effects
				(font
					(size 1 1)
					(thickness 0.15)
				)
				(justify mirror)
			)
		)
		(property "Manufacturer" "Texas Instruments"
			(at 231.4 142.2 0)
			(layer "B.Fab")
			(hide yes)
			(effects
				(font
					(size 1 1)
					(thickness 0.15)
				)
				(justify mirror)
			)
		)
		(property "Author" "Antmicro"
			(at 231.4 142.2 0)
			(layer "B.Fab")
			(hide yes)
			(effects
				(font
					(size 1 1)
					(thickness 0.15)
				)
				(justify mirror)
			)
		)
		(property "License" "Apache-2.0"
			(at 231.4 142.2 0)
			(layer "B.Fab")
			(hide yes)
			(effects
				(font
					(size 1 1)
					(thickness 0.15)
				)
				(justify mirror)
			)
		)
		(sheetname "Peripherals")
		(sheetfile "peripherals.kicad_sch")
		(attr smd)
		(fp_rect
			(start -0.725 0.475)
			(end 0.725 -0.475)
			(stroke
				(width 0.05)
				(type solid)
			)
			(fill none)
			(layer "B.CrtYd")
		)
		(fp_rect
			(start -0.55 0.35)
			(end 0.55 -0.35)
			(stroke
				(width 0.15)
				(type solid)
			)
			(fill none)
			(layer "B.Fab")
		)
		(fp_text user "${REFERENCE}"
			(at -0.8 -3.2 0)
			(layer "B.Fab")
			(hide yes)
			(effects
				(font
					(size 0.7 0.7)
					(thickness 0.15)
				)
				(justify left bottom mirror)
			)
		)
		(fp_text user "Author: Antmicro"
			(at -0.8 -4.4 0)
			(layer "B.Fab")
			(hide yes)
			(effects
				(font
					(size 0.7 0.7)
					(thickness 0.15)
				)
				(justify left bottom mirror)
			)
		)
		(fp_text user "License: Apache-2.0"
			(at -0.8 -5.6 0)
			(layer "B.Fab")
			(hide yes)
			(effects
				(font
					(size 0.7 0.7)
					(thickness 0.15)
				)
				(justify left bottom mirror)
			)
		)
		(pad "1" smd roundrect
			(at -0.351 0 180)
			(size 0.3 0.5)
			(layers "B.Cu" "B.Paste" "B.Mask")
			(roundrect_rratio 0.25)
			(net 114 "USBSS1_RX_P")
			(pinfunction "C")
			(pintype "passive")
		)
		(pad "2" smd roundrect
			(at 0.349 0 180)
			(size 0.3 0.5)
			(layers "B.Cu" "B.Paste" "B.Mask")
			(roundrect_rratio 0.25)
			(net 1 "GND")
			(pinfunction "A")
			(pintype "passive")
		)
	)
	(footprint "antmicro-footprints:C_0402_1005Metric"
		(layer "B.Cu")
		(at 126.735 90.75)
		(descr "Capacitor SMD 0402")
		(tags "capacitor SMD 0402")
		(property "Reference" "C19"
			(at 2.965 0.45 180)
			(layer "B.SilkS")
			(effects
				(font
					(size 0.7 0.7)
					(thickness 0.15)
				)
				(justify left bottom mirror)
			)
		)
		(property "Value" "C_220n_0402"
			(at 0 -1.4 180)
			(layer "B.Fab")
			(effects
				(font
					(size 0.7 0.7)
					(thickness 0.15)
				)
				(justify left bottom mirror)
			)
		)
		(property "Footprint" "antmicro-footprints:C_0402_1005Metric"
			(at 0 0 0)
			(layer "F.Fab")
			(hide yes)
			(effects
				(font
					(size 1.27 1.27)
					(thickness 0.15)
				)
			)
		)
		(property "Datasheet" "https://www.yageo.com/en/Chart/Download/pdf/CC0402KRX5R6BB224"
			(at 0 0 0)
			(layer "F.Fab")
			(hide yes)
			(effects
				(font
					(size 1.27 1.27)
					(thickness 0.15)
				)
			)
		)
		(property "Author" "Antmicro"
			(at 0 0 0)
			(layer "B.Fab")
			(hide yes)
			(effects
				(font
					(size 1 1)
					(thickness 0.15)
				)
				(justify mirror)
			)
		)
		(property "Dielectric" ""
			(at 0 0 0)
			(layer "B.Fab")
			(hide yes)
			(effects
				(font
					(size 1 1)
					(thickness 0.15)
				)
				(justify mirror)
			)
		)
		(property "License" "Apache-2.0"
			(at 0 0 0)
			(layer "B.Fab")
			(hide yes)
			(effects
				(font
					(size 1 1)
					(thickness 0.15)
				)
				(justify mirror)
			)
		)
		(property "MPN" "CC0402KRX5R6BB224"
			(at 0 0 0)
			(layer "B.Fab")
			(hide yes)
			(effects
				(font
					(size 1 1)
					(thickness 0.15)
				)
				(justify mirror)
			)
		)
		(property "Manufacturer" "YAGEO"
			(at 0 0 0)
			(layer "B.Fab")
			(hide yes)
			(effects
				(font
					(size 1 1)
					(thickness 0.15)
				)
				(justify mirror)
			)
		)
		(property "Val" "220n"
			(at 0 0 0)
			(layer "B.Fab")
			(hide yes)
			(effects
				(font
					(size 1 1)
					(thickness 0.15)
				)
				(justify mirror)
			)
		)
		(property "Voltage" ""
			(at 0 0 0)
			(layer "B.Fab")
			(hide yes)
			(effects
				(font
					(size 1 1)
					(thickness 0.15)
				)
				(justify mirror)
			)
		)
		(sheetname "M.2")
		(sheetfile "m-2.kicad_sch")
		(attr smd)
		(fp_rect
			(start -0.925 0.47)
			(end 0.925 -0.47)
			(stroke
				(width 0.05)
				(type default)
			)
			(fill none)
			(layer "B.CrtYd")
		)
		(fp_line
			(start -0.494 -0.248)
			(end 0.504 -0.248)
			(stroke
				(width 0.15)
				(type solid)
			)
			(layer "B.Fab")
		)
		(fp_line
			(start -0.494 0.25)
			(end -0.494 -0.248)
			(stroke
				(width 0.15)
				(type solid)
			)
			(layer "B.Fab")
		)
		(fp_line
			(start 0.504 -0.248)
			(end 0.504 0.25)
			(stroke
				(width 0.15)
				(type solid)
			)
			(layer "B.Fab")
		)
		(fp_line
			(start 0.504 0.25)
			(end -0.494 0.25)
			(stroke
				(width 0.15)
				(type solid)
			)
			(layer "B.Fab")
		)
		(fp_text user "${REFERENCE}"
			(at -0.932 -3.168 180)
			(layer "B.Fab")
			(hide yes)
			(effects
				(font
					(size 0.7 0.7)
					(thickness 0.15)
				)
				(justify left bottom mirror)
			)
		)
		(fp_text user "Author: Antmicro"
			(at -0.932 -4.17 180)
			(layer "B.Fab")
			(hide yes)
			(effects
				(font
					(size 0.7 0.7)
					(thickness 0.15)
				)
				(justify left bottom mirror)
			)
		)
		(fp_text user "License: Apache-2.0"
			(at -0.932 -5.17 180)
			(layer "B.Fab")
			(hide yes)
			(effects
				(font
					(size 0.7 0.7)
					(thickness 0.15)
				)
				(justify left bottom mirror)
			)
		)
		(pad "1" smd roundrect
			(at -0.48 0)
			(size 0.59 0.64)
			(layers "B.Cu" "B.Paste" "B.Mask")
			(roundrect_rratio 0.25)
			(net 93 "/M.2/C_PCIE0_TX2_N")
			(pintype "passive")
		)
		(pad "2" smd roundrect
			(at 0.48 0)
			(size 0.59 0.64)
			(layers "B.Cu" "B.Paste" "B.Mask")
			(roundrect_rratio 0.25)
			(net 445 "PCIE0_TX2_N")
			(pintype "passive")
		)
	)
	(footprint "antmicro-footprints:C_0402_1005Metric"
		(layer "B.Cu")
		(at 71.7 103.35 -90)
		(descr "Capacitor SMD 0402")
		(tags "capacitor SMD 0402")
		(property "Reference" "C56"
			(at -1.1 0.53 90)
			(layer "B.SilkS")
			(effects
				(font
					(size 0.7 0.7)
					(thickness 0.15)
				)
				(justify left bottom mirror)
			)
		)
		(property "Value" "C_10u_0402"
			(at -1.022927 -2.155213 90)
			(layer "B.Fab")
			(effects
				(font
					(size 0.7 0.7)
					(thickness 0.15)
				)
				(justify left bottom mirror)
			)
		)
		(property "Footprint" "antmicro-footprints:C_0402_1005Metric"
			(at 0 0 -90)
			(layer "F.Fab")
			(hide yes)
			(effects
				(font
					(size 1.27 1.27)
					(thickness 0.15)
				)
			)
		)
		(property "Datasheet" "https://www.yageo.com/en/Chart/Download/pdf/CC0402MRX5R5BB106"
			(at 0 0 -90)
			(layer "F.Fab")
			(hide yes)
			(effects
				(font
					(size 1.27 1.27)
					(thickness 0.15)
				)
			)
		)
		(property "Author" "Antmicro"
			(at -31.65 175.05 0)
			(layer "B.Fab")
			(hide yes)
			(effects
				(font
					(size 1 1)
					(thickness 0.15)
				)
				(justify mirror)
			)
		)
		(property "Dielectric" ""
			(at -31.65 175.05 0)
			(layer "B.Fab")
			(hide yes)
			(effects
				(font
					(size 1 1)
					(thickness 0.15)
				)
				(justify mirror)
			)
		)
		(property "License" "Apache-2.0"
			(at -31.65 175.05 0)
			(layer "B.Fab")
			(hide yes)
			(effects
				(font
					(size 1 1)
					(thickness 0.15)
				)
				(justify mirror)
			)
		)
		(property "MPN" "CC0402MRX5R5BB106"
			(at -31.65 175.05 0)
			(layer "B.Fab")
			(hide yes)
			(effects
				(font
					(size 1 1)
					(thickness 0.15)
				)
				(justify mirror)
			)
		)
		(property "Manufacturer" "YAGEO"
			(at -31.65 175.05 0)
			(layer "B.Fab")
			(hide yes)
			(effects
				(font
					(size 1 1)
					(thickness 0.15)
				)
				(justify mirror)
			)
		)
		(property "Val" "10u"
			(at -31.65 175.05 0)
			(layer "B.Fab")
			(hide yes)
			(effects
				(font
					(size 1 1)
					(thickness 0.15)
				)
				(justify mirror)
			)
		)
		(property "Voltage" ""
			(at -31.65 175.05 0)
			(layer "B.Fab")
			(hide yes)
			(effects
				(font
					(size 1 1)
					(thickness 0.15)
				)
				(justify mirror)
			)
		)
		(sheetname "USB Debug, DP")
		(sheetfile "usb.kicad_sch")
		(attr smd)
		(fp_rect
			(start -0.925 0.47)
			(end 0.925 -0.47)
			(stroke
				(width 0.05)
				(type default)
			)
			(fill none)
			(layer "B.CrtYd")
		)
		(fp_line
			(start -0.494 0.25)
			(end -0.494 -0.248)
			(stroke
				(width 0.15)
				(type solid)
			)
			(layer "B.Fab")
		)
		(fp_line
			(start 0.504 0.25)
			(end -0.494 0.25)
			(stroke
				(width 0.15)
				(type solid)
			)
			(layer "B.Fab")
		)
		(fp_line
			(start -0.494 -0.248)
			(end 0.504 -0.248)
			(stroke
				(width 0.15)
				(type solid)
			)
			(layer "B.Fab")
		)
		(fp_line
			(start 0.504 -0.248)
			(end 0.504 0.25)
			(stroke
				(width 0.15)
				(type solid)
			)
			(layer "B.Fab")
		)
		(fp_text user "${REFERENCE}"
			(at -0.939 -4.599 90)
			(layer "B.Fab")
			(hide yes)
			(effects
				(font
					(size 0.7 0.7)
					(thickness 0.15)
				)
				(justify left bottom mirror)
			)
		)
		(fp_text user "Author: Antmicro"
			(at -0.939 -3.399 90)
			(layer "B.Fab")
			(hide yes)
			(effects
				(font
					(size 0.7 0.7)
					(thickness 0.15)
				)
				(justify left bottom mirror)
			)
		)
		(fp_text user "License: Apache-2.0"
			(at -0.939 -5.799 90)
			(layer "B.Fab")
			(hide yes)
			(effects
				(font
					(size 0.7 0.7)
					(thickness 0.15)
				)
				(justify left bottom mirror)
			)
		)
		(pad "1" smd roundrect
			(at -0.48 0 270)
			(size 0.59 0.64)
			(layers "B.Cu" "B.Paste" "B.Mask")
			(roundrect_rratio 0.25)
			(net 1 "GND")
			(pintype "passive")
		)
		(pad "2" smd roundrect
			(at 0.48 0 270)
			(size 0.59 0.64)
			(layers "B.Cu" "B.Paste" "B.Mask")
			(roundrect_rratio 0.25)
			(net 87 "+3V3")
			(pintype "passive")
		)
	)
	(footprint "antmicro-footprints:C_0402_1005Metric"
		(layer "B.Cu")
		(at 47.3 80.1 90)
		(descr "Capacitor SMD 0402")
		(tags "capacitor SMD 0402")
		(property "Reference" "C150"
			(at 3.525 -0.5 90)
			(layer "B.SilkS")
			(effects
				(font
					(size 0.7 0.7)
					(thickness 0.15)
				)
				(justify left bottom mirror)
			)
		)
		(property "Value" "C_1u_25V_0402"
			(at 0 -1.4 -90)
			(layer "B.Fab")
			(effects
				(font
					(size 0.7 0.7)
					(thickness 0.15)
				)
				(justify left bottom mirror)
			)
		)
		(property "Footprint" "antmicro-footprints:C_0402_1005Metric"
			(at 0 0 90)
			(layer "F.Fab")
			(hide yes)
			(effects
				(font
					(size 1.27 1.27)
					(thickness 0.15)
				)
			)
		)
		(property "Datasheet" "https://www.murata.com/products/productdetail?partno=GRM155R61E105KE11%23"
			(at 0 0 90)
			(layer "F.Fab")
			(hide yes)
			(effects
				(font
					(size 1.27 1.27)
					(thickness 0.15)
				)
			)
		)
		(property "Author" "Antmicro"
			(at 128.55 31.65 0)
			(layer "B.Fab")
			(hide yes)
			(effects
				(font
					(size 1 1)
					(thickness 0.15)
				)
				(justify mirror)
			)
		)
		(property "Dielectric" "X5R"
			(at 128.55 31.65 0)
			(layer "B.Fab")
			(hide yes)
			(effects
				(font
					(size 1 1)
					(thickness 0.15)
				)
				(justify mirror)
			)
		)
		(property "License" "Apache-2.0"
			(at 128.55 31.65 0)
			(layer "B.Fab")
			(hide yes)
			(effects
				(font
					(size 1 1)
					(thickness 0.15)
				)
				(justify mirror)
			)
		)
		(property "MPN" "GRM155R61E105KE11J"
			(at 128.55 31.65 0)
			(layer "B.Fab")
			(hide yes)
			(effects
				(font
					(size 1 1)
					(thickness 0.15)
				)
				(justify mirror)
			)
		)
		(property "Manufacturer" "Murata"
			(at 128.55 31.65 0)
			(layer "B.Fab")
			(hide yes)
			(effects
				(font
					(size 1 1)
					(thickness 0.15)
				)
				(justify mirror)
			)
		)
		(property "Val" "1u"
			(at 128.55 31.65 0)
			(layer "B.Fab")
			(hide yes)
			(effects
				(font
					(size 1 1)
					(thickness 0.15)
				)
				(justify mirror)
			)
		)
		(property "Voltage" "25V"
			(at 128.55 31.65 0)
			(layer "B.Fab")
			(hide yes)
			(effects
				(font
					(size 1 1)
					(thickness 0.15)
				)
				(justify mirror)
			)
		)
		(sheetname "Supply")
		(sheetfile "supply.kicad_sch")
		(attr smd)
		(fp_rect
			(start -0.925 0.47)
			(end 0.925 -0.47)
			(stroke
				(width 0.05)
				(type default)
			)
			(fill none)
			(layer "B.CrtYd")
		)
		(fp_line
			(start 0.504 -0.248)
			(end 0.504 0.25)
			(stroke
				(width 0.15)
				(type solid)
			)
			(layer "B.Fab")
		)
		(fp_line
			(start -0.494 -0.248)
			(end 0.504 -0.248)
			(stroke
				(width 0.15)
				(type solid)
			)
			(layer "B.Fab")
		)
		(fp_line
			(start 0.504 0.25)
			(end -0.494 0.25)
			(stroke
				(width 0.15)
				(type solid)
			)
			(layer "B.Fab")
		)
		(fp_line
			(start -0.494 0.25)
			(end -0.494 -0.248)
			(stroke
				(width 0.15)
				(type solid)
			)
			(layer "B.Fab")
		)
		(fp_text user "${REFERENCE}"
			(at -0.932 -3.168 -90)
			(layer "B.Fab")
			(hide yes)
			(effects
				(font
					(size 0.7 0.7)
					(thickness 0.15)
				)
				(justify left bottom mirror)
			)
		)
		(fp_text user "License: Apache-2.0"
			(at -0.932 -5.17 -90)
			(layer "B.Fab")
			(hide yes)
			(effects
				(font
					(size 0.7 0.7)
					(thickness 0.15)
				)
				(justify left bottom mirror)
			)
		)
		(fp_text user "Author: Antmicro"
			(at -0.932 -4.17 -90)
			(layer "B.Fab")
			(hide yes)
			(effects
				(font
					(size 0.7 0.7)
					(thickness 0.15)
				)
				(justify left bottom mirror)
			)
		)
		(pad "1" smd roundrect
			(at -0.48 0 90)
			(size 0.59 0.64)
			(layers "B.Cu" "B.Paste" "B.Mask")
			(roundrect_rratio 0.25)
			(net 135 "Net-(Q18-G)")
			(pintype "passive")
		)
		(pad "2" smd roundrect
			(at 0.48 0 90)
			(size 0.59 0.64)
			(layers "B.Cu" "B.Paste" "B.Mask")
			(roundrect_rratio 0.25)
			(net 328 "/Supply/VCC_IN")
			(pintype "passive")
		)
	)
	(footprint "antmicro-footprints:R_0402_1005Metric"
		(layer "B.Cu")
		(at 46.9 88.6375)
		(descr "Resistor SMD 0402")
		(tags "resistor SMD 0402")
		(property "Reference" "R142"
			(at 0.335 -3.4775 180)
			(layer "B.SilkS")
			(effects
				(font
					(size 0.7 0.7)
					(thickness 0.15)
				)
				(justify left bottom mirror)
			)
		)
		(property "Value" "R_49k9_0402"
			(at 0 -1.4 180)
			(layer "B.Fab")
			(effects
				(font
					(size 0.7 0.7)
					(thickness 0.15)
				)
				(justify left bottom mirror)
			)
		)
		(property "Footprint" "antmicro-footprints:R_0402_1005Metric"
			(at 0 0 0)
			(layer "F.Fab")
			(hide yes)
			(effects
				(font
					(size 1.27 1.27)
					(thickness 0.15)
				)
			)
		)
		(property "Datasheet" "https://www.bourns.com/docs/product-datasheets/cr.pdf"
			(at 0 0 0)
			(layer "F.Fab")
			(hide yes)
			(effects
				(font
					(size 1.27 1.27)
					(thickness 0.15)
				)
			)
		)
		(property "Author" "Antmicro"
			(at 0 0 0)
			(layer "B.Fab")
			(hide yes)
			(effects
				(font
					(size 1 1)
					(thickness 0.15)
				)
				(justify mirror)
			)
		)
		(property "License" "Apache-2.0"
			(at 0 0 0)
			(layer "B.Fab")
			(hide yes)
			(effects
				(font
					(size 1 1)
					(thickness 0.15)
				)
				(justify mirror)
			)
		)
		(property "MPN" "CR0402-FX-4992GLF"
			(at 0 0 0)
			(layer "B.Fab")
			(hide yes)
			(effects
				(font
					(size 1 1)
					(thickness 0.15)
				)
				(justify mirror)
			)
		)
		(property "Manufacturer" "Bourns"
			(at 0 0 0)
			(layer "B.Fab")
			(hide yes)
			(effects
				(font
					(size 1 1)
					(thickness 0.15)
				)
				(justify mirror)
			)
		)
		(property "Tolerance" "1%"
			(at 0 0 0)
			(layer "B.Fab")
			(hide yes)
			(effects
				(font
					(size 1 1)
					(thickness 0.15)
				)
				(justify mirror)
			)
		)
		(property "Val" "49k9"
			(at 0 0 0)
			(layer "B.Fab")
			(hide yes)
			(effects
				(font
					(size 1 1)
					(thickness 0.15)
				)
				(justify mirror)
			)
		)
		(sheetname "Ethernet")
		(sheetfile "ethernet.kicad_sch")
		(attr smd)
		(fp_rect
			(start -0.925 0.47)
			(end 0.925 -0.47)
			(stroke
				(width 0.05)
				(type default)
			)
			(fill none)
			(layer "B.CrtYd")
		)
		(fp_rect
			(start -0.5 0.25)
			(end 0.5 -0.25)
			(stroke
				(width 0.15)
				(type solid)
			)
			(fill none)
			(layer "B.Fab")
		)
		(fp_text user "Author: Antmicro"
			(at -0.95 -4.169 180)
			(layer "B.Fab")
			(hide yes)
			(effects
				(font
					(size 0.7 0.7)
					(thickness 0.15)
				)
				(justify left bottom mirror)
			)
		)
		(fp_text user "${REFERENCE}"
			(at -0.95 -3.168 180)
			(layer "B.Fab")
			(hide yes)
			(effects
				(font
					(size 0.7 0.7)
					(thickness 0.15)
				)
				(justify left bottom mirror)
			)
		)
		(fp_text user "License: Apache-2.0"
			(at -0.95 -5.169 180)
			(layer "B.Fab")
			(hide yes)
			(effects
				(font
					(size 0.7 0.7)
					(thickness 0.15)
				)
				(justify left bottom mirror)
			)
		)
		(pad "1" smd roundrect
			(at -0.48 0)
			(size 0.59 0.64)
			(layers "B.Cu" "B.Paste" "B.Mask")
			(roundrect_rratio 0.25)
			(net 499 "/Ethernet/VSS")
			(pintype "passive")
		)
		(pad "2" smd roundrect
			(at 0.48 0)
			(size 0.59 0.64)
			(layers "B.Cu" "B.Paste" "B.Mask")
			(roundrect_rratio 0.25)
			(net 566 "/Ethernet/REF")
			(pintype "passive")
		)
	)
	(footprint "antmicro-footprints:R_0402_1005Metric"
		(layer "B.Cu")
		(at 53.9 116.8 -90)
		(descr "Resistor SMD 0402")
		(tags "resistor SMD 0402")
		(property "Reference" "R127"
			(at -1.35 -2.7 90)
			(layer "B.SilkS")
			(effects
				(font
					(size 0.7 0.7)
					(thickness 0.15)
				)
				(justify left bottom mirror)
			)
		)
		(property "Value" "R_27R_0402"
			(at 0 -1.4 90)
			(layer "B.Fab")
			(effects
				(font
					(size 0.7 0.7)
					(thickness 0.15)
				)
				(justify left bottom mirror)
			)
		)
		(property "Footprint" "antmicro-footprints:R_0402_1005Metric"
			(at 0 0 -90)
			(layer "F.Fab")
			(hide yes)
			(effects
				(font
					(size 1.27 1.27)
					(thickness 0.15)
				)
			)
		)
		(property "Datasheet" "https://www.bourns.com/docs/product-datasheets/cr.pdf"
			(at 0 0 -90)
			(layer "F.Fab")
			(hide yes)
			(effects
				(font
					(size 1.27 1.27)
					(thickness 0.15)
				)
			)
		)
		(property "Author" "Antmicro"
			(at -62.9 170.7 0)
			(layer "B.Fab")
			(hide yes)
			(effects
				(font
					(size 1 1)
					(thickness 0.15)
				)
				(justify mirror)
			)
		)
		(property "License" "Apache-2.0"
			(at -62.9 170.7 0)
			(layer "B.Fab")
			(hide yes)
			(effects
				(font
					(size 1 1)
					(thickness 0.15)
				)
				(justify mirror)
			)
		)
		(property "MPN" "CR0402-FX-27R0GLF"
			(at -62.9 170.7 0)
			(layer "B.Fab")
			(hide yes)
			(effects
				(font
					(size 1 1)
					(thickness 0.15)
				)
				(justify mirror)
			)
		)
		(property "Manufacturer" "Bourns"
			(at -62.9 170.7 0)
			(layer "B.Fab")
			(hide yes)
			(effects
				(font
					(size 1 1)
					(thickness 0.15)
				)
				(justify mirror)
			)
		)
		(property "Tolerance" "1%"
			(at -62.9 170.7 0)
			(layer "B.Fab")
			(hide yes)
			(effects
				(font
					(size 1 1)
					(thickness 0.15)
				)
				(justify mirror)
			)
		)
		(property "Val" "27R"
			(at -62.9 170.7 0)
			(layer "B.Fab")
			(hide yes)
			(effects
				(font
					(size 1 1)
					(thickness 0.15)
				)
				(justify mirror)
			)
		)
		(sheetname "USB Debug, DP")
		(sheetfile "usb.kicad_sch")
		(attr smd)
		(fp_rect
			(start -0.925 0.47)
			(end 0.925 -0.47)
			(stroke
				(width 0.05)
				(type default)
			)
			(fill none)
			(layer "B.CrtYd")
		)
		(fp_rect
			(start -0.5 0.25)
			(end 0.5 -0.25)
			(stroke
				(width 0.15)
				(type solid)
			)
			(fill none)
			(layer "B.Fab")
		)
		(fp_text user "Author: Antmicro"
			(at -0.95 -4.169 90)
			(layer "B.Fab")
			(hide yes)
			(effects
				(font
					(size 0.7 0.7)
					(thickness 0.15)
				)
				(justify left bottom mirror)
			)
		)
		(fp_text user "${REFERENCE}"
			(at -0.95 -3.168 90)
			(layer "B.Fab")
			(hide yes)
			(effects
				(font
					(size 0.7 0.7)
					(thickness 0.15)
				)
				(justify left bottom mirror)
			)
		)
		(fp_text user "License: Apache-2.0"
			(at -0.95 -5.169 90)
			(layer "B.Fab")
			(hide yes)
			(effects
				(font
					(size 0.7 0.7)
					(thickness 0.15)
				)
				(justify left bottom mirror)
			)
		)
		(pad "1" smd roundrect
			(at -0.48 0 270)
			(size 0.59 0.64)
			(layers "B.Cu" "B.Paste" "B.Mask")
			(roundrect_rratio 0.25)
			(net 313 "/USB Debug, DP/USB_FTDI_P")
			(pintype "passive")
		)
		(pad "2" smd roundrect
			(at 0.48 0 270)
			(size 0.59 0.64)
			(layers "B.Cu" "B.Paste" "B.Mask")
			(roundrect_rratio 0.25)
			(net 613 "/USB Debug, DP/USBC3_D_P")
			(pintype "passive")
		)
	)
	(footprint "antmicro-footprints:R_0402_1005Metric"
		(layer "B.Cu")
		(at 88.7 106.6 -90)
		(descr "Resistor SMD 0402")
		(tags "resistor SMD 0402")
		(property "Reference" "R193"
			(at -4.1 3.8 90)
			(layer "B.SilkS")
			(effects
				(font
					(size 0.7 0.7)
					(thickness 0.15)
				)
				(justify left bottom mirror)
			)
		)
		(property "Value" "R_10k_0402"
			(at 0 -1.4 90)
			(layer "B.Fab")
			(effects
				(font
					(size 0.7 0.7)
					(thickness 0.15)
				)
				(justify left bottom mirror)
			)
		)
		(property "Footprint" "antmicro-footprints:R_0402_1005Metric"
			(at 0 0 -90)
			(layer "F.Fab")
			(hide yes)
			(effects
				(font
					(size 1.27 1.27)
					(thickness 0.15)
				)
			)
		)
		(property "Datasheet" "https://www.bourns.com/docs/product-datasheets/cr.pdf"
			(at 0 0 -90)
			(layer "F.Fab")
			(hide yes)
			(effects
				(font
					(size 1.27 1.27)
					(thickness 0.15)
				)
			)
		)
		(property "Author" "Antmicro"
			(at -17.9 195.3 0)
			(layer "B.Fab")
			(hide yes)
			(effects
				(font
					(size 1 1)
					(thickness 0.15)
				)
				(justify mirror)
			)
		)
		(property "License" "Apache-2.0"
			(at -17.9 195.3 0)
			(layer "B.Fab")
			(hide yes)
			(effects
				(font
					(size 1 1)
					(thickness 0.15)
				)
				(justify mirror)
			)
		)
		(property "MPN" "CR0402-FX-1002GLF"
			(at -17.9 195.3 0)
			(layer "B.Fab")
			(hide yes)
			(effects
				(font
					(size 1 1)
					(thickness 0.15)
				)
				(justify mirror)
			)
		)
		(property "Manufacturer" "Bourns"
			(at -17.9 195.3 0)
			(layer "B.Fab")
			(hide yes)
			(effects
				(font
					(size 1 1)
					(thickness 0.15)
				)
				(justify mirror)
			)
		)
		(property "Tolerance" "1%"
			(at -17.9 195.3 0)
			(layer "B.Fab")
			(hide yes)
			(effects
				(font
					(size 1 1)
					(thickness 0.15)
				)
				(justify mirror)
			)
		)
		(property "Val" "10k"
			(at -17.9 195.3 0)
			(layer "B.Fab")
			(hide yes)
			(effects
				(font
					(size 1 1)
					(thickness 0.15)
				)
				(justify mirror)
			)
		)
		(sheetname "CSI")
		(sheetfile "csi.kicad_sch")
		(attr smd exclude_from_pos_files exclude_from_bom dnp)
		(fp_rect
			(start -0.925 0.47)
			(end 0.925 -0.47)
			(stroke
				(width 0.05)
				(type default)
			)
			(fill none)
			(layer "B.CrtYd")
		)
		(fp_rect
			(start -0.5 0.25)
			(end 0.5 -0.25)
			(stroke
				(width 0.15)
				(type solid)
			)
			(fill none)
			(layer "B.Fab")
		)
		(fp_text user "${REFERENCE}"
			(at -0.95 -3.168 90)
			(layer "B.Fab")
			(hide yes)
			(effects
				(font
					(size 0.7 0.7)
					(thickness 0.15)
				)
				(justify left bottom mirror)
			)
		)
		(fp_text user "Author: Antmicro"
			(at -0.95 -4.169 90)
			(layer "B.Fab")
			(hide yes)
			(effects
				(font
					(size 0.7 0.7)
					(thickness 0.15)
				)
				(justify left bottom mirror)
			)
		)
		(fp_text user "License: Apache-2.0"
			(at -0.95 -5.169 90)
			(layer "B.Fab")
			(hide yes)
			(effects
				(font
					(size 0.7 0.7)
					(thickness 0.15)
				)
				(justify left bottom mirror)
			)
		)
		(pad "1" smd roundrect
			(at -0.48 0 270)
			(size 0.59 0.64)
			(layers "B.Cu" "B.Paste" "B.Mask")
			(roundrect_rratio 0.25)
			(net 322 "CSIA_PEN")
			(pintype "passive")
		)
		(pad "2" smd roundrect
			(at 0.48 0 270)
			(size 0.59 0.64)
			(layers "B.Cu" "B.Paste" "B.Mask")
			(roundrect_rratio 0.25)
			(net 87 "+3V3")
			(pintype "passive")
		)
	)
	(footprint "antmicro-footprints:R_0402_1005Metric"
		(layer "B.Cu")
		(at 43.77 123.47 90)
		(descr "Resistor SMD 0402")
		(tags "resistor SMD 0402")
		(property "Reference" "R72"
			(at -2.18 -0.82 -90)
			(layer "B.SilkS")
			(effects
				(font
					(size 0.7 0.7)
					(thickness 0.15)
				)
				(justify left bottom mirror)
			)
		)
		(property "Value" "R_200R_0402"
			(at 0 -1.4 -90)
			(layer "B.Fab")
			(effects
				(font
					(size 0.7 0.7)
					(thickness 0.15)
				)
				(justify left bottom mirror)
			)
		)
		(property "Footprint" "antmicro-footprints:R_0402_1005Metric"
			(at 0 0 90)
			(layer "F.Fab")
			(hide yes)
			(effects
				(font
					(size 1.27 1.27)
					(thickness 0.15)
				)
			)
		)
		(property "Datasheet" "https://www.bourns.com/docs/product-datasheets/cr.pdf"
			(at 0 0 90)
			(layer "F.Fab")
			(hide yes)
			(effects
				(font
					(size 1.27 1.27)
					(thickness 0.15)
				)
			)
		)
		(property "Author" "Antmicro"
			(at 167.24 79.7 0)
			(layer "B.Fab")
			(hide yes)
			(effects
				(font
					(size 1 1)
					(thickness 0.15)
				)
				(justify mirror)
			)
		)
		(property "License" "Apache-2.0"
			(at 167.24 79.7 0)
			(layer "B.Fab")
			(hide yes)
			(effects
				(font
					(size 1 1)
					(thickness 0.15)
				)
				(justify mirror)
			)
		)
		(property "MPN" "CR0402-FX-2000GLF"
			(at 167.24 79.7 0)
			(layer "B.Fab")
			(hide yes)
			(effects
				(font
					(size 1 1)
					(thickness 0.15)
				)
				(justify mirror)
			)
		)
		(property "Manufacturer" "Bourns"
			(at 167.24 79.7 0)
			(layer "B.Fab")
			(hide yes)
			(effects
				(font
					(size 1 1)
					(thickness 0.15)
				)
				(justify mirror)
			)
		)
		(property "Tolerance" "1%"
			(at 167.24 79.7 0)
			(layer "B.Fab")
			(hide yes)
			(effects
				(font
					(size 1 1)
					(thickness 0.15)
				)
				(justify mirror)
			)
		)
		(property "Val" "200R"
			(at 167.24 79.7 0)
			(layer "B.Fab")
			(hide yes)
			(effects
				(font
					(size 1 1)
					(thickness 0.15)
				)
				(justify mirror)
			)
		)
		(sheetname "USB Debug, DP")
		(sheetfile "usb.kicad_sch")
		(attr smd)
		(fp_rect
			(start -0.925 0.47)
			(end 0.925 -0.47)
			(stroke
				(width 0.05)
				(type default)
			)
			(fill none)
			(layer "B.CrtYd")
		)
		(fp_rect
			(start -0.5 0.25)
			(end 0.5 -0.25)
			(stroke
				(width 0.15)
				(type solid)
			)
			(fill none)
			(layer "B.Fab")
		)
		(fp_text user "Author: Antmicro"
			(at -0.95 -4.169 -90)
			(layer "B.Fab")
			(hide yes)
			(effects
				(font
					(size 0.7 0.7)
					(thickness 0.15)
				)
				(justify left bottom mirror)
			)
		)
		(fp_text user "License: Apache-2.0"
			(at -0.95 -5.169 -90)
			(layer "B.Fab")
			(hide yes)
			(effects
				(font
					(size 0.7 0.7)
					(thickness 0.15)
				)
				(justify left bottom mirror)
			)
		)
		(fp_text user "${REFERENCE}"
			(at -0.95 -3.168 -90)
			(layer "B.Fab")
			(hide yes)
			(effects
				(font
					(size 0.7 0.7)
					(thickness 0.15)
				)
				(justify left bottom mirror)
			)
		)
		(pad "1" smd roundrect
			(at -0.48 0 90)
			(size 0.59 0.64)
			(layers "B.Cu" "B.Paste" "B.Mask")
			(roundrect_rratio 0.25)
			(net 142 "Net-(D2-A)")
			(pintype "passive")
		)
		(pad "2" smd roundrect
			(at 0.48 0 90)
			(size 0.59 0.64)
			(layers "B.Cu" "B.Paste" "B.Mask")
			(roundrect_rratio 0.25)
			(net 185 "/USB Debug, DP/FTDI_3V3")
			(pintype "passive")
		)
	)
	(footprint "antmicro-footprints:R_0603_1608Metric"
		(layer "B.Cu")
		(at 50.05 91.35)
		(descr "Resistor SMD 0603")
		(tags "resistor SMD 0603")
		(property "Reference" "R196"
			(at -1.1 0 180)
			(layer "B.SilkS")
			(effects
				(font
					(size 0.7 0.7)
					(thickness 0.15)
				)
				(justify left bottom mirror)
			)
		)
		(property "Value" "R_63R4_0603"
			(at 0 -1.6 180)
			(layer "B.Fab")
			(effects
				(font
					(size 0.7 0.7)
					(thickness 0.15)
				)
				(justify left bottom mirror)
			)
		)
		(property "Footprint" "antmicro-footprints:R_0603_1608Metric"
			(at 0 0 0)
			(layer "F.Fab")
			(hide yes)
			(effects
				(font
					(size 1.27 1.27)
					(thickness 0.15)
				)
			)
		)
		(property "Datasheet" "https://www.bourns.com/docs/product-datasheets/cr.pdf"
			(at 0 0 0)
			(layer "F.Fab")
			(hide yes)
			(effects
				(font
					(size 1.27 1.27)
					(thickness 0.15)
				)
			)
		)
		(property "Author" "Antmicro"
			(at 0 0 0)
			(layer "B.Fab")
			(hide yes)
			(effects
				(font
					(size 1 1)
					(thickness 0.15)
				)
				(justify mirror)
			)
		)
		(property "License" "Apache-2.0"
			(at 0 0 0)
			(layer "B.Fab")
			(hide yes)
			(effects
				(font
					(size 1 1)
					(thickness 0.15)
				)
				(justify mirror)
			)
		)
		(property "MPN" "CR0603-FX-63R4ELF"
			(at 0 0 0)
			(layer "B.Fab")
			(hide yes)
			(effects
				(font
					(size 1 1)
					(thickness 0.15)
				)
				(justify mirror)
			)
		)
		(property "Manufacturer" "Bourns"
			(at 0 0 0)
			(layer "B.Fab")
			(hide yes)
			(effects
				(font
					(size 1 1)
					(thickness 0.15)
				)
				(justify mirror)
			)
		)
		(property "Tolerance" "1%"
			(at 0 0 0)
			(layer "B.Fab")
			(hide yes)
			(effects
				(font
					(size 1 1)
					(thickness 0.15)
				)
				(justify mirror)
			)
		)
		(property "Val" "63R4"
			(at 0 0 0)
			(layer "B.Fab")
			(hide yes)
			(effects
				(font
					(size 1 1)
					(thickness 0.15)
				)
				(justify mirror)
			)
		)
		(sheetname "Ethernet")
		(sheetfile "ethernet.kicad_sch")
		(attr smd)
		(fp_line
			(start 0.15 -0.4)
			(end -0.15 -0.4)
			(stroke
				(width 0.15)
				(type solid)
			)
			(layer "B.SilkS")
		)
		(fp_line
			(start 0.15 0.4)
			(end -0.15 0.4)
			(stroke
				(width 0.15)
				(type solid)
			)
			(layer "B.SilkS")
		)
		(fp_rect
			(start -1.25 0.65)
			(end 1.25 -0.65)
			(stroke
				(width 0.05)
				(type solid)
			)
			(fill none)
			(layer "B.CrtYd")
		)
		(fp_rect
			(start -0.8 0.4)
			(end 0.8 -0.4)
			(stroke
				(width 0.15)
				(type solid)
			)
			(fill none)
			(layer "B.Fab")
		)
		(fp_text user "Author: Antmicro"
			(at -1.25 -4.9 180)
			(layer "B.Fab")
			(hide yes)
			(effects
				(font
					(size 0.7 0.7)
					(thickness 0.15)
				)
				(justify left bottom mirror)
			)
		)
		(fp_text user "${REFERENCE}"
			(at -1.25 -3.898 180)
			(layer "B.Fab")
			(hide yes)
			(effects
				(font
					(size 0.7 0.7)
					(thickness 0.15)
				)
				(justify left bottom mirror)
			)
		)
		(fp_text user "License: Apache-2.0"
			(at -1.25 -5.9 180)
			(layer "B.Fab")
			(hide yes)
			(effects
				(font
					(size 0.7 0.7)
					(thickness 0.15)
				)
				(justify left bottom mirror)
			)
		)
		(pad "1" smd roundrect
			(at -0.7 0)
			(size 0.8 1)
			(layers "B.Cu" "B.Paste" "B.Mask")
			(roundrect_rratio 0.2)
			(net 499 "/Ethernet/VSS")
			(pintype "passive")
		)
		(pad "2" smd roundrect
			(at 0.7 0)
			(size 0.8 1)
			(layers "B.Cu" "B.Paste" "B.Mask")
			(roundrect_rratio 0.2)
			(net 568 "/Ethernet/CLSA")
			(pintype "passive")
		)
	)
	(footprint "antmicro-footprints:C_0603_1608Metric"
		(layer "B.Cu")
		(at 114.5 95 180)
		(descr "Capacitor SMD 0603")
		(tags "capacitor 0603")
		(property "Reference" "C24"
			(at -1.1 -1.5 0)
			(layer "B.SilkS")
			(effects
				(font
					(size 0.7 0.7)
					(thickness 0.15)
				)
				(justify left bottom mirror)
			)
		)
		(property "Value" "C_10u_0603"
			(at 0 -1.6 0)
			(layer "B.Fab")
			(effects
				(font
					(size 0.7 0.7)
					(thickness 0.15)
				)
				(justify left bottom mirror)
			)
		)
		(property "Footprint" "antmicro-footprints:C_0603_1608Metric"
			(at 0 0 180)
			(layer "F.Fab")
			(hide yes)
			(effects
				(font
					(size 1.27 1.27)
					(thickness 0.15)
				)
			)
		)
		(property "Datasheet" "https://www.murata.com/products/productdetail?partno=GRM188R61A106KE69%23"
			(at 0 0 180)
			(layer "F.Fab")
			(hide yes)
			(effects
				(font
					(size 1.27 1.27)
					(thickness 0.15)
				)
			)
		)
		(property "Author" "Antmicro"
			(at 229 190 0)
			(layer "B.Fab")
			(hide yes)
			(effects
				(font
					(size 1 1)
					(thickness 0.15)
				)
				(justify mirror)
			)
		)
		(property "Dielectric" "template_dielectric"
			(at 229 190 0)
			(layer "B.Fab")
			(hide yes)
			(effects
				(font
					(size 1 1)
					(thickness 0.15)
				)
				(justify mirror)
			)
		)
		(property "License" "Apache-2.0"
			(at 229 190 0)
			(layer "B.Fab")
			(hide yes)
			(effects
				(font
					(size 1 1)
					(thickness 0.15)
				)
				(justify mirror)
			)
		)
		(property "MPN" "GRM188R61A106KE69D"
			(at 229 190 0)
			(layer "B.Fab")
			(hide yes)
			(effects
				(font
					(size 1 1)
					(thickness 0.15)
				)
				(justify mirror)
			)
		)
		(property "Manufacturer" "Murata"
			(at 229 190 0)
			(layer "B.Fab")
			(hide yes)
			(effects
				(font
					(size 1 1)
					(thickness 0.15)
				)
				(justify mirror)
			)
		)
		(property "Val" "10u"
			(at 229 190 0)
			(layer "B.Fab")
			(hide yes)
			(effects
				(font
					(size 1 1)
					(thickness 0.15)
				)
				(justify mirror)
			)
		)
		(property "Voltage" ""
			(at 229 190 0)
			(layer "B.Fab")
			(hide yes)
			(effects
				(font
					(size 1 1)
					(thickness 0.15)
				)
				(justify mirror)
			)
		)
		(sheetname "M.2")
		(sheetfile "m-2.kicad_sch")
		(attr smd)
		(fp_line
			(start 0.15 0.4)
			(end -0.15 0.4)
			(stroke
				(width 0.15)
				(type solid)
			)
			(layer "B.SilkS")
		)
		(fp_line
			(start 0.15 -0.4)
			(end -0.15 -0.4)
			(stroke
				(width 0.15)
				(type solid)
			)
			(layer "B.SilkS")
		)
		(fp_rect
			(start -1.25 0.65)
			(end 1.25 -0.65)
			(stroke
				(width 0.05)
				(type solid)
			)
			(fill none)
			(layer "B.CrtYd")
		)
		(fp_rect
			(start -0.8 0.4)
			(end 0.8 -0.4)
			(stroke
				(width 0.15)
				(type solid)
			)
			(fill none)
			(layer "B.Fab")
		)
		(fp_text user "License: Apache-2.0"
			(at -1.682 -5.895 0)
			(layer "B.Fab")
			(hide yes)
			(effects
				(font
					(size 0.7 0.7)
					(thickness 0.15)
				)
				(justify left bottom mirror)
			)
		)
		(fp_text user "Author: Antmicro"
			(at -1.682 -4.894 0)
			(layer "B.Fab")
			(hide yes)
			(effects
				(font
					(size 0.7 0.7)
					(thickness 0.15)
				)
				(justify left bottom mirror)
			)
		)
		(fp_text user "${REFERENCE}"
			(at -1.682 -3.895 0)
			(layer "B.Fab")
			(hide yes)
			(effects
				(font
					(size 0.7 0.7)
					(thickness 0.15)
				)
				(justify left bottom mirror)
			)
		)
		(pad "1" smd roundrect
			(at -0.7 0 180)
			(size 0.8 1)
			(layers "B.Cu" "B.Paste" "B.Mask")
			(roundrect_rratio 0.2)
			(net 635 "/M.2/3V3_M2")
			(pintype "passive")
		)
		(pad "2" smd roundrect
			(at 0.7 0 180)
			(size 0.8 1)
			(layers "B.Cu" "B.Paste" "B.Mask")
			(roundrect_rratio 0.2)
			(net 1 "GND")
			(pintype "passive")
		)
	)
	(footprint "antmicro-footprints:SOT-523"
		(layer "B.Cu")
		(at 47.825 116.75)
		(property "Reference" "Q20"
			(at -15.065 10.38 0)
			(layer "B.SilkS")
			(effects
				(font
					(size 0.7 0.7)
					(thickness 0.15)
				)
				(justify right bottom mirror)
			)
		)
		(property "Value" "PJE138K"
			(at 0.1 -1.824 0)
			(layer "B.Fab")
			(effects
				(font
					(size 0.7 0.7)
					(thickness 0.15)
				)
				(justify right bottom mirror)
			)
		)
		(property "Footprint" "antmicro-footprints:SOT-523"
			(at 0 0 0)
			(layer "F.Fab")
			(hide yes)
			(effects
				(font
					(size 1.27 1.27)
					(thickness 0.15)
				)
			)
		)
		(property "Datasheet" "https://www.mouser.com/datasheet/2/1057/PJE138K-1876698.pdf"
			(at 0 0 0)
			(layer "F.Fab")
			(hide yes)
			(effects
				(font
					(size 1.27 1.27)
					(thickness 0.15)
				)
			)
		)
		(property "Author" "Antmicro"
			(at 0 0 0)
			(layer "B.Fab")
			(hide yes)
			(effects
				(font
					(size 1 1)
					(thickness 0.15)
				)
				(justify mirror)
			)
		)
		(property "License" "Apache-2.0"
			(at 0 0 0)
			(layer "B.Fab")
			(hide yes)
			(effects
				(font
					(size 1 1)
					(thickness 0.15)
				)
				(justify mirror)
			)
		)
		(property "MPN" "PJE138K_R1_00001"
			(at 0 0 0)
			(layer "B.Fab")
			(hide yes)
			(effects
				(font
					(size 1 1)
					(thickness 0.15)
				)
				(justify mirror)
			)
		)
		(property "Manufacturer" "PANJIT"
			(at 0 0 0)
			(layer "B.Fab")
			(hide yes)
			(effects
				(font
					(size 1 1)
					(thickness 0.15)
				)
				(justify mirror)
			)
		)
		(sheetname "USB Debug, DP")
		(sheetfile "usb.kicad_sch")
		(attr smd)
		(fp_line
			(start -0.927 0.351)
			(end -0.927 0.051)
			(stroke
				(width 0.15)
				(type solid)
			)
			(layer "B.SilkS")
		)
		(fp_line
			(start -0.725 0.551)
			(end -0.927 0.351)
			(stroke
				(width 0.15)
				(type solid)
			)
			(layer "B.SilkS")
		)
		(fp_line
			(start -0.277 0.551)
			(end -0.725 0.551)
			(stroke
				(width 0.15)
				(type solid)
			)
			(layer "B.SilkS")
		)
		(fp_line
			(start -0.277 0.75)
			(end -0.277 0.551)
			(stroke
				(width 0.15)
				(type solid)
			)
			(layer "B.SilkS")
		)
		(fp_circle
			(center -0.9652 -0.9652)
			(end -0.9152 -0.9652)
			(stroke
				(width 0.15)
				(type solid)
			)
			(fill solid)
			(layer "B.SilkS")
		)
		(fp_line
			(start -1.12 -1.15)
			(end -1.12 1.16)
			(stroke
				(width 0.05)
				(type solid)
			)
			(layer "B.CrtYd")
		)
		(fp_line
			(start 1.1 -1.15)
			(end -1.12 -1.15)
			(stroke
				(width 0.05)
				(type solid)
			)
			(layer "B.CrtYd")
		)
		(fp_line
			(start 1.1 -1.15)
			(end 1.1 1.16)
			(stroke
				(width 0.05)
				(type solid)
			)
			(layer "B.CrtYd")
		)
		(fp_line
			(start 1.1 1.16)
			(end -1.12 1.16)
			(stroke
				(width 0.05)
				(type solid)
			)
			(layer "B.CrtYd")
		)
		(fp_line
			(start -0.802 -0.424)
			(end -0.802 0.276)
			(stroke
				(width 0.15)
				(type solid)
			)
			(layer "B.Fab")
		)
		(fp_line
			(start -0.802 -0.424)
			(end 0.8 -0.424)
			(stroke
				(width 0.15)
				(type solid)
			)
			(layer "B.Fab")
		)
		(fp_line
			(start -0.802 0.276)
			(end -0.652 0.425)
			(stroke
				(width 0.15)
				(type solid)
			)
			(layer "B.Fab")
		)
		(fp_line
			(start -0.652 0.425)
			(end 0.8 0.425)
			(stroke
				(width 0.15)
				(type solid)
			)
			(layer "B.Fab")
		)
		(fp_line
			(start 0.8 -0.424)
			(end 0.8 0.425)
			(stroke
				(width 0.15)
				(type solid)
			)
			(layer "B.Fab")
		)
		(fp_circle
			(center -0.9652 -0.9652)
			(end -0.9144 -0.9652)
			(stroke
				(width 0.15)
				(type solid)
			)
			(fill none)
			(layer "B.Fab")
		)
		(fp_text user "License: Apache-2.0"
			(at -1.12 -5.024 0)
			(layer "B.Fab")
			(hide yes)
			(effects
				(font
					(size 0.7 0.7)
					(thickness 0.15)
				)
				(justify right bottom mirror)
			)
		)
		(fp_text user "${REFERENCE}"
			(at -1.12 -3.824 0)
			(layer "B.Fab")
			(hide yes)
			(effects
				(font
					(size 0.7 0.7)
					(thickness 0.15)
				)
				(justify right bottom mirror)
			)
		)
		(fp_text user "Author: Antmicro"
			(at -1.12 -6.224 0)
			(layer "B.Fab")
			(hide yes)
			(effects
				(font
					(size 0.7 0.7)
					(thickness 0.15)
				)
				(justify right bottom mirror)
			)
		)
		(pad "1" smd rect
			(at -0.5 -0.65)
			(size 0.4 0.51)
			(layers "B.Cu" "B.Paste" "B.Mask")
			(net 86 "~{RESET}")
			(pinfunction "G")
			(pintype "passive")
		)
		(pad "2" smd rect
			(at 0.498 -0.65)
			(size 0.4 0.51)
			(layers "B.Cu" "B.Paste" "B.Mask")
			(net 1 "GND")
			(pinfunction "S")
			(pintype "passive")
		)
		(pad "3" smd rect
			(at 0 0.652)
			(size 0.4 0.51)
			(layers "B.Cu" "B.Paste" "B.Mask")
			(net 397 "/USB Debug, DP/FTDI_CBUS_EN")
			(pinfunction "D")
			(pintype "passive")
		)
	)
	(footprint "antmicro-footprints:R_0402_1005Metric"
		(layer "B.Cu")
		(at 96.5 98.43)
		(descr "Resistor SMD 0402")
		(tags "resistor SMD 0402")
		(property "Reference" "R168"
			(at 1.15 -0.43 180)
			(layer "B.SilkS")
			(effects
				(font
					(size 0.7 0.7)
					(thickness 0.15)
				)
				(justify left bottom mirror)
			)
		)
		(property "Value" "R_0R_0402"
			(at 0 -1.4 180)
			(layer "B.Fab")
			(effects
				(font
					(size 0.7 0.7)
					(thickness 0.15)
				)
				(justify left bottom mirror)
			)
		)
		(property "Footprint" "antmicro-footprints:R_0402_1005Metric"
			(at 0 0 0)
			(layer "F.Fab")
			(hide yes)
			(effects
				(font
					(size 1.27 1.27)
					(thickness 0.15)
				)
			)
		)
		(property "Datasheet" "https://industrial.panasonic.com/cdbs/www-data/pdf/RDA0000/AOA0000C301.pdf"
			(at 0 0 0)
			(layer "F.Fab")
			(hide yes)
			(effects
				(font
					(size 1.27 1.27)
					(thickness 0.15)
				)
			)
		)
		(property "Author" "Antmicro"
			(at 0 0 0)
			(layer "B.Fab")
			(hide yes)
			(effects
				(font
					(size 1 1)
					(thickness 0.15)
				)
				(justify mirror)
			)
		)
		(property "Current" "1A"
			(at 0 0 0)
			(layer "B.Fab")
			(hide yes)
			(effects
				(font
					(size 1 1)
					(thickness 0.15)
				)
				(justify mirror)
			)
		)
		(property "License" "Apache-2.0"
			(at 0 0 0)
			(layer "B.Fab")
			(hide yes)
			(effects
				(font
					(size 1 1)
					(thickness 0.15)
				)
				(justify mirror)
			)
		)
		(property "MPN" "ERJ2GE0R00X"
			(at 0 0 0)
			(layer "B.Fab")
			(hide yes)
			(effects
				(font
					(size 1 1)
					(thickness 0.15)
				)
				(justify mirror)
			)
		)
		(property "Manufacturer" "Panasonic"
			(at 0 0 0)
			(layer "B.Fab")
			(hide yes)
			(effects
				(font
					(size 1 1)
					(thickness 0.15)
				)
				(justify mirror)
			)
		)
		(property "Tolerance" ""
			(at 0 0 0)
			(layer "B.Fab")
			(hide yes)
			(effects
				(font
					(size 1 1)
					(thickness 0.15)
				)
				(justify mirror)
			)
		)
		(property "Val" "0R"
			(at 0 0 0)
			(layer "B.Fab")
			(hide yes)
			(effects
				(font
					(size 1 1)
					(thickness 0.15)
				)
				(justify mirror)
			)
		)
		(sheetname "CSI")
		(sheetfile "csi.kicad_sch")
		(attr smd)
		(fp_rect
			(start -0.925 0.47)
			(end 0.925 -0.47)
			(stroke
				(width 0.05)
				(type default)
			)
			(fill none)
			(layer "B.CrtYd")
		)
		(fp_rect
			(start -0.5 0.25)
			(end 0.5 -0.25)
			(stroke
				(width 0.15)
				(type solid)
			)
			(fill none)
			(layer "B.Fab")
		)
		(fp_text user "License: Apache-2.0"
			(at -0.95 -5.169 180)
			(layer "B.Fab")
			(hide yes)
			(effects
				(font
					(size 0.7 0.7)
					(thickness 0.15)
				)
				(justify left bottom mirror)
			)
		)
		(fp_text user "${REFERENCE}"
			(at -0.95 -3.168 180)
			(layer "B.Fab")
			(hide yes)
			(effects
				(font
					(size 0.7 0.7)
					(thickness 0.15)
				)
				(justify left bottom mirror)
			)
		)
		(fp_text user "Author: Antmicro"
			(at -0.95 -4.169 180)
			(layer "B.Fab")
			(hide yes)
			(effects
				(font
					(size 0.7 0.7)
					(thickness 0.15)
				)
				(justify left bottom mirror)
			)
		)
		(pad "1" smd roundrect
			(at -0.48 0)
			(size 0.59 0.64)
			(layers "B.Cu" "B.Paste" "B.Mask")
			(roundrect_rratio 0.25)
			(net 1 "GND")
			(pintype "passive")
		)
		(pad "2" smd roundrect
			(at 0.48 0)
			(size 0.59 0.64)
			(layers "B.Cu" "B.Paste" "B.Mask")
			(roundrect_rratio 0.25)
			(net 325 "/CSI/I2C_MUX_A0")
			(pintype "passive")
		)
	)
	(footprint "antmicro-footprints:R_0402_1005Metric"
		(layer "B.Cu")
		(at 100.175 104.625)
		(descr "Resistor SMD 0402")
		(tags "resistor SMD 0402")
		(property "Reference" "R171"
			(at 1.135 1.325 180)
			(layer "B.SilkS")
			(effects
				(font
					(size 0.7 0.7)
					(thickness 0.15)
				)
				(justify left bottom mirror)
			)
		)
		(property "Value" "R_0R_0402"
			(at 0 -1.4 180)
			(layer "B.Fab")
			(effects
				(font
					(size 0.7 0.7)
					(thickness 0.15)
				)
				(justify left bottom mirror)
			)
		)
		(property "Footprint" "antmicro-footprints:R_0402_1005Metric"
			(at 0 0 0)
			(layer "F.Fab")
			(hide yes)
			(effects
				(font
					(size 1.27 1.27)
					(thickness 0.15)
				)
			)
		)
		(property "Datasheet" "https://industrial.panasonic.com/cdbs/www-data/pdf/RDA0000/AOA0000C301.pdf"
			(at 0 0 0)
			(layer "F.Fab")
			(hide yes)
			(effects
				(font
					(size 1.27 1.27)
					(thickness 0.15)
				)
			)
		)
		(property "Author" "Antmicro"
			(at 0 0 0)
			(layer "B.Fab")
			(hide yes)
			(effects
				(font
					(size 1 1)
					(thickness 0.15)
				)
				(justify mirror)
			)
		)
		(property "Current" "1A"
			(at 0 0 0)
			(layer "B.Fab")
			(hide yes)
			(effects
				(font
					(size 1 1)
					(thickness 0.15)
				)
				(justify mirror)
			)
		)
		(property "License" "Apache-2.0"
			(at 0 0 0)
			(layer "B.Fab")
			(hide yes)
			(effects
				(font
					(size 1 1)
					(thickness 0.15)
				)
				(justify mirror)
			)
		)
		(property "MPN" "ERJ2GE0R00X"
			(at 0 0 0)
			(layer "B.Fab")
			(hide yes)
			(effects
				(font
					(size 1 1)
					(thickness 0.15)
				)
				(justify mirror)
			)
		)
		(property "Manufacturer" "Panasonic"
			(at 0 0 0)
			(layer "B.Fab")
			(hide yes)
			(effects
				(font
					(size 1 1)
					(thickness 0.15)
				)
				(justify mirror)
			)
		)
		(property "Tolerance" ""
			(at 0 0 0)
			(layer "B.Fab")
			(hide yes)
			(effects
				(font
					(size 1 1)
					(thickness 0.15)
				)
				(justify mirror)
			)
		)
		(property "Val" "0R"
			(at 0 0 0)
			(layer "B.Fab")
			(hide yes)
			(effects
				(font
					(size 1 1)
					(thickness 0.15)
				)
				(justify mirror)
			)
		)
		(sheetname "CSI")
		(sheetfile "csi.kicad_sch")
		(attr smd exclude_from_pos_files exclude_from_bom dnp)
		(fp_rect
			(start -0.925 0.47)
			(end 0.925 -0.47)
			(stroke
				(width 0.05)
				(type default)
			)
			(fill none)
			(layer "B.CrtYd")
		)
		(fp_rect
			(start -0.5 0.25)
			(end 0.5 -0.25)
			(stroke
				(width 0.15)
				(type solid)
			)
			(fill none)
			(layer "B.Fab")
		)
		(fp_text user "Author: Antmicro"
			(at -0.95 -4.169 180)
			(layer "B.Fab")
			(hide yes)
			(effects
				(font
					(size 0.7 0.7)
					(thickness 0.15)
				)
				(justify left bottom mirror)
			)
		)
		(fp_text user "${REFERENCE}"
			(at -0.95 -3.168 180)
			(layer "B.Fab")
			(hide yes)
			(effects
				(font
					(size 0.7 0.7)
					(thickness 0.15)
				)
				(justify left bottom mirror)
			)
		)
		(fp_text user "License: Apache-2.0"
			(at -0.95 -5.169 180)
			(layer "B.Fab")
			(hide yes)
			(effects
				(font
					(size 0.7 0.7)
					(thickness 0.15)
				)
				(justify left bottom mirror)
			)
		)
		(pad "1" smd roundrect
			(at -0.48 0)
			(size 0.59 0.64)
			(layers "B.Cu" "B.Paste" "B.Mask")
			(roundrect_rratio 0.25)
			(net 321 "/CSI/CSIA_I2C_VCC")
			(pintype "passive")
		)
		(pad "2" smd roundrect
			(at 0.48 0)
			(size 0.59 0.64)
			(layers "B.Cu" "B.Paste" "B.Mask")
			(roundrect_rratio 0.25)
			(net 112 "+1V8")
			(pintype "passive")
		)
	)
	(footprint "antmicro-footprints:R_0402_1005Metric"
		(layer "B.Cu")
		(at 53.78 83.2)
		(descr "Resistor SMD 0402")
		(tags "resistor SMD 0402")
		(property "Reference" "R284"
			(at -3.605 -0.525 0)
			(layer "B.SilkS")
			(effects
				(font
					(size 0.7 0.7)
					(thickness 0.15)
				)
				(justify right top mirror)
			)
		)
		(property "Value" "R_560R_0402"
			(at -1.011843 -1.772046 0)
			(layer "B.Fab")
			(effects
				(font
					(size 0.7 0.7)
					(thickness 0.15)
				)
				(justify right top mirror)
			)
		)
		(property "Footprint" "antmicro-footprints:R_0402_1005Metric"
			(at 0 0 0)
			(layer "B.Fab")
			(hide yes)
			(effects
				(font
					(size 1.27 1.27)
					(thickness 0.15)
				)
				(justify mirror)
			)
		)
		(property "Datasheet" "https://www.bourns.com/docs/product-datasheets/cr.pdf"
			(at 0 0 0)
			(layer "B.Fab")
			(hide yes)
			(effects
				(font
					(size 1.27 1.27)
					(thickness 0.15)
				)
				(justify mirror)
			)
		)
		(property "Description" "SMD Chip Resistor, 560 ohm, ± 1%, 100 mW, 0402 [1005 Metric], Thick Film, Precision"
			(at 0 0 0)
			(layer "B.Fab")
			(hide yes)
			(effects
				(font
					(size 1.27 1.27)
					(thickness 0.15)
				)
				(justify mirror)
			)
		)
		(property "MPN" "CR0402-FX-5600GLF"
			(at 0 0 180)
			(unlocked yes)
			(layer "B.Fab")
			(hide yes)
			(effects
				(font
					(size 1 1)
					(thickness 0.15)
				)
				(justify mirror)
			)
		)
		(property "Manufacturer" "Bourns"
			(at 0 0 180)
			(unlocked yes)
			(layer "B.Fab")
			(hide yes)
			(effects
				(font
					(size 1 1)
					(thickness 0.15)
				)
				(justify mirror)
			)
		)
		(property "License" "Apache-2.0"
			(at 0 0 180)
			(unlocked yes)
			(layer "B.Fab")
			(hide yes)
			(effects
				(font
					(size 1 1)
					(thickness 0.15)
				)
				(justify mirror)
			)
		)
		(property "Author" "Antmicro"
			(at 0 0 180)
			(unlocked yes)
			(layer "B.Fab")
			(hide yes)
			(effects
				(font
					(size 1 1)
					(thickness 0.15)
				)
				(justify mirror)
			)
		)
		(property "Val" "560R"
			(at 0 0 180)
			(unlocked yes)
			(layer "B.Fab")
			(hide yes)
			(effects
				(font
					(size 1 1)
					(thickness 0.15)
				)
				(justify mirror)
			)
		)
		(property "Tolerance" "1%"
			(at 0 0 180)
			(unlocked yes)
			(layer "B.Fab")
			(hide yes)
			(effects
				(font
					(size 1 1)
					(thickness 0.15)
				)
				(justify mirror)
			)
		)
		(sheetname "Supply")
		(sheetfile "supply.kicad_sch")
		(attr smd)
		(fp_poly
			(pts
				(xy -0.925 0.47) (xy 0.925 0.47) (xy 0.925 -0.47) (xy -0.925 -0.47)
			)
			(stroke
				(width 0.05)
				(type default)
			)
			(fill none)
			(layer "B.CrtYd")
		)
		(fp_poly
			(pts
				(xy -0.5 0.25) (xy 0.5 0.25) (xy 0.5 -0.25) (xy -0.5 -0.25)
			)
			(stroke
				(width 0.15)
				(type solid)
			)
			(fill none)
			(layer "B.Fab")
		)
		(fp_text user "License: Apache-2.0"
			(at -0.949999 -5.169 0)
			(layer "B.Fab")
			(hide yes)
			(effects
				(font
					(size 0.7 0.7)
					(thickness 0.15)
				)
				(justify right top mirror)
			)
		)
		(fp_text user "${REFERENCE}"
			(at -0.95 -3.168 0)
			(layer "B.Fab")
			(hide yes)
			(effects
				(font
					(size 0.7 0.7)
					(thickness 0.15)
				)
				(justify right top mirror)
			)
		)
		(fp_text user "Author: Antmicro"
			(at -0.95 -4.169 0)
			(layer "B.Fab")
			(hide yes)
			(effects
				(font
					(size 0.7 0.7)
					(thickness 0.15)
				)
				(justify right top mirror)
			)
		)
		(pad "1" smd roundrect
			(at -0.48 0)
			(size 0.59 0.64)
			(layers "B.Cu" "B.Paste" "B.Mask")
			(roundrect_rratio 0.25)
			(net 1 "GND")
			(pintype "passive")
		)
		(pad "2" smd roundrect
			(at 0.48 0)
			(size 0.59 0.64)
			(layers "B.Cu" "B.Paste" "B.Mask")
			(roundrect_rratio 0.25)
			(net 791 "Net-(U48-ILIM)")
			(pintype "passive")
		)
	)
	(footprint "antmicro-footprints:LED_0603_1608Metric_G"
		(layer "B.Cu")
		(at 144.5 114 180)
		(descr "LED SMD 0603 Green")
		(tags "LED SMD 0603 Green")
		(property "Reference" "D18"
			(at -0.55 -1.475 0)
			(layer "B.SilkS")
			(effects
				(font
					(size 0.7 0.7)
					(thickness 0.15)
				)
				(justify left bottom mirror)
			)
		)
		(property "Value" "LED_G_0603_LTST-C190GKT"
			(at -0.001 -1.599 0)
			(layer "B.Fab")
			(effects
				(font
					(size 0.7 0.7)
					(thickness 0.15)
				)
				(justify left bottom mirror)
			)
		)
		(property "Footprint" "antmicro-footprints:LED_0603_1608Metric_G"
			(at 0 0 180)
			(layer "F.Fab")
			(hide yes)
			(effects
				(font
					(size 1.27 1.27)
					(thickness 0.15)
				)
			)
		)
		(property "Datasheet" "https://media.digikey.com/pdf/Data%20Sheets/Lite-On%20PDFs/LTST-C190GKT.pdf"
			(at 0 0 180)
			(layer "F.Fab")
			(hide yes)
			(effects
				(font
					(size 1.27 1.27)
					(thickness 0.15)
				)
			)
		)
		(property "Author" "Antmicro"
			(at 289 228 0)
			(layer "B.Fab")
			(hide yes)
			(effects
				(font
					(size 1 1)
					(thickness 0.15)
				)
				(justify mirror)
			)
		)
		(property "Color" "Green"
			(at 289 228 0)
			(layer "B.Fab")
			(hide yes)
			(effects
				(font
					(size 1 1)
					(thickness 0.15)
				)
				(justify mirror)
			)
		)
		(property "License" "Apache-2.0"
			(at 289 228 0)
			(layer "B.Fab")
			(hide yes)
			(effects
				(font
					(size 1 1)
					(thickness 0.15)
				)
				(justify mirror)
			)
		)
		(property "MPN" "LTST-C190GKT"
			(at 289 228 0)
			(layer "B.Fab")
			(hide yes)
			(effects
				(font
					(size 1 1)
					(thickness 0.15)
				)
				(justify mirror)
			)
		)
		(property "Manufacturer" "Lite-On"
			(at 289 228 0)
			(layer "B.Fab")
			(hide yes)
			(effects
				(font
					(size 1 1)
					(thickness 0.15)
				)
				(justify mirror)
			)
		)
		(sheetname "CSI")
		(sheetfile "csi.kicad_sch")
		(attr smd)
		(fp_line
			(start 0.24 -0.001)
			(end 0.105328 -0.001008)
			(stroke
				(width 0.1)
				(type solid)
			)
			(layer "B.SilkS")
		)
		(fp_line
			(start 0.105328 0.198992)
			(end 0.105328 -0.201008)
			(stroke
				(width 0.1)
				(type solid)
			)
			(layer "B.SilkS")
		)
		(fp_line
			(start 0.105328 0.198992)
			(end -0.094672 -0.001008)
			(stroke
				(width 0.1)
				(type solid)
			)
			(layer "B.SilkS")
		)
		(fp_line
			(start -0.094672 0.198992)
			(end -0.094672 -0.201008)
			(stroke
				(width 0.1)
				(type solid)
			)
			(layer "B.SilkS")
		)
		(fp_line
			(start -0.094672 -0.001008)
			(end 0.105328 -0.201008)
			(stroke
				(width 0.1)
				(type solid)
			)
			(layer "B.SilkS")
		)
		(fp_line
			(start -0.22 0.35)
			(end 0.22 0.35)
			(stroke
				(width 0.15)
				(type solid)
			)
			(layer "B.SilkS")
		)
		(fp_line
			(start -0.22 -0.35)
			(end 0.22 -0.35)
			(stroke
				(width 0.15)
				(type solid)
			)
			(layer "B.SilkS")
		)
		(fp_line
			(start -0.24 -0.001008)
			(end -0.094672 -0.001008)
			(stroke
				(width 0.1)
				(type solid)
			)
			(layer "B.SilkS")
		)
		(fp_line
			(start -1.18 -0.321)
			(end -1.18 0.319)
			(stroke
				(width 0.15)
				(type solid)
			)
			(layer "B.SilkS")
		)
		(fp_rect
			(start 1.25 -0.65)
			(end -1.25 0.65)
			(stroke
				(width 0.05)
				(type solid)
			)
			(fill none)
			(layer "B.CrtYd")
		)
		(fp_line
			(start 0.201 0.202)
			(end 0.201 0)
			(stroke
				(width 0.15)
				(type solid)
			)
			(layer "B.Fab")
		)
		(fp_line
			(start 0.201 0)
			(end 0.599 0)
			(stroke
				(width 0.15)
				(type solid)
			)
			(layer "B.Fab")
		)
		(fp_line
			(start 0.201 0)
			(end 0.201 -0.2)
			(stroke
				(width 0.15)
				(type solid)
			)
			(layer "B.Fab")
		)
		(fp_line
			(start 0.201 -0.2)
			(end -0.101 0)
			(stroke
				(width 0.15)
				(type solid)
			)
			(layer "B.Fab")
		)
		(fp_line
			(start -0.101 0)
			(end 0.201 0.202)
			(stroke
				(width 0.15)
				(type solid)
			)
			(layer "B.Fab")
		)
		(fp_line
			(start -0.199 -0.1)
			(end -0.199 0.202)
			(stroke
				(width 0.15)
				(type solid)
			)
			(layer "B.Fab")
		)
		(fp_line
			(start -0.199 -0.1)
			(end -0.199 -0.2)
			(stroke
				(width 0.15)
				(type solid)
			)
			(layer "B.Fab")
		)
		(fp_line
			(start -0.597 0)
			(end -0.199 0)
			(stroke
				(width 0.15)
				(type solid)
			)
			(layer "B.Fab")
		)
		(fp_rect
			(start 0.848 -0.4)
			(end -0.85 0.402)
			(stroke
				(width 0.15)
				(type solid)
			)
			(fill none)
			(layer "B.Fab")
		)
		(fp_text user "License: Apache-2.0"
			(at -1.4224 -3.599 0)
			(layer "B.Fab")
			(hide yes)
			(effects
				(font
					(size 0.7 0.7)
					(thickness 0.15)
				)
				(justify left bottom mirror)
			)
		)
		(fp_text user "Author: Antmicro"
			(at -1.4224 -4.799 0)
			(layer "B.Fab")
			(hide yes)
			(effects
				(font
					(size 0.7 0.7)
					(thickness 0.15)
				)
				(justify left bottom mirror)
			)
		)
		(fp_text user "${REFERENCE}"
			(at -1.4224 -5.999 0)
			(layer "B.Fab")
			(hide yes)
			(effects
				(font
					(size 0.7 0.7)
					(thickness 0.15)
				)
				(justify left bottom mirror)
			)
		)
		(pad "1" smd roundrect
			(at -0.7 0)
			(size 0.8 1)
			(layers "B.Cu" "B.Paste" "B.Mask")
			(roundrect_rratio 0.2)
			(net 1 "GND")
			(pinfunction "C")
			(pintype "passive")
		)
		(pad "2" smd roundrect
			(at 0.7 0)
			(size 0.8 1)
			(layers "B.Cu" "B.Paste" "B.Mask")
			(roundrect_rratio 0.2)
			(net 155 "Net-(D18-A)")
			(pinfunction "A")
			(pintype "passive")
		)
	)
	(footprint "antmicro-footprints:C_1206_3216Metric"
		(layer "B.Cu")
		(at 31.5 77.75 90)
		(descr "Capacitor SMD 1206")
		(tags "capacitor SMD 1206")
		(property "Reference" "C84"
			(at 1.15 2.05 -90)
			(layer "B.SilkS")
			(effects
				(font
					(size 0.7 0.7)
					(thickness 0.15)
				)
				(justify left bottom mirror)
			)
		)
		(property "Value" "C_47u_16V_1206"
			(at 0 -2.1 -90)
			(layer "B.Fab")
			(effects
				(font
					(size 0.7 0.7)
					(thickness 0.15)
				)
				(justify left bottom mirror)
			)
		)
		(property "Footprint" "antmicro-footprints:C_1206_3216Metric"
			(at 0 0 90)
			(layer "F.Fab")
			(hide yes)
			(effects
				(font
					(size 1.27 1.27)
					(thickness 0.15)
				)
			)
		)
		(property "Datasheet" "https://product.tdk.com/en/search/capacitor/ceramic/mlcc/info?part_no=C3216X5R1C476M160AB"
			(at 0 0 90)
			(layer "F.Fab")
			(hide yes)
			(effects
				(font
					(size 1.27 1.27)
					(thickness 0.15)
				)
			)
		)
		(property "Author" "Antmicro"
			(at 109.25 46.25 0)
			(layer "B.Fab")
			(hide yes)
			(effects
				(font
					(size 1 1)
					(thickness 0.15)
				)
				(justify mirror)
			)
		)
		(property "Dielectric" "X5R"
			(at 109.25 46.25 0)
			(layer "B.Fab")
			(hide yes)
			(effects
				(font
					(size 1 1)
					(thickness 0.15)
				)
				(justify mirror)
			)
		)
		(property "License" "Apache-2.0"
			(at 109.25 46.25 0)
			(layer "B.Fab")
			(hide yes)
			(effects
				(font
					(size 1 1)
					(thickness 0.15)
				)
				(justify mirror)
			)
		)
		(property "MPN" "C3216X5R1C476M160AB"
			(at 109.25 46.25 0)
			(layer "B.Fab")
			(hide yes)
			(effects
				(font
					(size 1 1)
					(thickness 0.15)
				)
				(justify mirror)
			)
		)
		(property "Manufacturer" "TDK"
			(at 109.25 46.25 0)
			(layer "B.Fab")
			(hide yes)
			(effects
				(font
					(size 1 1)
					(thickness 0.15)
				)
				(justify mirror)
			)
		)
		(property "Public" "False"
			(at 109.25 46.25 0)
			(layer "B.Fab")
			(hide yes)
			(effects
				(font
					(size 1 1)
					(thickness 0.15)
				)
				(justify mirror)
			)
		)
		(property "Val" "47u"
			(at 109.25 46.25 0)
			(layer "B.Fab")
			(hide yes)
			(effects
				(font
					(size 1 1)
					(thickness 0.15)
				)
				(justify mirror)
			)
		)
		(property "Voltage" "16V"
			(at 109.25 46.25 0)
			(layer "B.Fab")
			(hide yes)
			(effects
				(font
					(size 1 1)
					(thickness 0.15)
				)
				(justify mirror)
			)
		)
		(sheetname "Ethernet")
		(sheetfile "ethernet.kicad_sch")
		(attr smd)
		(fp_line
			(start -0.8 -0.901)
			(end 0.8 -0.901)
			(stroke
				(width 0.15)
				(type solid)
			)
			(layer "B.SilkS")
		)
		(fp_line
			(start -0.8 0.899)
			(end 0.8 0.899)
			(stroke
				(width 0.15)
				(type solid)
			)
			(layer "B.SilkS")
		)
		(fp_rect
			(start -2.325 1.15)
			(end 2.325 -1.15)
			(stroke
				(width 0.05)
				(type default)
			)
			(fill none)
			(layer "B.CrtYd")
		)
		(fp_rect
			(start -1.6 0.799)
			(end 1.6 -0.801)
			(stroke
				(width 0.15)
				(type solid)
			)
			(fill none)
			(layer "B.Fab")
		)
		(fp_text user "Author: Antmicro"
			(at -2.8 -5.6 -90)
			(layer "B.Fab")
			(hide yes)
			(effects
				(font
					(size 0.7 0.7)
					(thickness 0.15)
				)
				(justify left bottom mirror)
			)
		)
		(fp_text user "License: Apache-2.0"
			(at -2.8 -6.6 -90)
			(layer "B.Fab")
			(hide yes)
			(effects
				(font
					(size 0.7 0.7)
					(thickness 0.15)
				)
				(justify left bottom mirror)
			)
		)
		(fp_text user "${REFERENCE}"
			(at -2.8 -4.6 -90)
			(layer "B.Fab")
			(hide yes)
			(effects
				(font
					(size 0.7 0.7)
					(thickness 0.15)
				)
				(justify left bottom mirror)
			)
		)
		(pad "1" smd roundrect
			(at -1.5 -0.001 90)
			(size 1.15 1.8)
			(layers "B.Cu" "B.Paste" "B.Mask")
			(roundrect_rratio 0.25)
			(net 1 "GND")
			(pintype "passive")
		)
		(pad "2" smd roundrect
			(at 1.5 -0.001 90)
			(size 1.15 1.8)
			(layers "B.Cu" "B.Paste" "B.Mask")
			(roundrect_rratio 0.25)
			(net 500 "POE_OUTPUT")
			(pintype "passive")
		)
	)
	(footprint "antmicro-footprints:R_0603_1608Metric"
		(layer "B.Cu")
		(at 39.8 69.8)
		(descr "Resistor SMD 0603")
		(tags "resistor SMD 0603")
		(property "Reference" "R243"
			(at 0.4 0.65 -90)
			(layer "B.SilkS")
			(effects
				(font
					(size 0.7 0.7)
					(thickness 0.15)
				)
				(justify left bottom mirror)
			)
		)
		(property "Value" "R_0R_0603"
			(at 0 -1.6 180)
			(layer "B.Fab")
			(effects
				(font
					(size 0.7 0.7)
					(thickness 0.15)
				)
				(justify left bottom mirror)
			)
		)
		(property "Footprint" "antmicro-footprints:R_0603_1608Metric"
			(at 0 0 0)
			(layer "F.Fab")
			(hide yes)
			(effects
				(font
					(size 1.27 1.27)
					(thickness 0.15)
				)
			)
		)
		(property "Datasheet" "https://www.bourns.com/docs/product-datasheets/cr.pdf?sfvrsn=574d41f6_14"
			(at 0 0 0)
			(layer "F.Fab")
			(hide yes)
			(effects
				(font
					(size 1.27 1.27)
					(thickness 0.15)
				)
			)
		)
		(property "Author" "Antmicro"
			(at 0 0 0)
			(layer "B.Fab")
			(hide yes)
			(effects
				(font
					(size 1 1)
					(thickness 0.15)
				)
				(justify mirror)
			)
		)
		(property "Current" "1A"
			(at 0 0 0)
			(layer "B.Fab")
			(hide yes)
			(effects
				(font
					(size 1 1)
					(thickness 0.15)
				)
				(justify mirror)
			)
		)
		(property "License" "Apache-2.0"
			(at 0 0 0)
			(layer "B.Fab")
			(hide yes)
			(effects
				(font
					(size 1 1)
					(thickness 0.15)
				)
				(justify mirror)
			)
		)
		(property "MPN" "CR0603-J/-000ELF"
			(at 0 0 0)
			(layer "B.Fab")
			(hide yes)
			(effects
				(font
					(size 1 1)
					(thickness 0.15)
				)
				(justify mirror)
			)
		)
		(property "Manufacturer" "Bourns"
			(at 0 0 0)
			(layer "B.Fab")
			(hide yes)
			(effects
				(font
					(size 1 1)
					(thickness 0.15)
				)
				(justify mirror)
			)
		)
		(property "Tolerance" ""
			(at 0 0 0)
			(layer "B.Fab")
			(hide yes)
			(effects
				(font
					(size 1 1)
					(thickness 0.15)
				)
				(justify mirror)
			)
		)
		(property "Val" "0R"
			(at 0 0 0)
			(layer "B.Fab")
			(hide yes)
			(effects
				(font
					(size 1 1)
					(thickness 0.15)
				)
				(justify mirror)
			)
		)
		(sheetname "Ethernet")
		(sheetfile "ethernet.kicad_sch")
		(attr smd exclude_from_pos_files exclude_from_bom dnp)
		(fp_line
			(start 0.15 -0.4)
			(end -0.15 -0.4)
			(stroke
				(width 0.15)
				(type solid)
			)
			(layer "B.SilkS")
		)
		(fp_line
			(start 0.15 0.4)
			(end -0.15 0.4)
			(stroke
				(width 0.15)
				(type solid)
			)
			(layer "B.SilkS")
		)
		(fp_rect
			(start -1.25 0.65)
			(end 1.25 -0.65)
			(stroke
				(width 0.05)
				(type solid)
			)
			(fill none)
			(layer "B.CrtYd")
		)
		(fp_rect
			(start -0.8 0.4)
			(end 0.8 -0.4)
			(stroke
				(width 0.15)
				(type solid)
			)
			(fill none)
			(layer "B.Fab")
		)
		(fp_text user "Author: Antmicro"
			(at -1.25 -4.9 180)
			(layer "B.Fab")
			(hide yes)
			(effects
				(font
					(size 0.7 0.7)
					(thickness 0.15)
				)
				(justify left bottom mirror)
			)
		)
		(fp_text user "${REFERENCE}"
			(at -1.25 -3.898 180)
			(layer "B.Fab")
			(hide yes)
			(effects
				(font
					(size 0.7 0.7)
					(thickness 0.15)
				)
				(justify left bottom mirror)
			)
		)
		(fp_text user "License: Apache-2.0"
			(at -1.25 -5.9 180)
			(layer "B.Fab")
			(hide yes)
			(effects
				(font
					(size 0.7 0.7)
					(thickness 0.15)
				)
				(justify left bottom mirror)
			)
		)
		(pad "1" smd roundrect
			(at -0.7 0)
			(size 0.8 1)
			(layers "B.Cu" "B.Paste" "B.Mask")
			(roundrect_rratio 0.2)
			(net 500 "POE_OUTPUT")
			(pintype "passive")
		)
		(pad "2" smd roundrect
			(at 0.7 0)
			(size 0.8 1)
			(layers "B.Cu" "B.Paste" "B.Mask")
			(roundrect_rratio 0.2)
			(net 683 "Net-(U23-TRIM)")
			(pintype "passive")
		)
	)
	(footprint "antmicro-footprints:R_0402_1005Metric"
		(layer "B.Cu")
		(at 68.6 94.4 -90)
		(descr "Resistor SMD 0402")
		(tags "resistor SMD 0402")
		(property "Reference" "R130"
			(at -1.15 -2.41 90)
			(layer "B.SilkS")
			(effects
				(font
					(size 0.7 0.7)
					(thickness 0.15)
				)
				(justify left bottom mirror)
			)
		)
		(property "Value" "R_4k7_0402"
			(at 0 -1.4 90)
			(layer "B.Fab")
			(effects
				(font
					(size 0.7 0.7)
					(thickness 0.15)
				)
				(justify left bottom mirror)
			)
		)
		(property "Footprint" "antmicro-footprints:R_0402_1005Metric"
			(at 0 0 -90)
			(layer "F.Fab")
			(hide yes)
			(effects
				(font
					(size 1.27 1.27)
					(thickness 0.15)
				)
			)
		)
		(property "Datasheet" "https://www.bourns.com/docs/product-datasheets/cr.pdf"
			(at 0 0 -90)
			(layer "F.Fab")
			(hide yes)
			(effects
				(font
					(size 1.27 1.27)
					(thickness 0.15)
				)
			)
		)
		(property "Author" "Antmicro"
			(at -25.8 163 0)
			(layer "B.Fab")
			(hide yes)
			(effects
				(font
					(size 1 1)
					(thickness 0.15)
				)
				(justify mirror)
			)
		)
		(property "License" "Apache-2.0"
			(at -25.8 163 0)
			(layer "B.Fab")
			(hide yes)
			(effects
				(font
					(size 1 1)
					(thickness 0.15)
				)
				(justify mirror)
			)
		)
		(property "MPN" "CR0402-FX-4701GLF"
			(at -25.8 163 0)
			(layer "B.Fab")
			(hide yes)
			(effects
				(font
					(size 1 1)
					(thickness 0.15)
				)
				(justify mirror)
			)
		)
		(property "Manufacturer" "Bourns"
			(at -25.8 163 0)
			(layer "B.Fab")
			(hide yes)
			(effects
				(font
					(size 1 1)
					(thickness 0.15)
				)
				(justify mirror)
			)
		)
		(property "Tolerance" "1%"
			(at -25.8 163 0)
			(layer "B.Fab")
			(hide yes)
			(effects
				(font
					(size 1 1)
					(thickness 0.15)
				)
				(justify mirror)
			)
		)
		(property "Val" "4k7"
			(at -25.8 163 0)
			(layer "B.Fab")
			(hide yes)
			(effects
				(font
					(size 1 1)
					(thickness 0.15)
				)
				(justify mirror)
			)
		)
		(sheetname "USB Debug, DP")
		(sheetfile "usb.kicad_sch")
		(attr smd)
		(fp_rect
			(start -0.925 0.47)
			(end 0.925 -0.47)
			(stroke
				(width 0.05)
				(type default)
			)
			(fill none)
			(layer "B.CrtYd")
		)
		(fp_rect
			(start -0.5 0.25)
			(end 0.5 -0.25)
			(stroke
				(width 0.15)
				(type solid)
			)
			(fill none)
			(layer "B.Fab")
		)
		(fp_text user "License: Apache-2.0"
			(at -0.95 -5.169 90)
			(layer "B.Fab")
			(hide yes)
			(effects
				(font
					(size 0.7 0.7)
					(thickness 0.15)
				)
				(justify left bottom mirror)
			)
		)
		(fp_text user "${REFERENCE}"
			(at -0.95 -3.168 90)
			(layer "B.Fab")
			(hide yes)
			(effects
				(font
					(size 0.7 0.7)
					(thickness 0.15)
				)
				(justify left bottom mirror)
			)
		)
		(fp_text user "Author: Antmicro"
			(at -0.95 -4.169 90)
			(layer "B.Fab")
			(hide yes)
			(effects
				(font
					(size 0.7 0.7)
					(thickness 0.15)
				)
				(justify left bottom mirror)
			)
		)
		(pad "1" smd roundrect
			(at -0.48 0 270)
			(size 0.59 0.64)
			(layers "B.Cu" "B.Paste" "B.Mask")
			(roundrect_rratio 0.25)
			(net 87 "+3V3")
			(pintype "passive")
		)
		(pad "2" smd roundrect
			(at 0.48 0 270)
			(size 0.59 0.64)
			(layers "B.Cu" "B.Paste" "B.Mask")
			(roundrect_rratio 0.25)
			(net 395 "/USB Debug, DP/PDC_I2C2_SCL")
			(pintype "passive")
		)
	)
	(footprint "antmicro-footprints:R_0402_1005Metric"
		(layer "B.Cu")
		(at 89 112.6 -90)
		(descr "Resistor SMD 0402")
		(tags "resistor SMD 0402")
		(property "Reference" "R219"
			(at -0.965 3.55 90)
			(layer "B.SilkS")
			(effects
				(font
					(size 0.7 0.7)
					(thickness 0.15)
				)
				(justify left bottom mirror)
			)
		)
		(property "Value" "R_10k_0402"
			(at 0 -1.4 90)
			(layer "B.Fab")
			(effects
				(font
					(size 0.7 0.7)
					(thickness 0.15)
				)
				(justify left bottom mirror)
			)
		)
		(property "Footprint" "antmicro-footprints:R_0402_1005Metric"
			(at 0 0 -90)
			(layer "F.Fab")
			(hide yes)
			(effects
				(font
					(size 1.27 1.27)
					(thickness 0.15)
				)
			)
		)
		(property "Datasheet" "https://www.bourns.com/docs/product-datasheets/cr.pdf"
			(at 0 0 -90)
			(layer "F.Fab")
			(hide yes)
			(effects
				(font
					(size 1.27 1.27)
					(thickness 0.15)
				)
			)
		)
		(property "Author" "Antmicro"
			(at -23.6 201.6 0)
			(layer "B.Fab")
			(hide yes)
			(effects
				(font
					(size 1 1)
					(thickness 0.15)
				)
				(justify mirror)
			)
		)
		(property "License" "Apache-2.0"
			(at -23.6 201.6 0)
			(layer "B.Fab")
			(hide yes)
			(effects
				(font
					(size 1 1)
					(thickness 0.15)
				)
				(justify mirror)
			)
		)
		(property "MPN" "CR0402-FX-1002GLF"
			(at -23.6 201.6 0)
			(layer "B.Fab")
			(hide yes)
			(effects
				(font
					(size 1 1)
					(thickness 0.15)
				)
				(justify mirror)
			)
		)
		(property "Manufacturer" "Bourns"
			(at -23.6 201.6 0)
			(layer "B.Fab")
			(hide yes)
			(effects
				(font
					(size 1 1)
					(thickness 0.15)
				)
				(justify mirror)
			)
		)
		(property "Tolerance" "1%"
			(at -23.6 201.6 0)
			(layer "B.Fab")
			(hide yes)
			(effects
				(font
					(size 1 1)
					(thickness 0.15)
				)
				(justify mirror)
			)
		)
		(property "Val" "10k"
			(at -23.6 201.6 0)
			(layer "B.Fab")
			(hide yes)
			(effects
				(font
					(size 1 1)
					(thickness 0.15)
				)
				(justify mirror)
			)
		)
		(sheetname "Peripherals")
		(sheetfile "peripherals.kicad_sch")
		(attr smd)
		(fp_rect
			(start -0.925 0.47)
			(end 0.925 -0.47)
			(stroke
				(width 0.05)
				(type default)
			)
			(fill none)
			(layer "B.CrtYd")
		)
		(fp_rect
			(start -0.5 0.25)
			(end 0.5 -0.25)
			(stroke
				(width 0.15)
				(type solid)
			)
			(fill none)
			(layer "B.Fab")
		)
		(fp_text user "License: Apache-2.0"
			(at -0.95 -5.169 90)
			(layer "B.Fab")
			(hide yes)
			(effects
				(font
					(size 0.7 0.7)
					(thickness 0.15)
				)
				(justify left bottom mirror)
			)
		)
		(fp_text user "${REFERENCE}"
			(at -0.95 -3.168 90)
			(layer "B.Fab")
			(hide yes)
			(effects
				(font
					(size 0.7 0.7)
					(thickness 0.15)
				)
				(justify left bottom mirror)
			)
		)
		(fp_text user "Author: Antmicro"
			(at -0.95 -4.169 90)
			(layer "B.Fab")
			(hide yes)
			(effects
				(font
					(size 0.7 0.7)
					(thickness 0.15)
				)
				(justify left bottom mirror)
			)
		)
		(pad "1" smd roundrect
			(at -0.48 0 270)
			(size 0.59 0.64)
			(layers "B.Cu" "B.Paste" "B.Mask")
			(roundrect_rratio 0.25)
			(net 281 "~{GPIO_INT}")
			(pintype "passive")
		)
		(pad "2" smd roundrect
			(at 0.48 0 270)
			(size 0.59 0.64)
			(layers "B.Cu" "B.Paste" "B.Mask")
			(roundrect_rratio 0.25)
			(net 112 "+1V8")
			(pintype "passive")
		)
	)
	(footprint "antmicro-footprints:TP_SMD_0.75mm"
		(layer "B.Cu")
		(at 89.7492 114.4 -90)
		(property "Reference" "TP56"
			(at -0.855 1.4042 90)
			(layer "B.SilkS")
			(effects
				(font
					(size 0.7 0.7)
					(thickness 0.15)
				)
				(justify left bottom mirror)
			)
		)
		(property "Value" "TP_0.75mm_SMD"
			(at 0 -1.2 90)
			(layer "B.Fab")
			(effects
				(font
					(size 0.7 0.7)
					(thickness 0.15)
				)
				(justify left bottom mirror)
			)
		)
		(property "Footprint" "antmicro-footprints:TP_SMD_0.75mm"
			(at 0 0 -90)
			(layer "F.Fab")
			(hide yes)
			(effects
				(font
					(size 1.27 1.27)
					(thickness 0.15)
				)
			)
		)
		(property "Author" "Antmicro"
			(at -24.6508 204.1492 0)
			(layer "B.Fab")
			(hide yes)
			(effects
				(font
					(size 1 1)
					(thickness 0.15)
				)
				(justify mirror)
			)
		)
		(property "License" "Apache-2.0"
			(at -24.6508 204.1492 0)
			(layer "B.Fab")
			(hide yes)
			(effects
				(font
					(size 1 1)
					(thickness 0.15)
				)
				(justify mirror)
			)
		)
		(property "MPN" ""
			(at -24.6508 204.1492 0)
			(layer "B.Fab")
			(hide yes)
			(effects
				(font
					(size 1 1)
					(thickness 0.15)
				)
				(justify mirror)
			)
		)
		(property "Manufacturer" ""
			(at -24.6508 204.1492 0)
			(layer "B.Fab")
			(hide yes)
			(effects
				(font
					(size 1 1)
					(thickness 0.15)
				)
				(justify mirror)
			)
		)
		(sheetname "HDMI")
		(sheetfile "hdmi.kicad_sch")
		(attr exclude_from_pos_files exclude_from_bom)
		(fp_circle
			(center 0 0)
			(end 0.475 0)
			(stroke
				(width 0.05)
				(type default)
			)
			(fill none)
			(layer "B.CrtYd")
		)
		(fp_text user "${REFERENCE}"
			(at -0.4 -2.7 90)
			(layer "B.Fab")
			(hide yes)
			(effects
				(font
					(size 0.7 0.7)
					(thickness 0.15)
				)
				(justify left bottom mirror)
			)
		)
		(fp_text user "License: Apache-2.0"
			(at -0.4 -5.101 90)
			(layer "B.Fab")
			(hide yes)
			(effects
				(font
					(size 0.7 0.7)
					(thickness 0.15)
				)
				(justify left bottom mirror)
			)
		)
		(fp_text user "Author: Antmicro"
			(at -0.4 -3.901 90)
			(layer "B.Fab")
			(hide yes)
			(effects
				(font
					(size 0.7 0.7)
					(thickness 0.15)
				)
				(justify left bottom mirror)
			)
		)
		(pad "1" smd circle
			(at 0 0 270)
			(size 0.75 0.75)
			(layers "B.Cu" "B.Mask")
			(net 701 "/HDMI/HDMI_SDA_3V3")
			(pinfunction "1")
			(pintype "passive")
		)
	)
	(footprint "antmicro-footprints:TP_SMD_0.75mm"
		(layer "B.Cu")
		(at 63.205 70.17 180)
		(property "Reference" "TP33"
			(at -3.165 -0.39 0)
			(layer "B.SilkS")
			(effects
				(font
					(size 0.7 0.7)
					(thickness 0.15)
				)
				(justify left bottom mirror)
			)
		)
		(property "Value" "TP_0.75mm_SMD"
			(at 0 -1.2 0)
			(layer "B.Fab")
			(effects
				(font
					(size 0.7 0.7)
					(thickness 0.15)
				)
				(justify left bottom mirror)
			)
		)
		(property "Footprint" "antmicro-footprints:TP_SMD_0.75mm"
			(at 0 0 180)
			(layer "F.Fab")
			(hide yes)
			(effects
				(font
					(size 1.27 1.27)
					(thickness 0.15)
				)
			)
		)
		(property "Author" "Antmicro"
			(at 126.41 140.34 0)
			(layer "B.Fab")
			(hide yes)
			(effects
				(font
					(size 1 1)
					(thickness 0.15)
				)
				(justify mirror)
			)
		)
		(property "License" "Apache-2.0"
			(at 126.41 140.34 0)
			(layer "B.Fab")
			(hide yes)
			(effects
				(font
					(size 1 1)
					(thickness 0.15)
				)
				(justify mirror)
			)
		)
		(property "MPN" ""
			(at 126.41 140.34 0)
			(layer "B.Fab")
			(hide yes)
			(effects
				(font
					(size 1 1)
					(thickness 0.15)
				)
				(justify mirror)
			)
		)
		(property "Manufacturer" ""
			(at 126.41 140.34 0)
			(layer "B.Fab")
			(hide yes)
			(effects
				(font
					(size 1 1)
					(thickness 0.15)
				)
				(justify mirror)
			)
		)
		(sheetname "Supply")
		(sheetfile "supply.kicad_sch")
		(attr exclude_from_pos_files exclude_from_bom)
		(fp_circle
			(center 0 0)
			(end 0.475 0)
			(stroke
				(width 0.05)
				(type default)
			)
			(fill none)
			(layer "B.CrtYd")
		)
		(fp_text user "Author: Antmicro"
			(at -0.4 -3.901 0)
			(layer "B.Fab")
			(hide yes)
			(effects
				(font
					(size 0.7 0.7)
					(thickness 0.15)
				)
				(justify left bottom mirror)
			)
		)
		(fp_text user "${REFERENCE}"
			(at -0.4 -2.7 0)
			(layer "B.Fab")
			(hide yes)
			(effects
				(font
					(size 0.7 0.7)
					(thickness 0.15)
				)
				(justify left bottom mirror)
			)
		)
		(fp_text user "License: Apache-2.0"
			(at -0.4 -5.101 0)
			(layer "B.Fab")
			(hide yes)
			(effects
				(font
					(size 0.7 0.7)
					(thickness 0.15)
				)
				(justify left bottom mirror)
			)
		)
		(pad "1" smd circle
			(at 0 0 180)
			(size 0.75 0.75)
			(layers "B.Cu" "B.Mask")
			(net 86 "~{RESET}")
			(pinfunction "1")
			(pintype "passive")
		)
	)
	(footprint "antmicro-footprints:R_0402_1005Metric"
		(layer "B.Cu")
		(at 72.3 106.2)
		(descr "Resistor SMD 0402")
		(tags "resistor SMD 0402")
		(property "Reference" "R79"
			(at -0.23 2.18 180)
			(layer "B.SilkS")
			(effects
				(font
					(size 0.7 0.7)
					(thickness 0.15)
				)
				(justify left bottom mirror)
			)
		)
		(property "Value" "R_0R_0402"
			(at 0 -1.4 180)
			(layer "B.Fab")
			(effects
				(font
					(size 0.7 0.7)
					(thickness 0.15)
				)
				(justify left bottom mirror)
			)
		)
		(property "Footprint" "antmicro-footprints:R_0402_1005Metric"
			(at 0 0 0)
			(layer "F.Fab")
			(hide yes)
			(effects
				(font
					(size 1.27 1.27)
					(thickness 0.15)
				)
			)
		)
		(property "Datasheet" "https://industrial.panasonic.com/cdbs/www-data/pdf/RDA0000/AOA0000C301.pdf"
			(at 0 0 0)
			(layer "F.Fab")
			(hide yes)
			(effects
				(font
					(size 1.27 1.27)
					(thickness 0.15)
				)
			)
		)
		(property "Author" "Antmicro"
			(at 0 0 0)
			(layer "B.Fab")
			(hide yes)
			(effects
				(font
					(size 1 1)
					(thickness 0.15)
				)
				(justify mirror)
			)
		)
		(property "Current" "1A"
			(at 0 0 0)
			(layer "B.Fab")
			(hide yes)
			(effects
				(font
					(size 1 1)
					(thickness 0.15)
				)
				(justify mirror)
			)
		)
		(property "License" "Apache-2.0"
			(at 0 0 0)
			(layer "B.Fab")
			(hide yes)
			(effects
				(font
					(size 1 1)
					(thickness 0.15)
				)
				(justify mirror)
			)
		)
		(property "MPN" "ERJ2GE0R00X"
			(at 0 0 0)
			(layer "B.Fab")
			(hide yes)
			(effects
				(font
					(size 1 1)
					(thickness 0.15)
				)
				(justify mirror)
			)
		)
		(property "Manufacturer" "Panasonic"
			(at 0 0 0)
			(layer "B.Fab")
			(hide yes)
			(effects
				(font
					(size 1 1)
					(thickness 0.15)
				)
				(justify mirror)
			)
		)
		(property "Tolerance" ""
			(at 0 0 0)
			(layer "B.Fab")
			(hide yes)
			(effects
				(font
					(size 1 1)
					(thickness 0.15)
				)
				(justify mirror)
			)
		)
		(property "Val" "0R"
			(at 0 0 0)
			(layer "B.Fab")
			(hide yes)
			(effects
				(font
					(size 1 1)
					(thickness 0.15)
				)
				(justify mirror)
			)
		)
		(sheetname "USB Debug, DP")
		(sheetfile "usb.kicad_sch")
		(attr smd exclude_from_pos_files exclude_from_bom dnp)
		(fp_rect
			(start -0.925 0.47)
			(end 0.925 -0.47)
			(stroke
				(width 0.05)
				(type default)
			)
			(fill none)
			(layer "B.CrtYd")
		)
		(fp_rect
			(start -0.5 0.25)
			(end 0.5 -0.25)
			(stroke
				(width 0.15)
				(type solid)
			)
			(fill none)
			(layer "B.Fab")
		)
		(fp_text user "License: Apache-2.0"
			(at -0.95 -5.169 180)
			(layer "B.Fab")
			(hide yes)
			(effects
				(font
					(size 0.7 0.7)
					(thickness 0.15)
				)
				(justify left bottom mirror)
			)
		)
		(fp_text user "${REFERENCE}"
			(at -0.95 -3.168 180)
			(layer "B.Fab")
			(hide yes)
			(effects
				(font
					(size 0.7 0.7)
					(thickness 0.15)
				)
				(justify left bottom mirror)
			)
		)
		(fp_text user "Author: Antmicro"
			(at -0.95 -4.169 180)
			(layer "B.Fab")
			(hide yes)
			(effects
				(font
					(size 0.7 0.7)
					(thickness 0.15)
				)
				(justify left bottom mirror)
			)
		)
		(pad "1" smd roundrect
			(at -0.48 0)
			(size 0.59 0.64)
			(layers "B.Cu" "B.Paste" "B.Mask")
			(roundrect_rratio 0.25)
			(net 295 "/USB Debug, DP/USBC0_CTL0")
			(pintype "passive")
		)
		(pad "2" smd roundrect
			(at 0.48 0)
			(size 0.59 0.64)
			(layers "B.Cu" "B.Paste" "B.Mask")
			(roundrect_rratio 0.25)
			(net 251 "SYS_SDA")
			(pintype "passive")
		)
	)
	(footprint "antmicro-footprints:R_0402_1005Metric"
		(layer "B.Cu")
		(at 58.9 79.95)
		(descr "Resistor SMD 0402")
		(tags "resistor SMD 0402")
		(property "Reference" "R256"
			(at 23.81 9.18 180)
			(layer "B.SilkS")
			(effects
				(font
					(size 0.7 0.7)
					(thickness 0.15)
				)
				(justify left bottom mirror)
			)
		)
		(property "Value" "R_1k_0402"
			(at 0 -1.4 180)
			(layer "B.Fab")
			(effects
				(font
					(size 0.7 0.7)
					(thickness 0.15)
				)
				(justify left bottom mirror)
			)
		)
		(property "Footprint" "antmicro-footprints:R_0402_1005Metric"
			(at 0 0 0)
			(layer "F.Fab")
			(hide yes)
			(effects
				(font
					(size 1.27 1.27)
					(thickness 0.15)
				)
			)
		)
		(property "Datasheet" "https://www.bourns.com/docs/product-datasheets/cr.pdf"
			(at 0 0 0)
			(layer "F.Fab")
			(hide yes)
			(effects
				(font
					(size 1.27 1.27)
					(thickness 0.15)
				)
			)
		)
		(property "Author" "Antmicro"
			(at 0 0 0)
			(layer "B.Fab")
			(hide yes)
			(effects
				(font
					(size 1 1)
					(thickness 0.15)
				)
				(justify mirror)
			)
		)
		(property "License" "Apache-2.0"
			(at 0 0 0)
			(layer "B.Fab")
			(hide yes)
			(effects
				(font
					(size 1 1)
					(thickness 0.15)
				)
				(justify mirror)
			)
		)
		(property "MPN" "CR0402-FX-1001GLF"
			(at 0 0 0)
			(layer "B.Fab")
			(hide yes)
			(effects
				(font
					(size 1 1)
					(thickness 0.15)
				)
				(justify mirror)
			)
		)
		(property "Manufacturer" "Bourns"
			(at 0 0 0)
			(layer "B.Fab")
			(hide yes)
			(effects
				(font
					(size 1 1)
					(thickness 0.15)
				)
				(justify mirror)
			)
		)
		(property "Tolerance" "1%"
			(at 0 0 0)
			(layer "B.Fab")
			(hide yes)
			(effects
				(font
					(size 1 1)
					(thickness 0.15)
				)
				(justify mirror)
			)
		)
		(property "Val" "1k"
			(at 0 0 0)
			(layer "B.Fab")
			(hide yes)
			(effects
				(font
					(size 1 1)
					(thickness 0.15)
				)
				(justify mirror)
			)
		)
		(sheetname "Supply")
		(sheetfile "supply.kicad_sch")
		(attr smd)
		(fp_rect
			(start -0.925 0.47)
			(end 0.925 -0.47)
			(stroke
				(width 0.05)
				(type default)
			)
			(fill none)
			(layer "B.CrtYd")
		)
		(fp_rect
			(start -0.5 0.25)
			(end 0.5 -0.25)
			(stroke
				(width 0.15)
				(type solid)
			)
			(fill none)
			(layer "B.Fab")
		)
		(fp_text user "${REFERENCE}"
			(at -0.95 -3.168 180)
			(layer "B.Fab")
			(hide yes)
			(effects
				(font
					(size 0.7 0.7)
					(thickness 0.15)
				)
				(justify left bottom mirror)
			)
		)
		(fp_text user "License: Apache-2.0"
			(at -0.95 -5.169 180)
			(layer "B.Fab")
			(hide yes)
			(effects
				(font
					(size 0.7 0.7)
					(thickness 0.15)
				)
				(justify left bottom mirror)
			)
		)
		(fp_text user "Author: Antmicro"
			(at -0.95 -4.169 180)
			(layer "B.Fab")
			(hide yes)
			(effects
				(font
					(size 0.7 0.7)
					(thickness 0.15)
				)
				(justify left bottom mirror)
			)
		)
		(pad "1" smd roundrect
			(at -0.48 0)
			(size 0.59 0.64)
			(layers "B.Cu" "B.Paste" "B.Mask")
			(roundrect_rratio 0.25)
			(net 530 "Net-(R256-Pad1)")
			(pintype "passive")
		)
		(pad "2" smd roundrect
			(at 0.48 0)
			(size 0.59 0.64)
			(layers "B.Cu" "B.Paste" "B.Mask")
			(roundrect_rratio 0.25)
			(net 117 "3V3_STDB")
			(pintype "passive")
		)
	)
	(footprint "antmicro-footprints:R_0402_1005Metric"
		(layer "B.Cu")
		(at 109.1 112 -90)
		(descr "Resistor SMD 0402")
		(tags "resistor SMD 0402")
		(property "Reference" "R60"
			(at 0.75 -0.45 90)
			(layer "B.SilkS")
			(effects
				(font
					(size 0.7 0.7)
					(thickness 0.15)
				)
				(justify left bottom mirror)
			)
		)
		(property "Value" "R_10k_0402"
			(at 0 -1.4 90)
			(layer "B.Fab")
			(effects
				(font
					(size 0.7 0.7)
					(thickness 0.15)
				)
				(justify left bottom mirror)
			)
		)
		(property "Footprint" "antmicro-footprints:R_0402_1005Metric"
			(at 0 0 -90)
			(layer "F.Fab")
			(hide yes)
			(effects
				(font
					(size 1.27 1.27)
					(thickness 0.15)
				)
			)
		)
		(property "Datasheet" "https://www.bourns.com/docs/product-datasheets/cr.pdf"
			(at 0 0 -90)
			(layer "F.Fab")
			(hide yes)
			(effects
				(font
					(size 1.27 1.27)
					(thickness 0.15)
				)
			)
		)
		(property "Author" "Antmicro"
			(at -2.9 221.1 0)
			(layer "B.Fab")
			(hide yes)
			(effects
				(font
					(size 1 1)
					(thickness 0.15)
				)
				(justify mirror)
			)
		)
		(property "License" "Apache-2.0"
			(at -2.9 221.1 0)
			(layer "B.Fab")
			(hide yes)
			(effects
				(font
					(size 1 1)
					(thickness 0.15)
				)
				(justify mirror)
			)
		)
		(property "MPN" "CR0402-FX-1002GLF"
			(at -2.9 221.1 0)
			(layer "B.Fab")
			(hide yes)
			(effects
				(font
					(size 1 1)
					(thickness 0.15)
				)
				(justify mirror)
			)
		)
		(property "Manufacturer" "Bourns"
			(at -2.9 221.1 0)
			(layer "B.Fab")
			(hide yes)
			(effects
				(font
					(size 1 1)
					(thickness 0.15)
				)
				(justify mirror)
			)
		)
		(property "Tolerance" "1%"
			(at -2.9 221.1 0)
			(layer "B.Fab")
			(hide yes)
			(effects
				(font
					(size 1 1)
					(thickness 0.15)
				)
				(justify mirror)
			)
		)
		(property "Val" "10k"
			(at -2.9 221.1 0)
			(layer "B.Fab")
			(hide yes)
			(effects
				(font
					(size 1 1)
					(thickness 0.15)
				)
				(justify mirror)
			)
		)
		(sheetname "USB3")
		(sheetfile "usb3.kicad_sch")
		(attr smd exclude_from_pos_files exclude_from_bom dnp)
		(fp_rect
			(start -0.925 0.47)
			(end 0.925 -0.47)
			(stroke
				(width 0.05)
				(type default)
			)
			(fill none)
			(layer "B.CrtYd")
		)
		(fp_rect
			(start -0.5 0.25)
			(end 0.5 -0.25)
			(stroke
				(width 0.15)
				(type solid)
			)
			(fill none)
			(layer "B.Fab")
		)
		(fp_text user "Author: Antmicro"
			(at -0.95 -4.169 90)
			(layer "B.Fab")
			(hide yes)
			(effects
				(font
					(size 0.7 0.7)
					(thickness 0.15)
				)
				(justify left bottom mirror)
			)
		)
		(fp_text user "${REFERENCE}"
			(at -0.95 -3.168 90)
			(layer "B.Fab")
			(hide yes)
			(effects
				(font
					(size 0.7 0.7)
					(thickness 0.15)
				)
				(justify left bottom mirror)
			)
		)
		(fp_text user "License: Apache-2.0"
			(at -0.95 -5.169 90)
			(layer "B.Fab")
			(hide yes)
			(effects
				(font
					(size 0.7 0.7)
					(thickness 0.15)
				)
				(justify left bottom mirror)
			)
		)
		(pad "1" smd roundrect
			(at -0.48 0 270)
			(size 0.59 0.64)
			(layers "B.Cu" "B.Paste" "B.Mask")
			(roundrect_rratio 0.25)
			(net 632 "Net-(Q19-G)")
			(pintype "passive")
		)
		(pad "2" smd roundrect
			(at 0.48 0 270)
			(size 0.59 0.64)
			(layers "B.Cu" "B.Paste" "B.Mask")
			(roundrect_rratio 0.25)
			(net 270 "/USB3/USBC1_VBUS")
			(pintype "passive")
		)
	)
	(footprint "antmicro-footprints:TP_SMD_0.75mm"
		(layer "B.Cu")
		(at 86.5 102.3008 180)
		(property "Reference" "TP22"
			(at -0.93 0.6808 0)
			(layer "B.SilkS")
			(effects
				(font
					(size 0.7 0.7)
					(thickness 0.15)
				)
				(justify left bottom mirror)
			)
		)
		(property "Value" "TP_0.75mm_SMD"
			(at 0 -1.2 0)
			(layer "B.Fab")
			(effects
				(font
					(size 0.7 0.7)
					(thickness 0.15)
				)
				(justify left bottom mirror)
			)
		)
		(property "Footprint" "antmicro-footprints:TP_SMD_0.75mm"
			(at 0 0 180)
			(layer "F.Fab")
			(hide yes)
			(effects
				(font
					(size 1.27 1.27)
					(thickness 0.15)
				)
			)
		)
		(property "Author" "Antmicro"
			(at 173 204.6016 0)
			(layer "B.Fab")
			(hide yes)
			(effects
				(font
					(size 1 1)
					(thickness 0.15)
				)
				(justify mirror)
			)
		)
		(property "License" "Apache-2.0"
			(at 173 204.6016 0)
			(layer "B.Fab")
			(hide yes)
			(effects
				(font
					(size 1 1)
					(thickness 0.15)
				)
				(justify mirror)
			)
		)
		(property "MPN" ""
			(at 173 204.6016 0)
			(layer "B.Fab")
			(hide yes)
			(effects
				(font
					(size 1 1)
					(thickness 0.15)
				)
				(justify mirror)
			)
		)
		(property "Manufacturer" ""
			(at 173 204.6016 0)
			(layer "B.Fab")
			(hide yes)
			(effects
				(font
					(size 1 1)
					(thickness 0.15)
				)
				(justify mirror)
			)
		)
		(sheetname "HDMI")
		(sheetfile "hdmi.kicad_sch")
		(attr exclude_from_pos_files exclude_from_bom)
		(fp_circle
			(center 0 0)
			(end 0.475 0)
			(stroke
				(width 0.05)
				(type default)
			)
			(fill none)
			(layer "B.CrtYd")
		)
		(fp_text user "License: Apache-2.0"
			(at -0.4 -5.101 0)
			(layer "B.Fab")
			(hide yes)
			(effects
				(font
					(size 0.7 0.7)
					(thickness 0.15)
				)
				(justify left bottom mirror)
			)
		)
		(fp_text user "${REFERENCE}"
			(at -0.4 -2.7 0)
			(layer "B.Fab")
			(hide yes)
			(effects
				(font
					(size 0.7 0.7)
					(thickness 0.15)
				)
				(justify left bottom mirror)
			)
		)
		(fp_text user "Author: Antmicro"
			(at -0.4 -3.901 0)
			(layer "B.Fab")
			(hide yes)
			(effects
				(font
					(size 0.7 0.7)
					(thickness 0.15)
				)
				(justify left bottom mirror)
			)
		)
		(pad "1" smd circle
			(at 0 0 180)
			(size 0.75 0.75)
			(layers "B.Cu" "B.Mask")
			(net 703 "/HDMI/HDMI_HPD")
			(pinfunction "1")
			(pintype "passive")
		)
	)
	(footprint "antmicro-footprints:C_0603_1608Metric"
		(layer "B.Cu")
		(at 76.26 79.55 -90)
		(descr "Capacitor SMD 0603")
		(tags "capacitor 0603")
		(property "Reference" "C134"
			(at -1.45 -1.54 90)
			(layer "B.SilkS")
			(effects
				(font
					(size 0.7 0.7)
					(thickness 0.15)
				)
				(justify left bottom mirror)
			)
		)
		(property "Value" "C_10u_25V_0603"
			(at 0 -1.6 90)
			(layer "B.Fab")
			(effects
				(font
					(size 0.7 0.7)
					(thickness 0.15)
				)
				(justify left bottom mirror)
			)
		)
		(property "Footprint" "antmicro-footprints:C_0603_1608Metric"
			(at 0 0 -90)
			(layer "F.Fab")
			(hide yes)
			(effects
				(font
					(size 1.27 1.27)
					(thickness 0.15)
				)
			)
		)
		(property "Datasheet" "https://product.tdk.com/en/search/capacitor/ceramic/mlcc/info?part_no=C1608X5R1E106M080AC"
			(at 0 0 -90)
			(layer "F.Fab")
			(hide yes)
			(effects
				(font
					(size 1.27 1.27)
					(thickness 0.15)
				)
			)
		)
		(property "Author" "Antmicro"
			(at -3.29 155.81 0)
			(layer "B.Fab")
			(hide yes)
			(effects
				(font
					(size 1 1)
					(thickness 0.15)
				)
				(justify mirror)
			)
		)
		(property "Dielectric" ""
			(at -3.29 155.81 0)
			(layer "B.Fab")
			(hide yes)
			(effects
				(font
					(size 1 1)
					(thickness 0.15)
				)
				(justify mirror)
			)
		)
		(property "License" "Apache-2.0"
			(at -3.29 155.81 0)
			(layer "B.Fab")
			(hide yes)
			(effects
				(font
					(size 1 1)
					(thickness 0.15)
				)
				(justify mirror)
			)
		)
		(property "MPN" "C1608X5R1E106M080AC"
			(at -3.29 155.81 0)
			(layer "B.Fab")
			(hide yes)
			(effects
				(font
					(size 1 1)
					(thickness 0.15)
				)
				(justify mirror)
			)
		)
		(property "Manufacturer" "TDK"
			(at -3.29 155.81 0)
			(layer "B.Fab")
			(hide yes)
			(effects
				(font
					(size 1 1)
					(thickness 0.15)
				)
				(justify mirror)
			)
		)
		(property "Val" "10u"
			(at -3.29 155.81 0)
			(layer "B.Fab")
			(hide yes)
			(effects
				(font
					(size 1 1)
					(thickness 0.15)
				)
				(justify mirror)
			)
		)
		(property "Voltage" "25V"
			(at -3.29 155.81 0)
			(layer "B.Fab")
			(hide yes)
			(effects
				(font
					(size 1 1)
					(thickness 0.15)
				)
				(justify mirror)
			)
		)
		(sheetname "Supply")
		(sheetfile "supply.kicad_sch")
		(attr smd)
		(fp_line
			(start 0.15 0.4)
			(end -0.15 0.4)
			(stroke
				(width 0.15)
				(type solid)
			)
			(layer "B.SilkS")
		)
		(fp_line
			(start 0.15 -0.4)
			(end -0.15 -0.4)
			(stroke
				(width 0.15)
				(type solid)
			)
			(layer "B.SilkS")
		)
		(fp_rect
			(start -1.25 0.65)
			(end 1.25 -0.65)
			(stroke
				(width 0.05)
				(type solid)
			)
			(fill none)
			(layer "B.CrtYd")
		)
		(fp_rect
			(start -0.8 0.4)
			(end 0.8 -0.4)
			(stroke
				(width 0.15)
				(type solid)
			)
			(fill none)
			(layer "B.Fab")
		)
		(fp_text user "License: Apache-2.0"
			(at -1.682 -5.895 90)
			(layer "B.Fab")
			(hide yes)
			(effects
				(font
					(size 0.7 0.7)
					(thickness 0.15)
				)
				(justify left bottom mirror)
			)
		)
		(fp_text user "Author: Antmicro"
			(at -1.682 -4.894 90)
			(layer "B.Fab")
			(hide yes)
			(effects
				(font
					(size 0.7 0.7)
					(thickness 0.15)
				)
				(justify left bottom mirror)
			)
		)
		(fp_text user "${REFERENCE}"
			(at -1.682 -3.895 90)
			(layer "B.Fab")
			(hide yes)
			(effects
				(font
					(size 0.7 0.7)
					(thickness 0.15)
				)
				(justify left bottom mirror)
			)
		)
		(pad "1" smd roundrect
			(at -0.7 0 270)
			(size 0.8 1)
			(layers "B.Cu" "B.Paste" "B.Mask")
			(roundrect_rratio 0.2)
			(net 1 "GND")
			(pintype "passive")
		)
		(pad "2" smd roundrect
			(at 0.7 0 270)
			(size 0.8 1)
			(layers "B.Cu" "B.Paste" "B.Mask")
			(roundrect_rratio 0.2)
			(net 115 "VCC")
			(pintype "passive")
		)
	)
	(footprint "antmicro-footprints:SC-74-6_1.5x2.9mm_P0.95mm"
		(layer "B.Cu")
		(at 109 92.02 180)
		(tags "sc74 sc-74 sot23-6 sot457 tsop6 tsop-6")
		(property "Reference" "U2"
			(at -2.1 -2.33 0)
			(layer "B.SilkS")
			(effects
				(font
					(size 0.7 0.7)
					(thickness 0.15)
				)
				(justify left bottom mirror)
			)
		)
		(property "Value" "74LVC2G07_SOT457"
			(at -2 -2.999 0)
			(layer "B.Fab")
			(effects
				(font
					(size 0.7 0.7)
					(thickness 0.15)
				)
				(justify left bottom mirror)
			)
		)
		(property "Footprint" "antmicro-footprints:SC-74-6_1.5x2.9mm_P0.95mm"
			(at 0 0 180)
			(layer "F.Fab")
			(hide yes)
			(effects
				(font
					(size 1.27 1.27)
					(thickness 0.15)
				)
			)
		)
		(property "Datasheet" "https://www.tme.eu/Document/2ad9356043a4952b9021ef50162f8c34/74LVC2G07.pdf"
			(at 0 0 180)
			(layer "F.Fab")
			(hide yes)
			(effects
				(font
					(size 1.27 1.27)
					(thickness 0.15)
				)
			)
		)
		(property "Author" "Antmicro"
			(at 218 184.04 0)
			(layer "B.Fab")
			(hide yes)
			(effects
				(font
					(size 1 1)
					(thickness 0.15)
				)
				(justify mirror)
			)
		)
		(property "License" "Apache-2.0"
			(at 218 184.04 0)
			(layer "B.Fab")
			(hide yes)
			(effects
				(font
					(size 1 1)
					(thickness 0.15)
				)
				(justify mirror)
			)
		)
		(property "MPN" "74LVC2G07GV,125"
			(at 218 184.04 0)
			(layer "B.Fab")
			(hide yes)
			(effects
				(font
					(size 1 1)
					(thickness 0.15)
				)
				(justify mirror)
			)
		)
		(property "Manufacturer" "Nexperia"
			(at 218 184.04 0)
			(layer "B.Fab")
			(hide yes)
			(effects
				(font
					(size 1 1)
					(thickness 0.15)
				)
				(justify mirror)
			)
		)
		(property ki_fp_filters "SG-74 SOT23-6 TSOP6 SOT457")
		(sheetname "M.2")
		(sheetfile "m-2.kicad_sch")
		(attr smd exclude_from_pos_files exclude_from_bom dnp)
		(fp_circle
			(center -1.11 1.454)
			(end -1.06 1.454)
			(stroke
				(width 0.15)
				(type solid)
			)
			(fill solid)
			(layer "B.SilkS")
		)
		(fp_rect
			(start -1.7 1.7)
			(end 1.7 -1.7)
			(stroke
				(width 0.05)
				(type solid)
			)
			(fill none)
			(layer "B.CrtYd")
		)
		(fp_line
			(start 1.22 1.422)
			(end 1.22 -1.372)
			(stroke
				(width 0.15)
				(type solid)
			)
			(layer "B.Fab")
		)
		(fp_line
			(start 1.22 -1.372)
			(end -1.167 -1.372)
			(stroke
				(width 0.15)
				(type solid)
			)
			(layer "B.Fab")
		)
		(fp_line
			(start -0.76 1.422)
			(end 1.22 1.422)
			(stroke
				(width 0.15)
				(type solid)
			)
			(layer "B.Fab")
		)
		(fp_line
			(start -1.167 -1.372)
			(end -1.269 -1.372)
			(stroke
				(width 0.15)
				(type solid)
			)
			(layer "B.Fab")
		)
		(fp_line
			(start -1.269 0.915)
			(end -0.76 1.422)
			(stroke
				(width 0.15)
				(type solid)
			)
			(layer "B.Fab")
		)
		(fp_line
			(start -1.269 -1.372)
			(end -1.269 0.915)
			(stroke
				(width 0.15)
				(type solid)
			)
			(layer "B.Fab")
		)
		(fp_text user "${REFERENCE}"
			(at -2.12 -7.399 0)
			(layer "B.Fab")
			(hide yes)
			(effects
				(font
					(size 0.7 0.7)
					(thickness 0.15)
				)
				(justify left bottom mirror)
			)
		)
		(fp_text user "License: Apache-2.0"
			(at -2.12 -6.199 0)
			(layer "B.Fab")
			(hide yes)
			(effects
				(font
					(size 0.7 0.7)
					(thickness 0.15)
				)
				(justify left bottom mirror)
			)
		)
		(fp_text user "Author: Antmicro"
			(at -2.12 -4.999 0)
			(layer "B.Fab")
			(hide yes)
			(effects
				(font
					(size 0.7 0.7)
					(thickness 0.15)
				)
				(justify left bottom mirror)
			)
		)
		(pad "1" smd roundrect
			(at -1.2 0.95 180)
			(size 0.8 0.55)
			(layers "B.Cu" "B.Paste" "B.Mask")
			(roundrect_rratio 0.15)
			(net 561 "/M.2/PCIE_WAKE_SEL0")
			(pintype "input")
		)
		(pad "2" smd roundrect
			(at -1.2 0 180)
			(size 0.8 0.55)
			(layers "B.Cu" "B.Paste" "B.Mask")
			(roundrect_rratio 0.15)
			(net 1 "GND")
			(pinfunction "GND")
			(pintype "power_in")
		)
		(pad "3" smd roundrect
			(at -1.2 -0.95 180)
			(size 0.8 0.55)
			(layers "B.Cu" "B.Paste" "B.Mask")
			(roundrect_rratio 0.15)
			(net 454 "PCIE0_CLKREQ*")
			(pintype "input")
		)
		(pad "4" smd roundrect
			(at 1.2 -0.95 180)
			(size 0.8 0.55)
			(layers "B.Cu" "B.Paste" "B.Mask")
			(roundrect_rratio 0.15)
			(net 248 "/M.2/~{M2_M_CLKREQ0}")
			(pintype "output")
		)
		(pad "5" smd roundrect
			(at 1.2 0 180)
			(size 0.8 0.55)
			(layers "B.Cu" "B.Paste" "B.Mask")
			(roundrect_rratio 0.15)
			(net 635 "/M.2/3V3_M2")
			(pinfunction "V_{CC}")
			(pintype "power_in")
		)
		(pad "6" smd roundrect
			(at 1.2 0.95 180)
			(size 0.8 0.55)
			(layers "B.Cu" "B.Paste" "B.Mask")
			(roundrect_rratio 0.15)
			(net 249 "/M.2/~{M2_M_PEWAKE0}")
			(pintype "output")
		)
	)
	(footprint "antmicro-footprints:TP_SMD_0.75mm"
		(layer "B.Cu")
		(at 69 96.3)
		(property "Reference" "TP20"
			(at 4.98 0.79 180)
			(layer "B.SilkS")
			(hide yes)
			(effects
				(font
					(size 0.7 0.7)
					(thickness 0.15)
				)
				(justify left bottom mirror)
			)
		)
		(property "Value" "TP_0.75mm_SMD"
			(at 0 -1.2 180)
			(layer "B.Fab")
			(effects
				(font
					(size 0.7 0.7)
					(thickness 0.15)
				)
				(justify left bottom mirror)
			)
		)
		(property "Footprint" "antmicro-footprints:TP_SMD_0.75mm"
			(at 0 0 0)
			(layer "F.Fab")
			(hide yes)
			(effects
				(font
					(size 1.27 1.27)
					(thickness 0.15)
				)
			)
		)
		(property "Author" "Antmicro"
			(at 0 0 0)
			(layer "B.Fab")
			(hide yes)
			(effects
				(font
					(size 1 1)
					(thickness 0.15)
				)
				(justify mirror)
			)
		)
		(property "License" "Apache-2.0"
			(at 0 0 0)
			(layer "B.Fab")
			(hide yes)
			(effects
				(font
					(size 1 1)
					(thickness 0.15)
				)
				(justify mirror)
			)
		)
		(property "MPN" ""
			(at 0 0 0)
			(layer "B.Fab")
			(hide yes)
			(effects
				(font
					(size 1 1)
					(thickness 0.15)
				)
				(justify mirror)
			)
		)
		(property "Manufacturer" ""
			(at 0 0 0)
			(layer "B.Fab")
			(hide yes)
			(effects
				(font
					(size 1 1)
					(thickness 0.15)
				)
				(justify mirror)
			)
		)
		(sheetname "USB Debug, DP")
		(sheetfile "usb.kicad_sch")
		(attr exclude_from_pos_files exclude_from_bom)
		(fp_circle
			(center 0 0)
			(end 0.475 0)
			(stroke
				(width 0.05)
				(type default)
			)
			(fill none)
			(layer "B.CrtYd")
		)
		(fp_text user "License: Apache-2.0"
			(at -0.4 -5.101 180)
			(layer "B.Fab")
			(hide yes)
			(effects
				(font
					(size 0.7 0.7)
					(thickness 0.15)
				)
				(justify left bottom mirror)
			)
		)
		(fp_text user "Author: Antmicro"
			(at -0.4 -3.901 180)
			(layer "B.Fab")
			(hide yes)
			(effects
				(font
					(size 0.7 0.7)
					(thickness 0.15)
				)
				(justify left bottom mirror)
			)
		)
		(fp_text user "${REFERENCE}"
			(at -0.4 -2.7 180)
			(layer "B.Fab")
			(hide yes)
			(effects
				(font
					(size 0.7 0.7)
					(thickness 0.15)
				)
				(justify left bottom mirror)
			)
		)
		(pad "1" smd circle
			(at 0 0)
			(size 0.75 0.75)
			(layers "B.Cu" "B.Mask")
			(net 396 "/USB Debug, DP/PDC_I2C2_SDA")
			(pinfunction "1")
			(pintype "passive")
		)
	)
	(footprint "antmicro-footprints:R_0402_1005Metric"
		(layer "B.Cu")
		(at 111.6 92 90)
		(descr "Resistor SMD 0402")
		(tags "resistor SMD 0402")
		(property "Reference" "R13"
			(at 0.83 1.38 -90)
			(layer "B.SilkS")
			(effects
				(font
					(size 0.7 0.7)
					(thickness 0.15)
				)
				(justify left bottom mirror)
			)
		)
		(property "Value" "R_0R_0402"
			(at 0 -1.4 -90)
			(layer "B.Fab")
			(effects
				(font
					(size 0.7 0.7)
					(thickness 0.15)
				)
				(justify left bottom mirror)
			)
		)
		(property "Footprint" "antmicro-footprints:R_0402_1005Metric"
			(at 0 0 90)
			(layer "F.Fab")
			(hide yes)
			(effects
				(font
					(size 1.27 1.27)
					(thickness 0.15)
				)
			)
		)
		(property "Datasheet" "https://industrial.panasonic.com/cdbs/www-data/pdf/RDA0000/AOA0000C301.pdf"
			(at 0 0 90)
			(layer "F.Fab")
			(hide yes)
			(effects
				(font
					(size 1.27 1.27)
					(thickness 0.15)
				)
			)
		)
		(property "Author" "Antmicro"
			(at 203.6 -19.6 0)
			(layer "B.Fab")
			(hide yes)
			(effects
				(font
					(size 1 1)
					(thickness 0.15)
				)
				(justify mirror)
			)
		)
		(property "Current" "1A"
			(at 203.6 -19.6 0)
			(layer "B.Fab")
			(hide yes)
			(effects
				(font
					(size 1 1)
					(thickness 0.15)
				)
				(justify mirror)
			)
		)
		(property "License" "Apache-2.0"
			(at 203.6 -19.6 0)
			(layer "B.Fab")
			(hide yes)
			(effects
				(font
					(size 1 1)
					(thickness 0.15)
				)
				(justify mirror)
			)
		)
		(property "MPN" "ERJ2GE0R00X"
			(at 203.6 -19.6 0)
			(layer "B.Fab")
			(hide yes)
			(effects
				(font
					(size 1 1)
					(thickness 0.15)
				)
				(justify mirror)
			)
		)
		(property "Manufacturer" "Panasonic"
			(at 203.6 -19.6 0)
			(layer "B.Fab")
			(hide yes)
			(effects
				(font
					(size 1 1)
					(thickness 0.15)
				)
				(justify mirror)
			)
		)
		(property "Tolerance" ""
			(at 203.6 -19.6 0)
			(layer "B.Fab")
			(hide yes)
			(effects
				(font
					(size 1 1)
					(thickness 0.15)
				)
				(justify mirror)
			)
		)
		(property "Val" "0R"
			(at 203.6 -19.6 0)
			(layer "B.Fab")
			(hide yes)
			(effects
				(font
					(size 1 1)
					(thickness 0.15)
				)
				(justify mirror)
			)
		)
		(sheetname "M.2")
		(sheetfile "m-2.kicad_sch")
		(attr smd)
		(fp_rect
			(start -0.925 0.47)
			(end 0.925 -0.47)
			(stroke
				(width 0.05)
				(type default)
			)
			(fill none)
			(layer "B.CrtYd")
		)
		(fp_rect
			(start -0.5 0.25)
			(end 0.5 -0.25)
			(stroke
				(width 0.15)
				(type solid)
			)
			(fill none)
			(layer "B.Fab")
		)
		(fp_text user "${REFERENCE}"
			(at -0.95 -3.168 -90)
			(layer "B.Fab")
			(hide yes)
			(effects
				(font
					(size 0.7 0.7)
					(thickness 0.15)
				)
				(justify left bottom mirror)
			)
		)
		(fp_text user "Author: Antmicro"
			(at -0.95 -4.169 -90)
			(layer "B.Fab")
			(hide yes)
			(effects
				(font
					(size 0.7 0.7)
					(thickness 0.15)
				)
				(justify left bottom mirror)
			)
		)
		(fp_text user "License: Apache-2.0"
			(at -0.95 -5.169 -90)
			(layer "B.Fab")
			(hide yes)
			(effects
				(font
					(size 0.7 0.7)
					(thickness 0.15)
				)
				(justify left bottom mirror)
			)
		)
		(pad "1" smd roundrect
			(at -0.48 0 90)
			(size 0.59 0.64)
			(layers "B.Cu" "B.Paste" "B.Mask")
			(roundrect_rratio 0.25)
			(net 453 "PCIE_WAKE*")
			(pintype "passive")
		)
		(pad "2" smd roundrect
			(at 0.48 0 90)
			(size 0.59 0.64)
			(layers "B.Cu" "B.Paste" "B.Mask")
			(roundrect_rratio 0.25)
			(net 561 "/M.2/PCIE_WAKE_SEL0")
			(pintype "passive")
		)
	)
	(footprint "antmicro-footprints:R_0402_1005Metric"
		(layer "B.Cu")
		(at 112.5 80.4)
		(descr "Resistor SMD 0402")
		(tags "resistor SMD 0402")
		(property "Reference" "R19"
			(at 1 -0.4 180)
			(layer "B.SilkS")
			(effects
				(font
					(size 0.7 0.7)
					(thickness 0.15)
				)
				(justify left bottom mirror)
			)
		)
		(property "Value" "R_0R_0402"
			(at 0 -1.4 180)
			(layer "B.Fab")
			(effects
				(font
					(size 0.7 0.7)
					(thickness 0.15)
				)
				(justify left bottom mirror)
			)
		)
		(property "Footprint" "antmicro-footprints:R_0402_1005Metric"
			(at 0 0 0)
			(layer "F.Fab")
			(hide yes)
			(effects
				(font
					(size 1.27 1.27)
					(thickness 0.15)
				)
			)
		)
		(property "Datasheet" "https://industrial.panasonic.com/cdbs/www-data/pdf/RDA0000/AOA0000C301.pdf"
			(at 0 0 0)
			(layer "F.Fab")
			(hide yes)
			(effects
				(font
					(size 1.27 1.27)
					(thickness 0.15)
				)
			)
		)
		(property "Author" "Antmicro"
			(at 0 0 0)
			(layer "B.Fab")
			(hide yes)
			(effects
				(font
					(size 1 1)
					(thickness 0.15)
				)
				(justify mirror)
			)
		)
		(property "Current" "1A"
			(at 0 0 0)
			(layer "B.Fab")
			(hide yes)
			(effects
				(font
					(size 1 1)
					(thickness 0.15)
				)
				(justify mirror)
			)
		)
		(property "License" "Apache-2.0"
			(at 0 0 0)
			(layer "B.Fab")
			(hide yes)
			(effects
				(font
					(size 1 1)
					(thickness 0.15)
				)
				(justify mirror)
			)
		)
		(property "MPN" "ERJ2GE0R00X"
			(at 0 0 0)
			(layer "B.Fab")
			(hide yes)
			(effects
				(font
					(size 1 1)
					(thickness 0.15)
				)
				(justify mirror)
			)
		)
		(property "Manufacturer" "Panasonic"
			(at 0 0 0)
			(layer "B.Fab")
			(hide yes)
			(effects
				(font
					(size 1 1)
					(thickness 0.15)
				)
				(justify mirror)
			)
		)
		(property "Tolerance" ""
			(at 0 0 0)
			(layer "B.Fab")
			(hide yes)
			(effects
				(font
					(size 1 1)
					(thickness 0.15)
				)
				(justify mirror)
			)
		)
		(property "Val" "0R"
			(at 0 0 0)
			(layer "B.Fab")
			(hide yes)
			(effects
				(font
					(size 1 1)
					(thickness 0.15)
				)
				(justify mirror)
			)
		)
		(sheetname "M.2")
		(sheetfile "m-2.kicad_sch")
		(attr smd)
		(fp_rect
			(start -0.925 0.47)
			(end 0.925 -0.47)
			(stroke
				(width 0.05)
				(type default)
			)
			(fill none)
			(layer "B.CrtYd")
		)
		(fp_rect
			(start -0.5 0.25)
			(end 0.5 -0.25)
			(stroke
				(width 0.15)
				(type solid)
			)
			(fill none)
			(layer "B.Fab")
		)
		(fp_text user "Author: Antmicro"
			(at -0.95 -4.169 180)
			(layer "B.Fab")
			(hide yes)
			(effects
				(font
					(size 0.7 0.7)
					(thickness 0.15)
				)
				(justify left bottom mirror)
			)
		)
		(fp_text user "License: Apache-2.0"
			(at -0.95 -5.169 180)
			(layer "B.Fab")
			(hide yes)
			(effects
				(font
					(size 0.7 0.7)
					(thickness 0.15)
				)
				(justify left bottom mirror)
			)
		)
		(fp_text user "${REFERENCE}"
			(at -0.95 -3.168 180)
			(layer "B.Fab")
			(hide yes)
			(effects
				(font
					(size 0.7 0.7)
					(thickness 0.15)
				)
				(justify left bottom mirror)
			)
		)
		(pad "1" smd roundrect
			(at -0.48 0)
			(size 0.59 0.64)
			(layers "B.Cu" "B.Paste" "B.Mask")
			(roundrect_rratio 0.25)
			(net 456 "/M.2/32.7KHZ_OUT")
			(pintype "passive")
		)
		(pad "2" smd roundrect
			(at 0.48 0)
			(size 0.59 0.64)
			(layers "B.Cu" "B.Paste" "B.Mask")
			(roundrect_rratio 0.25)
			(net 250 "/M.2/M2_M_SUSCLK")
			(pintype "passive")
		)
	)
	(footprint "antmicro-footprints:SOD-923"
		(layer "B.Cu")
		(at 53.4 76.8 90)
		(property "Reference" "D29"
			(at -7.4 21.75 90)
			(unlocked yes)
			(layer "B.SilkS")
			(effects
				(font
					(size 0.7 0.7)
					(thickness 0.15)
				)
				(justify left bottom mirror)
			)
		)
		(property "Value" "DF2S30FS_SOD"
			(at 0 -1.3 -90)
			(unlocked yes)
			(layer "B.Fab")
			(effects
				(font
					(size 0.7 0.7)
					(thickness 0.15)
				)
				(justify left bottom mirror)
			)
		)
		(property "Footprint" "antmicro-footprints:SOD-923"
			(at 0 0 90)
			(layer "F.Fab")
			(hide yes)
			(effects
				(font
					(size 1.27 1.27)
					(thickness 0.15)
				)
			)
		)
		(property "Datasheet" "https://toshiba.semicon-storage.com/info/DF2S30FS_datasheet_en_20211216.pdf?did=11156&prodName=DF2S30FS"
			(at 0 0 90)
			(layer "F.Fab")
			(hide yes)
			(effects
				(font
					(size 1.27 1.27)
					(thickness 0.15)
				)
			)
		)
		(property "Author" "Antmicro"
			(at 130.2 23.4 0)
			(layer "B.Fab")
			(hide yes)
			(effects
				(font
					(size 1 1)
					(thickness 0.15)
				)
				(justify mirror)
			)
		)
		(property "License" "Apache-2.0"
			(at 130.2 23.4 0)
			(layer "B.Fab")
			(hide yes)
			(effects
				(font
					(size 1 1)
					(thickness 0.15)
				)
				(justify mirror)
			)
		)
		(property "MPN" "DF2S30FS"
			(at 130.2 23.4 0)
			(layer "B.Fab")
			(hide yes)
			(effects
				(font
					(size 1 1)
					(thickness 0.15)
				)
				(justify mirror)
			)
		)
		(property "Manufacturer" "Toshiba"
			(at 130.2 23.4 0)
			(layer "B.Fab")
			(hide yes)
			(effects
				(font
					(size 1 1)
					(thickness 0.15)
				)
				(justify mirror)
			)
		)
		(sheetname "Supply")
		(sheetfile "supply.kicad_sch")
		(attr smd)
		(fp_line
			(start 0.5 -0.4)
			(end -0.5 -0.4)
			(stroke
				(width 0.15)
				(type solid)
			)
			(layer "B.SilkS")
		)
		(fp_line
			(start -0.16 -0.4)
			(end -0.16 0.4)
			(stroke
				(width 0.15)
				(type solid)
			)
			(layer "B.SilkS")
		)
		(fp_line
			(start 0.5 -0.3)
			(end 0.5 -0.4)
			(stroke
				(width 0.15)
				(type solid)
			)
			(layer "B.SilkS")
		)
		(fp_line
			(start -0.5 -0.3)
			(end -0.5 -0.4)
			(stroke
				(width 0.15)
				(type solid)
			)
			(layer "B.SilkS")
		)
		(fp_line
			(start 0.5 0.3)
			(end 0.5 0.4)
			(stroke
				(width 0.15)
				(type solid)
			)
			(layer "B.SilkS")
		)
		(fp_line
			(start 0.5 0.4)
			(end -0.5 0.4)
			(stroke
				(width 0.15)
				(type solid)
			)
			(layer "B.SilkS")
		)
		(fp_line
			(start -0.5 0.4)
			(end -0.5 0.3)
			(stroke
				(width 0.15)
				(type solid)
			)
			(layer "B.SilkS")
		)
		(fp_rect
			(start -0.68 0.41)
			(end 0.68 -0.41)
			(stroke
				(width 0.05)
				(type solid)
			)
			(fill none)
			(layer "B.CrtYd")
		)
		(fp_line
			(start -0.202 -0.298)
			(end -0.202 0.3)
			(stroke
				(width 0.15)
				(type solid)
			)
			(layer "B.Fab")
		)
		(fp_rect
			(start -0.402 0.3)
			(end 0.4 -0.298)
			(stroke
				(width 0.15)
				(type solid)
			)
			(fill none)
			(layer "B.Fab")
		)
		(fp_text user "Author: Antmicro"
			(at -0.68 -5.7 -90)
			(layer "B.Fab")
			(hide yes)
			(effects
				(font
					(size 0.7 0.7)
					(thickness 0.15)
				)
				(justify left bottom mirror)
			)
		)
		(fp_text user "License: Apache-2.0"
			(at -0.68 -4.5 -90)
			(layer "B.Fab")
			(hide yes)
			(effects
				(font
					(size 0.7 0.7)
					(thickness 0.15)
				)
				(justify left bottom mirror)
			)
		)
		(fp_text user "${REFERENCE}"
			(at -0.68 -3.3 -90)
			(unlocked yes)
			(layer "B.Fab")
			(hide yes)
			(effects
				(font
					(size 0.7 0.7)
					(thickness 0.15)
				)
				(justify left bottom mirror)
			)
		)
		(pad "1" smd roundrect
			(at -0.438 0 90)
			(size 0.4 0.325)
			(layers "B.Cu" "B.Paste" "B.Mask")
			(roundrect_rratio 0.25)
			(net 115 "VCC")
			(pinfunction "C")
			(pintype "passive")
		)
		(pad "2" smd roundrect
			(at 0.436 0 90)
			(size 0.4 0.325)
			(layers "B.Cu" "B.Paste" "B.Mask")
			(roundrect_rratio 0.25)
			(net 1 "GND")
			(pinfunction "A")
			(pintype "passive")
		)
	)
	(footprint "antmicro-footprints:C_0402_1005Metric"
		(layer "B.Cu")
		(at 39.608 117.856 -90)
		(descr "Capacitor SMD 0402")
		(tags "capacitor SMD 0402")
		(property "Reference" "C78"
			(at -1.206 1.458 90)
			(layer "B.SilkS")
			(effects
				(font
					(size 0.7 0.7)
					(thickness 0.15)
				)
				(justify left bottom mirror)
			)
		)
		(property "Value" "C_100n_0402"
			(at 0 -1.4 90)
			(layer "B.Fab")
			(effects
				(font
					(size 0.7 0.7)
					(thickness 0.15)
				)
				(justify left bottom mirror)
			)
		)
		(property "Footprint" "antmicro-footprints:C_0402_1005Metric"
			(at 0 0 -90)
			(layer "F.Fab")
			(hide yes)
			(effects
				(font
					(size 1.27 1.27)
					(thickness 0.15)
				)
			)
		)
		(property "Datasheet" "https://www.murata.com/products/productdetail?partno=GRM155R61H104KE14%23"
			(at 0 0 -90)
			(layer "F.Fab")
			(hide yes)
			(effects
				(font
					(size 1.27 1.27)
					(thickness 0.15)
				)
			)
		)
		(property "Author" "Antmicro"
			(at -78.248 157.464 0)
			(layer "B.Fab")
			(hide yes)
			(effects
				(font
					(size 1 1)
					(thickness 0.15)
				)
				(justify mirror)
			)
		)
		(property "Dielectric" "X5R"
			(at -78.248 157.464 0)
			(layer "B.Fab")
			(hide yes)
			(effects
				(font
					(size 1 1)
					(thickness 0.15)
				)
				(justify mirror)
			)
		)
		(property "License" "Apache-2.0"
			(at -78.248 157.464 0)
			(layer "B.Fab")
			(hide yes)
			(effects
				(font
					(size 1 1)
					(thickness 0.15)
				)
				(justify mirror)
			)
		)
		(property "MPN" "GRM155R61H104KE14D"
			(at -78.248 157.464 0)
			(layer "B.Fab")
			(hide yes)
			(effects
				(font
					(size 1 1)
					(thickness 0.15)
				)
				(justify mirror)
			)
		)
		(property "Manufacturer" "Murata"
			(at -78.248 157.464 0)
			(layer "B.Fab")
			(hide yes)
			(effects
				(font
					(size 1 1)
					(thickness 0.15)
				)
				(justify mirror)
			)
		)
		(property "Val" "100n"
			(at -78.248 157.464 0)
			(layer "B.Fab")
			(hide yes)
			(effects
				(font
					(size 1 1)
					(thickness 0.15)
				)
				(justify mirror)
			)
		)
		(property "Voltage" "50V"
			(at -78.248 157.464 0)
			(layer "B.Fab")
			(hide yes)
			(effects
				(font
					(size 1 1)
					(thickness 0.15)
				)
				(justify mirror)
			)
		)
		(sheetname "Ethernet")
		(sheetfile "ethernet.kicad_sch")
		(attr smd)
		(fp_rect
			(start -0.925 0.47)
			(end 0.925 -0.47)
			(stroke
				(width 0.05)
				(type default)
			)
			(fill none)
			(layer "B.CrtYd")
		)
		(fp_line
			(start -0.494 0.25)
			(end -0.494 -0.248)
			(stroke
				(width 0.15)
				(type solid)
			)
			(layer "B.Fab")
		)
		(fp_line
			(start 0.504 0.25)
			(end -0.494 0.25)
			(stroke
				(width 0.15)
				(type solid)
			)
			(layer "B.Fab")
		)
		(fp_line
			(start -0.494 -0.248)
			(end 0.504 -0.248)
			(stroke
				(width 0.15)
				(type solid)
			)
			(layer "B.Fab")
		)
		(fp_line
			(start 0.504 -0.248)
			(end 0.504 0.25)
			(stroke
				(width 0.15)
				(type solid)
			)
			(layer "B.Fab")
		)
		(fp_text user "License: Apache-2.0"
			(at -0.932 -5.17 90)
			(layer "B.Fab")
			(hide yes)
			(effects
				(font
					(size 0.7 0.7)
					(thickness 0.15)
				)
				(justify left bottom mirror)
			)
		)
		(fp_text user "Author: Antmicro"
			(at -0.932 -4.17 90)
			(layer "B.Fab")
			(hide yes)
			(effects
				(font
					(size 0.7 0.7)
					(thickness 0.15)
				)
				(justify left bottom mirror)
			)
		)
		(fp_text user "${REFERENCE}"
			(at -0.932 -3.168 90)
			(layer "B.Fab")
			(hide yes)
			(effects
				(font
					(size 0.7 0.7)
					(thickness 0.15)
				)
				(justify left bottom mirror)
			)
		)
		(pad "1" smd roundrect
			(at -0.48 0 270)
			(size 0.59 0.64)
			(layers "B.Cu" "B.Paste" "B.Mask")
			(roundrect_rratio 0.25)
			(net 715 "Net-(C78-Pad1)")
			(pintype "passive")
		)
		(pad "2" smd roundrect
			(at 0.48 0 270)
			(size 0.59 0.64)
			(layers "B.Cu" "B.Paste" "B.Mask")
			(roundrect_rratio 0.25)
			(net 1 "GND")
			(pintype "passive")
		)
	)
	(footprint "antmicro-footprints:C_0402_1005Metric"
		(layer "B.Cu")
		(at 126.735 89.75)
		(descr "Capacitor SMD 0402")
		(tags "capacitor SMD 0402")
		(property "Reference" "C15"
			(at 2.965 0.45 180)
			(layer "B.SilkS")
			(effects
				(font
					(size 0.7 0.7)
					(thickness 0.15)
				)
				(justify left bottom mirror)
			)
		)
		(property "Value" "C_220n_0402"
			(at 0 -1.4 180)
			(layer "B.Fab")
			(effects
				(font
					(size 0.7 0.7)
					(thickness 0.15)
				)
				(justify left bottom mirror)
			)
		)
		(property "Footprint" "antmicro-footprints:C_0402_1005Metric"
			(at 0 0 0)
			(layer "F.Fab")
			(hide yes)
			(effects
				(font
					(size 1.27 1.27)
					(thickness 0.15)
				)
			)
		)
		(property "Datasheet" "https://www.yageo.com/en/Chart/Download/pdf/CC0402KRX5R6BB224"
			(at 0 0 0)
			(layer "F.Fab")
			(hide yes)
			(effects
				(font
					(size 1.27 1.27)
					(thickness 0.15)
				)
			)
		)
		(property "Author" "Antmicro"
			(at 0 0 0)
			(layer "B.Fab")
			(hide yes)
			(effects
				(font
					(size 1 1)
					(thickness 0.15)
				)
				(justify mirror)
			)
		)
		(property "Dielectric" ""
			(at 0 0 0)
			(layer "B.Fab")
			(hide yes)
			(effects
				(font
					(size 1 1)
					(thickness 0.15)
				)
				(justify mirror)
			)
		)
		(property "License" "Apache-2.0"
			(at 0 0 0)
			(layer "B.Fab")
			(hide yes)
			(effects
				(font
					(size 1 1)
					(thickness 0.15)
				)
				(justify mirror)
			)
		)
		(property "MPN" "CC0402KRX5R6BB224"
			(at 0 0 0)
			(layer "B.Fab")
			(hide yes)
			(effects
				(font
					(size 1 1)
					(thickness 0.15)
				)
				(justify mirror)
			)
		)
		(property "Manufacturer" "YAGEO"
			(at 0 0 0)
			(layer "B.Fab")
			(hide yes)
			(effects
				(font
					(size 1 1)
					(thickness 0.15)
				)
				(justify mirror)
			)
		)
		(property "Val" "220n"
			(at 0 0 0)
			(layer "B.Fab")
			(hide yes)
			(effects
				(font
					(size 1 1)
					(thickness 0.15)
				)
				(justify mirror)
			)
		)
		(property "Voltage" ""
			(at 0 0 0)
			(layer "B.Fab")
			(hide yes)
			(effects
				(font
					(size 1 1)
					(thickness 0.15)
				)
				(justify mirror)
			)
		)
		(sheetname "M.2")
		(sheetfile "m-2.kicad_sch")
		(attr smd)
		(fp_rect
			(start -0.925 0.47)
			(end 0.925 -0.47)
			(stroke
				(width 0.05)
				(type default)
			)
			(fill none)
			(layer "B.CrtYd")
		)
		(fp_line
			(start -0.494 -0.248)
			(end 0.504 -0.248)
			(stroke
				(width 0.15)
				(type solid)
			)
			(layer "B.Fab")
		)
		(fp_line
			(start -0.494 0.25)
			(end -0.494 -0.248)
			(stroke
				(width 0.15)
				(type solid)
			)
			(layer "B.Fab")
		)
		(fp_line
			(start 0.504 -0.248)
			(end 0.504 0.25)
			(stroke
				(width 0.15)
				(type solid)
			)
			(layer "B.Fab")
		)
		(fp_line
			(start 0.504 0.25)
			(end -0.494 0.25)
			(stroke
				(width 0.15)
				(type solid)
			)
			(layer "B.Fab")
		)
		(fp_text user "Author: Antmicro"
			(at -0.932 -4.17 180)
			(layer "B.Fab")
			(hide yes)
			(effects
				(font
					(size 0.7 0.7)
					(thickness 0.15)
				)
				(justify left bottom mirror)
			)
		)
		(fp_text user "${REFERENCE}"
			(at -0.932 -3.168 180)
			(layer "B.Fab")
			(hide yes)
			(effects
				(font
					(size 0.7 0.7)
					(thickness 0.15)
				)
				(justify left bottom mirror)
			)
		)
		(fp_text user "License: Apache-2.0"
			(at -0.932 -5.17 180)
			(layer "B.Fab")
			(hide yes)
			(effects
				(font
					(size 0.7 0.7)
					(thickness 0.15)
				)
				(justify left bottom mirror)
			)
		)
		(pad "1" smd roundrect
			(at -0.48 0)
			(size 0.59 0.64)
			(layers "B.Cu" "B.Paste" "B.Mask")
			(roundrect_rratio 0.25)
			(net 92 "/M.2/C_PCIE0_TX2_P")
			(pintype "passive")
		)
		(pad "2" smd roundrect
			(at 0.48 0)
			(size 0.59 0.64)
			(layers "B.Cu" "B.Paste" "B.Mask")
			(roundrect_rratio 0.25)
			(net 446 "PCIE0_TX2_P")
			(pintype "passive")
		)
	)
	(footprint "antmicro-footprints:R_0402_1005Metric"
		(layer "B.Cu")
		(at 67.2 110.25 90)
		(descr "Resistor SMD 0402")
		(tags "resistor SMD 0402")
		(property "Reference" "R42"
			(at -0.98 0.35 -90)
			(layer "B.SilkS")
			(effects
				(font
					(size 0.7 0.7)
					(thickness 0.15)
				)
				(justify left bottom mirror)
			)
		)
		(property "Value" "R_10k_0402"
			(at 0 -1.4 -90)
			(layer "B.Fab")
			(effects
				(font
					(size 0.7 0.7)
					(thickness 0.15)
				)
				(justify left bottom mirror)
			)
		)
		(property "Footprint" "antmicro-footprints:R_0402_1005Metric"
			(at 0 0 90)
			(layer "F.Fab")
			(hide yes)
			(effects
				(font
					(size 1.27 1.27)
					(thickness 0.15)
				)
			)
		)
		(property "Datasheet" "https://www.bourns.com/docs/product-datasheets/cr.pdf"
			(at 0 0 90)
			(layer "F.Fab")
			(hide yes)
			(effects
				(font
					(size 1.27 1.27)
					(thickness 0.15)
				)
			)
		)
		(property "Author" "Antmicro"
			(at 177.45 43.05 0)
			(layer "B.Fab")
			(hide yes)
			(effects
				(font
					(size 1 1)
					(thickness 0.15)
				)
				(justify mirror)
			)
		)
		(property "License" "Apache-2.0"
			(at 177.45 43.05 0)
			(layer "B.Fab")
			(hide yes)
			(effects
				(font
					(size 1 1)
					(thickness 0.15)
				)
				(justify mirror)
			)
		)
		(property "MPN" "CR0402-FX-1002GLF"
			(at 177.45 43.05 0)
			(layer "B.Fab")
			(hide yes)
			(effects
				(font
					(size 1 1)
					(thickness 0.15)
				)
				(justify mirror)
			)
		)
		(property "Manufacturer" "Bourns"
			(at 177.45 43.05 0)
			(layer "B.Fab")
			(hide yes)
			(effects
				(font
					(size 1 1)
					(thickness 0.15)
				)
				(justify mirror)
			)
		)
		(property "Tolerance" "1%"
			(at 177.45 43.05 0)
			(layer "B.Fab")
			(hide yes)
			(effects
				(font
					(size 1 1)
					(thickness 0.15)
				)
				(justify mirror)
			)
		)
		(property "Val" "10k"
			(at 177.45 43.05 0)
			(layer "B.Fab")
			(hide yes)
			(effects
				(font
					(size 1 1)
					(thickness 0.15)
				)
				(justify mirror)
			)
		)
		(sheetname "USB Debug, DP")
		(sheetfile "usb.kicad_sch")
		(attr smd)
		(fp_rect
			(start -0.925 0.47)
			(end 0.925 -0.47)
			(stroke
				(width 0.05)
				(type default)
			)
			(fill none)
			(layer "B.CrtYd")
		)
		(fp_rect
			(start -0.5 0.25)
			(end 0.5 -0.25)
			(stroke
				(width 0.15)
				(type solid)
			)
			(fill none)
			(layer "B.Fab")
		)
		(fp_text user "${REFERENCE}"
			(at -0.95 -3.168 -90)
			(layer "B.Fab")
			(hide yes)
			(effects
				(font
					(size 0.7 0.7)
					(thickness 0.15)
				)
				(justify left bottom mirror)
			)
		)
		(fp_text user "Author: Antmicro"
			(at -0.95 -4.169 -90)
			(layer "B.Fab")
			(hide yes)
			(effects
				(font
					(size 0.7 0.7)
					(thickness 0.15)
				)
				(justify left bottom mirror)
			)
		)
		(fp_text user "License: Apache-2.0"
			(at -0.95 -5.169 -90)
			(layer "B.Fab")
			(hide yes)
			(effects
				(font
					(size 0.7 0.7)
					(thickness 0.15)
				)
				(justify left bottom mirror)
			)
		)
		(pad "1" smd roundrect
			(at -0.48 0 90)
			(size 0.59 0.64)
			(layers "B.Cu" "B.Paste" "B.Mask")
			(roundrect_rratio 0.25)
			(net 134 "/USB Debug, DP/PDC_LDO_3V3")
			(pintype "passive")
		)
		(pad "2" smd roundrect
			(at 0.48 0 90)
			(size 0.59 0.64)
			(layers "B.Cu" "B.Paste" "B.Mask")
			(roundrect_rratio 0.25)
			(net 286 "/USB Debug, DP/PDC_ADCIN1")
			(pintype "passive")
		)
	)
	(footprint "antmicro-footprints:XDFN-2_1x0.60mm"
		(layer "B.Cu")
		(at 120.25 127.1)
		(property "Reference" "D58"
			(at -1.1 -0.55 180)
			(layer "B.SilkS")
			(effects
				(font
					(size 0.7 0.7)
					(thickness 0.15)
				)
				(justify right bottom mirror)
			)
		)
		(property "Value" "TPD1E0B04_XDFN-2"
			(at 0 -1.5 180)
			(layer "B.Fab")
			(effects
				(font
					(size 0.7 0.7)
					(thickness 0.15)
				)
				(justify left bottom mirror)
			)
		)
		(property "Footprint" "antmicro-footprints:XDFN-2_1x0.60mm"
			(at 0 0 0)
			(layer "F.Fab")
			(hide yes)
			(effects
				(font
					(size 1.27 1.27)
					(thickness 0.15)
				)
			)
		)
		(property "Datasheet" "https://www.ti.com/general/docs/suppproductinfo.tsp?distId=26&gotoUrl=https://www.ti.com/lit/gpn/tpd1e0b04"
			(at 0 0 0)
			(layer "F.Fab")
			(hide yes)
			(effects
				(font
					(size 1.27 1.27)
					(thickness 0.15)
				)
			)
		)
		(property "MPN" "TPD1E0B04DPYR"
			(at 0 0 0)
			(layer "B.Fab")
			(hide yes)
			(effects
				(font
					(size 1 1)
					(thickness 0.15)
				)
				(justify mirror)
			)
		)
		(property "Manufacturer" "Texas Instruments"
			(at 0 0 0)
			(layer "B.Fab")
			(hide yes)
			(effects
				(font
					(size 1 1)
					(thickness 0.15)
				)
				(justify mirror)
			)
		)
		(property "Author" "Antmicro"
			(at 0 0 0)
			(layer "B.Fab")
			(hide yes)
			(effects
				(font
					(size 1 1)
					(thickness 0.15)
				)
				(justify mirror)
			)
		)
		(property "License" "Apache-2.0"
			(at 0 0 0)
			(layer "B.Fab")
			(hide yes)
			(effects
				(font
					(size 1 1)
					(thickness 0.15)
				)
				(justify mirror)
			)
		)
		(sheetname "Peripherals")
		(sheetfile "peripherals.kicad_sch")
		(attr smd)
		(fp_rect
			(start -0.725 0.475)
			(end 0.725 -0.475)
			(stroke
				(width 0.05)
				(type solid)
			)
			(fill none)
			(layer "B.CrtYd")
		)
		(fp_rect
			(start -0.55 0.35)
			(end 0.55 -0.35)
			(stroke
				(width 0.15)
				(type solid)
			)
			(fill none)
			(layer "B.Fab")
		)
		(fp_text user "${REFERENCE}"
			(at -0.8 -3.2 180)
			(layer "B.Fab")
			(hide yes)
			(effects
				(font
					(size 0.7 0.7)
					(thickness 0.15)
				)
				(justify left bottom mirror)
			)
		)
		(fp_text user "License: Apache-2.0"
			(at -0.8 -5.6 180)
			(layer "B.Fab")
			(hide yes)
			(effects
				(font
					(size 0.7 0.7)
					(thickness 0.15)
				)
				(justify left bottom mirror)
			)
		)
		(fp_text user "Author: Antmicro"
			(at -0.8 -4.4 180)
			(layer "B.Fab")
			(hide yes)
			(effects
				(font
					(size 0.7 0.7)
					(thickness 0.15)
				)
				(justify left bottom mirror)
			)
		)
		(pad "1" smd roundrect
			(at -0.351 0)
			(size 0.3 0.5)
			(layers "B.Cu" "B.Paste" "B.Mask")
			(roundrect_rratio 0.25)
			(net 1 "GND")
			(pinfunction "C")
			(pintype "passive")
		)
		(pad "2" smd roundrect
			(at 0.349 0)
			(size 0.3 0.5)
			(layers "B.Cu" "B.Paste" "B.Mask")
			(roundrect_rratio 0.25)
			(net 45 "USER_BTN0")
			(pinfunction "A")
			(pintype "passive")
		)
	)
	(footprint "antmicro-footprints:R_0402_1005Metric"
		(layer "B.Cu")
		(at 52.55 110.15 180)
		(descr "Resistor SMD 0402")
		(tags "resistor SMD 0402")
		(property "Reference" "R111"
			(at -1.122484 0.772697 0)
			(layer "B.SilkS")
			(effects
				(font
					(size 0.7 0.7)
					(thickness 0.15)
				)
				(justify left bottom mirror)
			)
		)
		(property "Value" "R_1k_0402"
			(at -1.011843 -1.772047 0)
			(layer "B.Fab")
			(effects
				(font
					(size 0.7 0.7)
					(thickness 0.15)
				)
				(justify left bottom mirror)
			)
		)
		(property "Footprint" "antmicro-footprints:R_0402_1005Metric"
			(at 0 0 180)
			(layer "F.Fab")
			(hide yes)
			(effects
				(font
					(size 1.27 1.27)
					(thickness 0.15)
				)
			)
		)
		(property "Datasheet" "https://www.bourns.com/docs/product-datasheets/cr.pdf"
			(at 0 0 180)
			(layer "F.Fab")
			(hide yes)
			(effects
				(font
					(size 1.27 1.27)
					(thickness 0.15)
				)
			)
		)
		(property "Author" "Antmicro"
			(at 105.1 220.3 0)
			(layer "B.Fab")
			(hide yes)
			(effects
				(font
					(size 1 1)
					(thickness 0.15)
				)
				(justify mirror)
			)
		)
		(property "License" "Apache-2.0"
			(at 105.1 220.3 0)
			(layer "B.Fab")
			(hide yes)
			(effects
				(font
					(size 1 1)
					(thickness 0.15)
				)
				(justify mirror)
			)
		)
		(property "MPN" "CR0402-FX-1001GLF"
			(at 105.1 220.3 0)
			(layer "B.Fab")
			(hide yes)
			(effects
				(font
					(size 1 1)
					(thickness 0.15)
				)
				(justify mirror)
			)
		)
		(property "Manufacturer" "Bourns"
			(at 105.1 220.3 0)
			(layer "B.Fab")
			(hide yes)
			(effects
				(font
					(size 1 1)
					(thickness 0.15)
				)
				(justify mirror)
			)
		)
		(property "Tolerance" "1%"
			(at 105.1 220.3 0)
			(layer "B.Fab")
			(hide yes)
			(effects
				(font
					(size 1 1)
					(thickness 0.15)
				)
				(justify mirror)
			)
		)
		(property "Val" "1k"
			(at 105.1 220.3 0)
			(layer "B.Fab")
			(hide yes)
			(effects
				(font
					(size 1 1)
					(thickness 0.15)
				)
				(justify mirror)
			)
		)
		(sheetname "USB Debug, DP")
		(sheetfile "usb.kicad_sch")
		(attr smd)
		(fp_rect
			(start -0.925 0.47)
			(end 0.925 -0.47)
			(stroke
				(width 0.05)
				(type default)
			)
			(fill none)
			(layer "B.CrtYd")
		)
		(fp_rect
			(start -0.5 0.25)
			(end 0.5 -0.25)
			(stroke
				(width 0.15)
				(type solid)
			)
			(fill none)
			(layer "B.Fab")
		)
		(fp_text user "License: Apache-2.0"
			(at -0.95 -5.169 0)
			(layer "B.Fab")
			(hide yes)
			(effects
				(font
					(size 0.7 0.7)
					(thickness 0.15)
				)
				(justify left bottom mirror)
			)
		)
		(fp_text user "${REFERENCE}"
			(at -0.95 -3.168 0)
			(layer "B.Fab")
			(hide yes)
			(effects
				(font
					(size 0.7 0.7)
					(thickness 0.15)
				)
				(justify left bottom mirror)
			)
		)
		(fp_text user "Author: Antmicro"
			(at -0.95 -4.169 0)
			(layer "B.Fab")
			(hide yes)
			(effects
				(font
					(size 0.7 0.7)
					(thickness 0.15)
				)
				(justify left bottom mirror)
			)
		)
		(pad "1" smd roundrect
			(at -0.48 0 180)
			(size 0.59 0.64)
			(layers "B.Cu" "B.Paste" "B.Mask")
			(roundrect_rratio 0.25)
			(net 398 "/USB Debug, DP/FTDI_CBUS3{slash}SCL")
			(pintype "passive")
		)
		(pad "2" smd roundrect
			(at 0.48 0 180)
			(size 0.59 0.64)
			(layers "B.Cu" "B.Paste" "B.Mask")
			(roundrect_rratio 0.25)
			(net 185 "/USB Debug, DP/FTDI_3V3")
			(pintype "passive")
		)
	)
	(footprint "antmicro-footprints:SOT-523"
		(layer "B.Cu")
		(at 61 73.1 90)
		(property "Reference" "Q7"
			(at 1.01 0.71 0)
			(layer "B.SilkS")
			(effects
				(font
					(size 0.7 0.7)
					(thickness 0.15)
				)
				(justify left bottom mirror)
			)
		)
		(property "Value" "PJE138K"
			(at 0.1 -1.824 -90)
			(layer "B.Fab")
			(effects
				(font
					(size 0.7 0.7)
					(thickness 0.15)
				)
				(justify left bottom mirror)
			)
		)
		(property "Footprint" "antmicro-footprints:SOT-523"
			(at 0 0 90)
			(layer "F.Fab")
			(hide yes)
			(effects
				(font
					(size 1.27 1.27)
					(thickness 0.15)
				)
			)
		)
		(property "Datasheet" "https://www.mouser.com/datasheet/2/1057/PJE138K-1876698.pdf"
			(at 0 0 90)
			(layer "F.Fab")
			(hide yes)
			(effects
				(font
					(size 1.27 1.27)
					(thickness 0.15)
				)
			)
		)
		(property "Author" "Antmicro"
			(at 134.1 12.1 0)
			(layer "B.Fab")
			(hide yes)
			(effects
				(font
					(size 1 1)
					(thickness 0.15)
				)
				(justify mirror)
			)
		)
		(property "License" "Apache-2.0"
			(at 134.1 12.1 0)
			(layer "B.Fab")
			(hide yes)
			(effects
				(font
					(size 1 1)
					(thickness 0.15)
				)
				(justify mirror)
			)
		)
		(property "MPN" "PJE138K_R1_00001"
			(at 134.1 12.1 0)
			(layer "B.Fab")
			(hide yes)
			(effects
				(font
					(size 1 1)
					(thickness 0.15)
				)
				(justify mirror)
			)
		)
		(property "Manufacturer" "PANJIT"
			(at 134.1 12.1 0)
			(layer "B.Fab")
			(hide yes)
			(effects
				(font
					(size 1 1)
					(thickness 0.15)
				)
				(justify mirror)
			)
		)
		(sheetname "Supply")
		(sheetfile "supply.kicad_sch")
		(attr smd)
		(fp_line
			(start -0.927 0.351)
			(end -0.927 0.051)
			(stroke
				(width 0.15)
				(type solid)
			)
			(layer "B.SilkS")
		)
		(fp_line
			(start -0.277 0.551)
			(end -0.725 0.551)
			(stroke
				(width 0.15)
				(type solid)
			)
			(layer "B.SilkS")
		)
		(fp_line
			(start -0.725 0.551)
			(end -0.927 0.351)
			(stroke
				(width 0.15)
				(type solid)
			)
			(layer "B.SilkS")
		)
		(fp_line
			(start -0.277 0.75)
			(end -0.277 0.551)
			(stroke
				(width 0.15)
				(type solid)
			)
			(layer "B.SilkS")
		)
		(fp_circle
			(center -0.9652 -0.9652)
			(end -0.9152 -0.9652)
			(stroke
				(width 0.15)
				(type solid)
			)
			(fill solid)
			(layer "B.SilkS")
		)
		(fp_line
			(start 1.1 -1.15)
			(end -1.12 -1.15)
			(stroke
				(width 0.05)
				(type solid)
			)
			(layer "B.CrtYd")
		)
		(fp_line
			(start 1.1 -1.15)
			(end 1.1 1.16)
			(stroke
				(width 0.05)
				(type solid)
			)
			(layer "B.CrtYd")
		)
		(fp_line
			(start -1.12 -1.15)
			(end -1.12 1.16)
			(stroke
				(width 0.05)
				(type solid)
			)
			(layer "B.CrtYd")
		)
		(fp_line
			(start 1.1 1.16)
			(end -1.12 1.16)
			(stroke
				(width 0.05)
				(type solid)
			)
			(layer "B.CrtYd")
		)
		(fp_line
			(start 0.8 -0.424)
			(end 0.8 0.425)
			(stroke
				(width 0.15)
				(type solid)
			)
			(layer "B.Fab")
		)
		(fp_line
			(start -0.802 -0.424)
			(end 0.8 -0.424)
			(stroke
				(width 0.15)
				(type solid)
			)
			(layer "B.Fab")
		)
		(fp_line
			(start -0.802 -0.424)
			(end -0.802 0.276)
			(stroke
				(width 0.15)
				(type solid)
			)
			(layer "B.Fab")
		)
		(fp_line
			(start -0.802 0.276)
			(end -0.652 0.425)
			(stroke
				(width 0.15)
				(type solid)
			)
			(layer "B.Fab")
		)
		(fp_line
			(start -0.652 0.425)
			(end 0.8 0.425)
			(stroke
				(width 0.15)
				(type solid)
			)
			(layer "B.Fab")
		)
		(fp_circle
			(center -0.9652 -0.9652)
			(end -0.9144 -0.9652)
			(stroke
				(width 0.15)
				(type solid)
			)
			(fill none)
			(layer "B.Fab")
		)
		(fp_text user "${REFERENCE}"
			(at -1.12 -3.824 -90)
			(layer "B.Fab")
			(hide yes)
			(effects
				(font
					(size 0.7 0.7)
					(thickness 0.15)
				)
				(justify left bottom mirror)
			)
		)
		(fp_text user "Author: Antmicro"
			(at -1.12 -6.224 -90)
			(layer "B.Fab")
			(hide yes)
			(effects
				(font
					(size 0.7 0.7)
					(thickness 0.15)
				)
				(justify left bottom mirror)
			)
		)
		(fp_text user "License: Apache-2.0"
			(at -1.12 -5.024 -90)
			(layer "B.Fab")
			(hide yes)
			(effects
				(font
					(size 0.7 0.7)
					(thickness 0.15)
				)
				(justify left bottom mirror)
			)
		)
		(pad "1" smd rect
			(at -0.5 -0.65 90)
			(size 0.4 0.51)
			(layers "B.Cu" "B.Paste" "B.Mask")
			(net 279 "PWR_SOFT")
			(pinfunction "G")
			(pintype "passive")
		)
		(pad "2" smd rect
			(at 0.498 -0.65 90)
			(size 0.4 0.51)
			(layers "B.Cu" "B.Paste" "B.Mask")
			(net 1 "GND")
			(pinfunction "S")
			(pintype "passive")
		)
		(pad "3" smd rect
			(at 0 0.652 90)
			(size 0.4 0.51)
			(layers "B.Cu" "B.Paste" "B.Mask")
			(net 137 "Net-(D36-A)")
			(pinfunction "D")
			(pintype "passive")
		)
	)
	(footprint "antmicro-footprints:C_0402_1005Metric"
		(layer "B.Cu")
		(at 68.2 108.2 -90)
		(descr "Capacitor SMD 0402")
		(tags "capacitor SMD 0402")
		(property "Reference" "C65"
			(at -0.89 -1.31 90)
			(layer "B.SilkS")
			(effects
				(font
					(size 0.7 0.7)
					(thickness 0.15)
				)
				(justify left bottom mirror)
			)
		)
		(property "Value" "C_100n_0402"
			(at 0 -1.4 90)
			(layer "B.Fab")
			(effects
				(font
					(size 0.7 0.7)
					(thickness 0.15)
				)
				(justify left bottom mirror)
			)
		)
		(property "Footprint" "antmicro-footprints:C_0402_1005Metric"
			(at 0 0 -90)
			(layer "F.Fab")
			(hide yes)
			(effects
				(font
					(size 1.27 1.27)
					(thickness 0.15)
				)
			)
		)
		(property "Datasheet" "https://www.murata.com/products/productdetail?partno=GRM155R61H104KE14%23"
			(at 0 0 -90)
			(layer "F.Fab")
			(hide yes)
			(effects
				(font
					(size 1.27 1.27)
					(thickness 0.15)
				)
			)
		)
		(property "Author" "Antmicro"
			(at -40 176.4 0)
			(layer "B.Fab")
			(hide yes)
			(effects
				(font
					(size 1 1)
					(thickness 0.15)
				)
				(justify mirror)
			)
		)
		(property "Dielectric" "X5R"
			(at -40 176.4 0)
			(layer "B.Fab")
			(hide yes)
			(effects
				(font
					(size 1 1)
					(thickness 0.15)
				)
				(justify mirror)
			)
		)
		(property "License" "Apache-2.0"
			(at -40 176.4 0)
			(layer "B.Fab")
			(hide yes)
			(effects
				(font
					(size 1 1)
					(thickness 0.15)
				)
				(justify mirror)
			)
		)
		(property "MPN" "GRM155R61H104KE14D"
			(at -40 176.4 0)
			(layer "B.Fab")
			(hide yes)
			(effects
				(font
					(size 1 1)
					(thickness 0.15)
				)
				(justify mirror)
			)
		)
		(property "Manufacturer" "Murata"
			(at -40 176.4 0)
			(layer "B.Fab")
			(hide yes)
			(effects
				(font
					(size 1 1)
					(thickness 0.15)
				)
				(justify mirror)
			)
		)
		(property "Val" "100n"
			(at -40 176.4 0)
			(layer "B.Fab")
			(hide yes)
			(effects
				(font
					(size 1 1)
					(thickness 0.15)
				)
				(justify mirror)
			)
		)
		(property "Voltage" "50V"
			(at -40 176.4 0)
			(layer "B.Fab")
			(hide yes)
			(effects
				(font
					(size 1 1)
					(thickness 0.15)
				)
				(justify mirror)
			)
		)
		(sheetname "USB Debug, DP")
		(sheetfile "usb.kicad_sch")
		(attr smd)
		(fp_rect
			(start -0.925 0.47)
			(end 0.925 -0.47)
			(stroke
				(width 0.05)
				(type default)
			)
			(fill none)
			(layer "B.CrtYd")
		)
		(fp_line
			(start -0.494 0.25)
			(end -0.494 -0.248)
			(stroke
				(width 0.15)
				(type solid)
			)
			(layer "B.Fab")
		)
		(fp_line
			(start 0.504 0.25)
			(end -0.494 0.25)
			(stroke
				(width 0.15)
				(type solid)
			)
			(layer "B.Fab")
		)
		(fp_line
			(start -0.494 -0.248)
			(end 0.504 -0.248)
			(stroke
				(width 0.15)
				(type solid)
			)
			(layer "B.Fab")
		)
		(fp_line
			(start 0.504 -0.248)
			(end 0.504 0.25)
			(stroke
				(width 0.15)
				(type solid)
			)
			(layer "B.Fab")
		)
		(fp_text user "License: Apache-2.0"
			(at -0.932 -5.17 90)
			(layer "B.Fab")
			(hide yes)
			(effects
				(font
					(size 0.7 0.7)
					(thickness 0.15)
				)
				(justify left bottom mirror)
			)
		)
		(fp_text user "${REFERENCE}"
			(at -0.932 -3.168 90)
			(layer "B.Fab")
			(hide yes)
			(effects
				(font
					(size 0.7 0.7)
					(thickness 0.15)
				)
				(justify left bottom mirror)
			)
		)
		(fp_text user "Author: Antmicro"
			(at -0.932 -4.17 90)
			(layer "B.Fab")
			(hide yes)
			(effects
				(font
					(size 0.7 0.7)
					(thickness 0.15)
				)
				(justify left bottom mirror)
			)
		)
		(pad "1" smd roundrect
			(at -0.48 0 270)
			(size 0.59 0.64)
			(layers "B.Cu" "B.Paste" "B.Mask")
			(roundrect_rratio 0.25)
			(net 261 "/USB Debug, DP/USBC0_VBUS")
			(pintype "passive")
		)
		(pad "2" smd roundrect
			(at 0.48 0 270)
			(size 0.59 0.64)
			(layers "B.Cu" "B.Paste" "B.Mask")
			(roundrect_rratio 0.25)
			(net 1 "GND")
			(pintype "passive")
		)
	)
	(footprint "antmicro-footprints:R_0402_1005Metric"
		(layer "B.Cu")
		(at 72.3 75.7 90)
		(descr "Resistor SMD 0402")
		(tags "resistor SMD 0402")
		(property "Reference" "R261"
			(at -2.3 14.41 -90)
			(layer "B.SilkS")
			(effects
				(font
					(size 0.7 0.7)
					(thickness 0.15)
				)
				(justify left bottom mirror)
			)
		)
		(property "Value" "R_200k_0402"
			(at 0 -1.4 -90)
			(layer "B.Fab")
			(effects
				(font
					(size 0.7 0.7)
					(thickness 0.15)
				)
				(justify left bottom mirror)
			)
		)
		(property "Footprint" "antmicro-footprints:R_0402_1005Metric"
			(at 0 0 90)
			(layer "F.Fab")
			(hide yes)
			(effects
				(font
					(size 1.27 1.27)
					(thickness 0.15)
				)
			)
		)
		(property "Datasheet" "https://www.bourns.com/docs/product-datasheets/cr.pdf"
			(at 0 0 90)
			(layer "F.Fab")
			(hide yes)
			(effects
				(font
					(size 1.27 1.27)
					(thickness 0.15)
				)
			)
		)
		(property "Author" "Antmicro"
			(at 148 3.4 0)
			(layer "B.Fab")
			(hide yes)
			(effects
				(font
					(size 1 1)
					(thickness 0.15)
				)
				(justify mirror)
			)
		)
		(property "License" "Apache-2.0"
			(at 148 3.4 0)
			(layer "B.Fab")
			(hide yes)
			(effects
				(font
					(size 1 1)
					(thickness 0.15)
				)
				(justify mirror)
			)
		)
		(property "MPN" "CR0402-FX-2003GLF"
			(at 148 3.4 0)
			(layer "B.Fab")
			(hide yes)
			(effects
				(font
					(size 1 1)
					(thickness 0.15)
				)
				(justify mirror)
			)
		)
		(property "Manufacturer" "Bourns"
			(at 148 3.4 0)
			(layer "B.Fab")
			(hide yes)
			(effects
				(font
					(size 1 1)
					(thickness 0.15)
				)
				(justify mirror)
			)
		)
		(property "Tolerance" "1%"
			(at 148 3.4 0)
			(layer "B.Fab")
			(hide yes)
			(effects
				(font
					(size 1 1)
					(thickness 0.15)
				)
				(justify mirror)
			)
		)
		(property "Val" "200k"
			(at 148 3.4 0)
			(layer "B.Fab")
			(hide yes)
			(effects
				(font
					(size 1 1)
					(thickness 0.15)
				)
				(justify mirror)
			)
		)
		(sheetname "Supply")
		(sheetfile "supply.kicad_sch")
		(attr smd)
		(fp_rect
			(start -0.925 0.47)
			(end 0.925 -0.47)
			(stroke
				(width 0.05)
				(type default)
			)
			(fill none)
			(layer "B.CrtYd")
		)
		(fp_rect
			(start -0.5 0.25)
			(end 0.5 -0.25)
			(stroke
				(width 0.15)
				(type solid)
			)
			(fill none)
			(layer "B.Fab")
		)
		(fp_text user "License: Apache-2.0"
			(at -0.95 -5.169 -90)
			(layer "B.Fab")
			(hide yes)
			(effects
				(font
					(size 0.7 0.7)
					(thickness 0.15)
				)
				(justify left bottom mirror)
			)
		)
		(fp_text user "${REFERENCE}"
			(at -0.95 -3.168 -90)
			(layer "B.Fab")
			(hide yes)
			(effects
				(font
					(size 0.7 0.7)
					(thickness 0.15)
				)
				(justify left bottom mirror)
			)
		)
		(fp_text user "Author: Antmicro"
			(at -0.95 -4.169 -90)
			(layer "B.Fab")
			(hide yes)
			(effects
				(font
					(size 0.7 0.7)
					(thickness 0.15)
				)
				(justify left bottom mirror)
			)
		)
		(pad "1" smd roundrect
			(at -0.48 0 90)
			(size 0.59 0.64)
			(layers "B.Cu" "B.Paste" "B.Mask")
			(roundrect_rratio 0.25)
			(net 1 "GND")
			(pintype "passive")
		)
		(pad "2" smd roundrect
			(at 0.48 0 90)
			(size 0.59 0.64)
			(layers "B.Cu" "B.Paste" "B.Mask")
			(roundrect_rratio 0.25)
			(net 179 "Net-(D61-A)")
			(pintype "passive")
		)
	)
	(footprint "antmicro-footprints:TSOT23-6"
		(layer "B.Cu")
		(at 137.53 113.95 -90)
		(property "Reference" "U24"
			(at -2 1.08 0)
			(layer "B.SilkS")
			(effects
				(font
					(size 0.7 0.7)
					(thickness 0.15)
				)
				(justify right bottom mirror)
			)
		)
		(property "Value" "AP22615A_TSOT26"
			(at 0 -2.6 90)
			(layer "B.Fab")
			(effects
				(font
					(size 0.7 0.7)
					(thickness 0.15)
				)
				(justify left bottom mirror)
			)
		)
		(property "Footprint" "antmicro-footprints:TSOT23-6"
			(at 0 0 -90)
			(layer "F.Fab")
			(hide yes)
			(effects
				(font
					(size 1.27 1.27)
					(thickness 0.15)
				)
			)
		)
		(property "Datasheet" "https://www.mouser.com/datasheet/2/115/DIOD_S_A0008958405_1-2543193.pdf"
			(at 0 0 -90)
			(layer "F.Fab")
			(hide yes)
			(effects
				(font
					(size 1.27 1.27)
					(thickness 0.15)
				)
			)
		)
		(property "Author" "Antmicro"
			(at 23.58 251.48 0)
			(layer "B.Fab")
			(hide yes)
			(effects
				(font
					(size 1 1)
					(thickness 0.15)
				)
				(justify mirror)
			)
		)
		(property "License" "Apache-2.0"
			(at 23.58 251.48 0)
			(layer "B.Fab")
			(hide yes)
			(effects
				(font
					(size 1 1)
					(thickness 0.15)
				)
				(justify mirror)
			)
		)
		(property "MPN" "AP22615AWU-7"
			(at 23.58 251.48 0)
			(layer "B.Fab")
			(hide yes)
			(effects
				(font
					(size 1 1)
					(thickness 0.15)
				)
				(justify mirror)
			)
		)
		(property "Manufacturer" "Diodes Incorporated"
			(at 23.58 251.48 0)
			(layer "B.Fab")
			(hide yes)
			(effects
				(font
					(size 1 1)
					(thickness 0.15)
				)
				(justify mirror)
			)
		)
		(sheetname "CSI")
		(sheetfile "csi.kicad_sch")
		(attr smd)
		(fp_line
			(start -1 1.5)
			(end 1 1.497)
			(stroke
				(width 0.15)
				(type solid)
			)
			(layer "B.SilkS")
		)
		(fp_line
			(start -1 1.375)
			(end -1 1.5)
			(stroke
				(width 0.15)
				(type solid)
			)
			(layer "B.SilkS")
		)
		(fp_line
			(start 1 1.375)
			(end 1 1.497)
			(stroke
				(width 0.15)
				(type solid)
			)
			(layer "B.SilkS")
		)
		(fp_line
			(start -1 -1.4)
			(end -1 -1.55)
			(stroke
				(width 0.15)
				(type solid)
			)
			(layer "B.SilkS")
		)
		(fp_line
			(start 1 -1.4)
			(end 1 -1.55)
			(stroke
				(width 0.15)
				(type solid)
			)
			(layer "B.SilkS")
		)
		(fp_line
			(start -1 -1.55)
			(end 1 -1.55)
			(stroke
				(width 0.15)
				(type solid)
			)
			(layer "B.SilkS")
		)
		(fp_circle
			(center -1.44 1.5)
			(end -1.39 1.5)
			(stroke
				(width 0.15)
				(type solid)
			)
			(fill solid)
			(layer "B.SilkS")
		)
		(fp_rect
			(start 1.93 1.7)
			(end -1.93 -1.7)
			(stroke
				(width 0.05)
				(type solid)
			)
			(fill none)
			(layer "B.CrtYd")
		)
		(fp_line
			(start -0.876 1.096)
			(end -0.45 1.521)
			(stroke
				(width 0.15)
				(type solid)
			)
			(layer "B.Fab")
		)
		(fp_rect
			(start 0.875 -1.528)
			(end -0.875 1.525)
			(stroke
				(width 0.15)
				(type solid)
			)
			(fill none)
			(layer "B.Fab")
		)
		(fp_text user "${REFERENCE}"
			(at -1.93 -3.8 90)
			(layer "B.Fab")
			(hide yes)
			(effects
				(font
					(size 0.7 0.7)
					(thickness 0.15)
				)
				(justify left bottom mirror)
			)
		)
		(fp_text user "License: Apache-2.0"
			(at -1.93 -6.199 90)
			(layer "B.Fab")
			(hide yes)
			(effects
				(font
					(size 0.7 0.7)
					(thickness 0.15)
				)
				(justify left bottom mirror)
			)
		)
		(fp_text user "Author: Antmicro"
			(at -1.93 -5 90)
			(layer "B.Fab")
			(hide yes)
			(effects
				(font
					(size 0.7 0.7)
					(thickness 0.15)
				)
				(justify left bottom mirror)
			)
		)
		(pad "1" smd rect
			(at -1.301 0.947)
			(size 0.7 1.2)
			(layers "B.Cu" "B.Paste" "B.Mask")
			(net 109 "/CSI/CSIA_5V")
			(pinfunction "OUT")
			(pintype "power_out")
		)
		(pad "2" smd rect
			(at -1.301 -0.004)
			(size 0.7 1.2)
			(layers "B.Cu" "B.Paste" "B.Mask")
			(net 1 "GND")
			(pinfunction "GND")
			(pintype "power_in")
		)
		(pad "3" smd rect
			(at -1.301 -0.954)
			(size 0.7 1.2)
			(layers "B.Cu" "B.Paste" "B.Mask")
			(net 311 "CSIA_FLG")
			(pinfunction "FLG")
			(pintype "output")
		)
		(pad "4" smd rect
			(at 1.299 -0.954)
			(size 0.7 1.2)
			(layers "B.Cu" "B.Paste" "B.Mask")
			(net 322 "CSIA_PEN")
			(pinfunction "EN")
			(pintype "input")
		)
		(pad "5" smd rect
			(at 1.299 -0.004)
			(size 0.7 1.2)
			(layers "B.Cu" "B.Paste" "B.Mask")
			(net 334 "/CSI/CSIA_5V_ISET")
			(pinfunction "ISET")
			(pintype "passive")
		)
		(pad "6" smd rect
			(at 1.299 0.947)
			(size 0.7 1.2)
			(layers "B.Cu" "B.Paste" "B.Mask")
			(net 99 "+5V")
			(pinfunction "IN")
			(pintype "power_in")
		)
	)
	(footprint "antmicro-footprints:R_0402_1005Metric"
		(layer "B.Cu")
		(at 109.8 105.4)
		(descr "Resistor SMD 0402")
		(tags "resistor SMD 0402")
		(property "Reference" "R265"
			(at -0.87 0.53 180)
			(layer "B.SilkS")
			(effects
				(font
					(size 0.7 0.7)
					(thickness 0.15)
				)
				(justify left bottom mirror)
			)
		)
		(property "Value" "R_200k_0402"
			(at 0 -1.4 180)
			(layer "B.Fab")
			(effects
				(font
					(size 0.7 0.7)
					(thickness 0.15)
				)
				(justify left bottom mirror)
			)
		)
		(property "Footprint" "antmicro-footprints:R_0402_1005Metric"
			(at 0 0 0)
			(layer "F.Fab")
			(hide yes)
			(effects
				(font
					(size 1.27 1.27)
					(thickness 0.15)
				)
			)
		)
		(property "Datasheet" "https://www.bourns.com/docs/product-datasheets/cr.pdf"
			(at 0 0 0)
			(layer "F.Fab")
			(hide yes)
			(effects
				(font
					(size 1.27 1.27)
					(thickness 0.15)
				)
			)
		)
		(property "Author" "Antmicro"
			(at 0 0 0)
			(layer "B.Fab")
			(hide yes)
			(effects
				(font
					(size 1 1)
					(thickness 0.15)
				)
				(justify mirror)
			)
		)
		(property "License" "Apache-2.0"
			(at 0 0 0)
			(layer "B.Fab")
			(hide yes)
			(effects
				(font
					(size 1 1)
					(thickness 0.15)
				)
				(justify mirror)
			)
		)
		(property "MPN" "CR0402-FX-2003GLF"
			(at 0 0 0)
			(layer "B.Fab")
			(hide yes)
			(effects
				(font
					(size 1 1)
					(thickness 0.15)
				)
				(justify mirror)
			)
		)
		(property "Manufacturer" "Bourns"
			(at 0 0 0)
			(layer "B.Fab")
			(hide yes)
			(effects
				(font
					(size 1 1)
					(thickness 0.15)
				)
				(justify mirror)
			)
		)
		(property "Tolerance" "1%"
			(at 0 0 0)
			(layer "B.Fab")
			(hide yes)
			(effects
				(font
					(size 1 1)
					(thickness 0.15)
				)
				(justify mirror)
			)
		)
		(property "Val" "200k"
			(at 0 0 0)
			(layer "B.Fab")
			(hide yes)
			(effects
				(font
					(size 1 1)
					(thickness 0.15)
				)
				(justify mirror)
			)
		)
		(sheetname "USB3")
		(sheetfile "usb3.kicad_sch")
		(attr smd)
		(fp_rect
			(start -0.925 0.47)
			(end 0.925 -0.47)
			(stroke
				(width 0.05)
				(type default)
			)
			(fill none)
			(layer "B.CrtYd")
		)
		(fp_rect
			(start -0.5 0.25)
			(end 0.5 -0.25)
			(stroke
				(width 0.15)
				(type solid)
			)
			(fill none)
			(layer "B.Fab")
		)
		(fp_text user "Author: Antmicro"
			(at -0.95 -4.169 180)
			(layer "B.Fab")
			(hide yes)
			(effects
				(font
					(size 0.7 0.7)
					(thickness 0.15)
				)
				(justify left bottom mirror)
			)
		)
		(fp_text user "${REFERENCE}"
			(at -0.95 -3.168 180)
			(layer "B.Fab")
			(hide yes)
			(effects
				(font
					(size 0.7 0.7)
					(thickness 0.15)
				)
				(justify left bottom mirror)
			)
		)
		(fp_text user "License: Apache-2.0"
			(at -0.95 -5.169 180)
			(layer "B.Fab")
			(hide yes)
			(effects
				(font
					(size 0.7 0.7)
					(thickness 0.15)
				)
				(justify left bottom mirror)
			)
		)
		(pad "1" smd roundrect
			(at -0.48 0)
			(size 0.59 0.64)
			(layers "B.Cu" "B.Paste" "B.Mask")
			(roundrect_rratio 0.25)
			(net 87 "+3V3")
			(pintype "passive")
		)
		(pad "2" smd roundrect
			(at 0.48 0)
			(size 0.59 0.64)
			(layers "B.Cu" "B.Paste" "B.Mask")
			(roundrect_rratio 0.25)
			(net 362 "/USB3/USBC1_I2C_SDA")
			(pintype "passive")
		)
	)
	(footprint "antmicro-footprints:SOIC-4_4.55x2.6mm_P1.27mm"
		(layer "B.Cu")
		(at 56.625 101.925 90)
		(descr "ACPL-217-500E")
		(tags "Integrated Circuit")
		(property "Reference" "U39"
			(at -1.185 -1.535 90)
			(layer "B.SilkS")
			(effects
				(font
					(size 0.7 0.7)
					(thickness 0.15)
				)
				(justify right bottom mirror)
			)
		)
		(property "Value" "ACPL-217-500E"
			(at -4.25 -2.75 90)
			(layer "B.Fab")
			(effects
				(font
					(size 0.7 0.7)
					(thickness 0.15)
				)
				(justify right bottom mirror)
			)
		)
		(property "Footprint" "antmicro-footprints:SOIC-4_4.55x2.6mm_P1.27mm"
			(at 0 0 90)
			(layer "F.Fab")
			(hide yes)
			(effects
				(font
					(size 1.27 1.27)
					(thickness 0.15)
				)
			)
		)
		(property "Datasheet" "https://docs.broadcom.com/doc/AV02-0470EN"
			(at 0 0 90)
			(layer "F.Fab")
			(hide yes)
			(effects
				(font
					(size 1.27 1.27)
					(thickness 0.15)
				)
			)
		)
		(property "Description" "Broadcom ACPL-217-500E DC Input Transistor Output Optocoupler, Surface Mount, 4-Pin SO"
			(at 158.55 45.3 0)
			(layer "F.Fab")
			(hide yes)
			(effects
				(font
					(size 1.27 1.27)
					(thickness 0.15)
				)
			)
		)
		(property "Author" "Antmicro"
			(at 158.55 45.3 0)
			(layer "B.Fab")
			(hide yes)
			(effects
				(font
					(size 1 1)
					(thickness 0.15)
				)
				(justify mirror)
			)
		)
		(property "License" "Apache-2.0"
			(at 158.55 45.3 0)
			(layer "B.Fab")
			(hide yes)
			(effects
				(font
					(size 1 1)
					(thickness 0.15)
				)
				(justify mirror)
			)
		)
		(property "MPN" "ACPL-217-500E"
			(at 158.55 45.3 0)
			(layer "B.Fab")
			(hide yes)
			(effects
				(font
					(size 1 1)
					(thickness 0.15)
				)
				(justify mirror)
			)
		)
		(property "Manufacturer" "Broadcom"
			(at 158.55 45.3 0)
			(layer "B.Fab")
			(hide yes)
			(effects
				(font
					(size 1 1)
					(thickness 0.15)
				)
				(justify mirror)
			)
		)
		(sheetname "Ethernet")
		(sheetfile "ethernet.kicad_sch")
		(attr smd)
		(fp_line
			(start 2.3 -1.4)
			(end 2.3 -1.1)
			(stroke
				(width 0.12)
				(type solid)
			)
			(layer "B.SilkS")
		)
		(fp_line
			(start 1.8 -1.4)
			(end 2.3 -1.4)
			(stroke
				(width 0.12)
				(type solid)
			)
			(layer "B.SilkS")
		)
		(fp_line
			(start -2.3 -1.4)
			(end -1.8 -1.4)
			(stroke
				(width 0.12)
				(type solid)
			)
			(layer "B.SilkS")
		)
		(fp_line
			(start -2.3 -1.4)
			(end -2.3 -1.1)
			(stroke
				(width 0.12)
				(type solid)
			)
			(layer "B.SilkS")
		)
		(fp_line
			(start 2.3 1.4)
			(end 2.3 1.1)
			(stroke
				(width 0.12)
				(type solid)
			)
			(layer "B.SilkS")
		)
		(fp_line
			(start 2.3 1.4)
			(end 1.8 1.4)
			(stroke
				(width 0.12)
				(type solid)
			)
			(layer "B.SilkS")
		)
		(fp_line
			(start -1.8 1.4)
			(end -2.3 1.4)
			(stroke
				(width 0.12)
				(type solid)
			)
			(layer "B.SilkS")
		)
		(fp_line
			(start 4.29 -1.69)
			(end 4.29 1.7)
			(stroke
				(width 0.05)
				(type solid)
			)
			(layer "B.CrtYd")
		)
		(fp_line
			(start -4.3 -1.69)
			(end 4.29 -1.69)
			(stroke
				(width 0.05)
				(type solid)
			)
			(layer "B.CrtYd")
		)
		(fp_line
			(start 4.29 1.7)
			(end -4.3 1.7)
			(stroke
				(width 0.05)
				(type solid)
			)
			(layer "B.CrtYd")
		)
		(fp_line
			(start -4.3 1.7)
			(end -4.3 -1.69)
			(stroke
				(width 0.05)
				(type solid)
			)
			(layer "B.CrtYd")
		)
		(fp_line
			(start 2.2 -1.3)
			(end 2.2 1.301)
			(stroke
				(width 0.15)
				(type solid)
			)
			(layer "B.Fab")
		)
		(fp_line
			(start -2.201 -1.3)
			(end 2.2 -1.3)
			(stroke
				(width 0.15)
				(type solid)
			)
			(layer "B.Fab")
		)
		(fp_line
			(start 2.2 1.301)
			(end -2.201 1.301)
			(stroke
				(width 0.15)
				(type solid)
			)
			(layer "B.Fab")
		)
		(fp_line
			(start -0.931 1.301)
			(end -2.201 0.03)
			(stroke
				(width 0.15)
				(type solid)
			)
			(layer "B.Fab")
		)
		(fp_line
			(start -2.201 1.301)
			(end -2.201 -1.3)
			(stroke
				(width 0.15)
				(type solid)
			)
			(layer "B.Fab")
		)
		(fp_text user "."
			(at -2.7 1.6 90)
			(layer "B.SilkS")
			(effects
				(font
					(size 1 1)
					(thickness 0.15)
				)
				(justify mirror)
			)
		)
		(fp_text user "${REFERENCE}"
			(at -4.3 -4.25 90)
			(layer "B.Fab")
			(hide yes)
			(effects
				(font
					(size 0.7 0.7)
					(thickness 0.15)
				)
				(justify right bottom mirror)
			)
		)
		(fp_text user "Author: Antmicro"
			(at -4.3 -5.5 90)
			(layer "B.Fab")
			(hide yes)
			(effects
				(font
					(size 0.7 0.7)
					(thickness 0.15)
				)
				(justify right bottom mirror)
			)
		)
		(fp_text user "License: Apache-2.0"
			(at -4.25 -7 90)
			(layer "B.Fab")
			(hide yes)
			(effects
				(font
					(size 0.7 0.7)
					(thickness 0.15)
				)
				(justify right bottom mirror)
			)
		)
		(pad "1" smd roundrect
			(at -3.125 0.635)
			(size 0.65 1.85)
			(layers "B.Cu" "B.Paste" "B.Mask")
			(roundrect_rratio 0.15)
			(net 514 "DISABLE_POE_DCDC")
			(pintype "passive")
		)
		(pad "2" smd roundrect
			(at -3.125 -0.634)
			(size 0.65 1.85)
			(layers "B.Cu" "B.Paste" "B.Mask")
			(roundrect_rratio 0.15)
			(net 731 "Net-(R156-Pad1)")
			(pintype "passive")
		)
		(pad "3" smd roundrect
			(at 3.124 -0.634)
			(size 0.65 1.85)
			(layers "B.Cu" "B.Paste" "B.Mask")
			(roundrect_rratio 0.15)
			(net 730 "Net-(R155-Pad2)")
			(pintype "passive")
		)
		(pad "4" smd roundrect
			(at 3.124 0.635)
			(size 0.65 1.85)
			(layers "B.Cu" "B.Paste" "B.Mask")
			(roundrect_rratio 0.15)
			(net 127 "/Ethernet/POE_ACTIVE")
			(pintype "passive")
		)
	)
	(footprint "antmicro-footprints:TP_SMD_0.75mm"
		(layer "B.Cu")
		(at 130.085 87.77)
		(property "Reference" "TP11"
			(at 0.395 0.365001 0)
			(layer "B.SilkS")
			(effects
				(font
					(size 0.7 0.7)
					(thickness 0.15)
				)
				(justify right bottom mirror)
			)
		)
		(property "Value" "TP_0.75mm_SMD"
			(at 0 -1.2 0)
			(layer "B.Fab")
			(effects
				(font
					(size 0.7 0.7)
					(thickness 0.15)
				)
				(justify right bottom mirror)
			)
		)
		(property "Footprint" "antmicro-footprints:TP_SMD_0.75mm"
			(at 0 0 0)
			(layer "F.Fab")
			(hide yes)
			(effects
				(font
					(size 1.27 1.27)
					(thickness 0.15)
				)
			)
		)
		(property "Author" "Antmicro"
			(at 0 0 0)
			(layer "B.Fab")
			(hide yes)
			(effects
				(font
					(size 1 1)
					(thickness 0.15)
				)
				(justify mirror)
			)
		)
		(property "License" "Apache-2.0"
			(at 0 0 0)
			(layer "B.Fab")
			(hide yes)
			(effects
				(font
					(size 1 1)
					(thickness 0.15)
				)
				(justify mirror)
			)
		)
		(property "MPN" ""
			(at 0 0 0)
			(layer "B.Fab")
			(hide yes)
			(effects
				(font
					(size 1 1)
					(thickness 0.15)
				)
				(justify mirror)
			)
		)
		(property "Manufacturer" ""
			(at 0 0 0)
			(layer "B.Fab")
			(hide yes)
			(effects
				(font
					(size 1 1)
					(thickness 0.15)
				)
				(justify mirror)
			)
		)
		(sheetname "M.2")
		(sheetfile "m-2.kicad_sch")
		(attr exclude_from_pos_files exclude_from_bom)
		(fp_circle
			(center 0 0)
			(end 0.475 0)
			(stroke
				(width 0.05)
				(type default)
			)
			(fill none)
			(layer "B.CrtYd")
		)
		(fp_text user "Author: Antmicro"
			(at -0.4 -3.901 0)
			(layer "B.Fab")
			(hide yes)
			(effects
				(font
					(size 0.7 0.7)
					(thickness 0.15)
				)
				(justify right bottom mirror)
			)
		)
		(fp_text user "${REFERENCE}"
			(at -0.4 -2.7 0)
			(layer "B.Fab")
			(hide yes)
			(effects
				(font
					(size 0.7 0.7)
					(thickness 0.15)
				)
				(justify right bottom mirror)
			)
		)
		(fp_text user "License: Apache-2.0"
			(at -0.4 -5.101 0)
			(layer "B.Fab")
			(hide yes)
			(effects
				(font
					(size 0.7 0.7)
					(thickness 0.15)
				)
				(justify right bottom mirror)
			)
		)
		(pad "1" smd circle
			(at 0 0)
			(size 0.75 0.75)
			(layers "B.Cu" "B.Mask")
			(net 245 "/M.2/M2_M_SMB_DATA")
			(pinfunction "1")
			(pintype "passive")
		)
	)
	(footprint "antmicro-footprints:C_0402_1005Metric"
		(layer "B.Cu")
		(at 133.45 117.55)
		(descr "Capacitor SMD 0402")
		(tags "capacitor SMD 0402")
		(property "Reference" "C43"
			(at -0.8 0.45 180)
			(layer "B.SilkS")
			(effects
				(font
					(size 0.7 0.7)
					(thickness 0.15)
				)
				(justify left bottom mirror)
			)
		)
		(property "Value" "C_100n_0402"
			(at 0 -1.4 180)
			(layer "B.Fab")
			(effects
				(font
					(size 0.7 0.7)
					(thickness 0.15)
				)
				(justify left bottom mirror)
			)
		)
		(property "Footprint" "antmicro-footprints:C_0402_1005Metric"
			(at 0 0 0)
			(layer "F.Fab")
			(hide yes)
			(effects
				(font
					(size 1.27 1.27)
					(thickness 0.15)
				)
			)
		)
		(property "Datasheet" "https://www.murata.com/products/productdetail?partno=GRM155R61H104KE14%23"
			(at 0 0 0)
			(layer "F.Fab")
			(hide yes)
			(effects
				(font
					(size 1.27 1.27)
					(thickness 0.15)
				)
			)
		)
		(property "Author" "Antmicro"
			(at 0 0 0)
			(layer "B.Fab")
			(hide yes)
			(effects
				(font
					(size 1 1)
					(thickness 0.15)
				)
				(justify mirror)
			)
		)
		(property "Dielectric" "X5R"
			(at 0 0 0)
			(layer "B.Fab")
			(hide yes)
			(effects
				(font
					(size 1 1)
					(thickness 0.15)
				)
				(justify mirror)
			)
		)
		(property "License" "Apache-2.0"
			(at 0 0 0)
			(layer "B.Fab")
			(hide yes)
			(effects
				(font
					(size 1 1)
					(thickness 0.15)
				)
				(justify mirror)
			)
		)
		(property "MPN" "GRM155R61H104KE14D"
			(at 0 0 0)
			(layer "B.Fab")
			(hide yes)
			(effects
				(font
					(size 1 1)
					(thickness 0.15)
				)
				(justify mirror)
			)
		)
		(property "Manufacturer" "Murata"
			(at 0 0 0)
			(layer "B.Fab")
			(hide yes)
			(effects
				(font
					(size 1 1)
					(thickness 0.15)
				)
				(justify mirror)
			)
		)
		(property "Val" "100n"
			(at 0 0 0)
			(layer "B.Fab")
			(hide yes)
			(effects
				(font
					(size 1 1)
					(thickness 0.15)
				)
				(justify mirror)
			)
		)
		(property "Voltage" "50V"
			(at 0 0 0)
			(layer "B.Fab")
			(hide yes)
			(effects
				(font
					(size 1 1)
					(thickness 0.15)
				)
				(justify mirror)
			)
		)
		(sheetname "CSI")
		(sheetfile "csi.kicad_sch")
		(attr smd)
		(fp_rect
			(start -0.925 0.47)
			(end 0.925 -0.47)
			(stroke
				(width 0.05)
				(type default)
			)
			(fill none)
			(layer "B.CrtYd")
		)
		(fp_line
			(start -0.494 -0.248)
			(end 0.504 -0.248)
			(stroke
				(width 0.15)
				(type solid)
			)
			(layer "B.Fab")
		)
		(fp_line
			(start -0.494 0.25)
			(end -0.494 -0.248)
			(stroke
				(width 0.15)
				(type solid)
			)
			(layer "B.Fab")
		)
		(fp_line
			(start 0.504 -0.248)
			(end 0.504 0.25)
			(stroke
				(width 0.15)
				(type solid)
			)
			(layer "B.Fab")
		)
		(fp_line
			(start 0.504 0.25)
			(end -0.494 0.25)
			(stroke
				(width 0.15)
				(type solid)
			)
			(layer "B.Fab")
		)
		(fp_text user "Author: Antmicro"
			(at -0.932 -4.17 180)
			(layer "B.Fab")
			(hide yes)
			(effects
				(font
					(size 0.7 0.7)
					(thickness 0.15)
				)
				(justify left bottom mirror)
			)
		)
		(fp_text user "${REFERENCE}"
			(at -0.932 -3.168 180)
			(layer "B.Fab")
			(hide yes)
			(effects
				(font
					(size 0.7 0.7)
					(thickness 0.15)
				)
				(justify left bottom mirror)
			)
		)
		(fp_text user "License: Apache-2.0"
			(at -0.932 -5.17 180)
			(layer "B.Fab")
			(hide yes)
			(effects
				(font
					(size 0.7 0.7)
					(thickness 0.15)
				)
				(justify left bottom mirror)
			)
		)
		(pad "1" smd roundrect
			(at -0.48 0)
			(size 0.59 0.64)
			(layers "B.Cu" "B.Paste" "B.Mask")
			(roundrect_rratio 0.25)
			(net 87 "+3V3")
			(pintype "passive")
		)
		(pad "2" smd roundrect
			(at 0.48 0)
			(size 0.59 0.64)
			(layers "B.Cu" "B.Paste" "B.Mask")
			(roundrect_rratio 0.25)
			(net 1 "GND")
			(pintype "passive")
		)
	)
	(footprint "antmicro-footprints:R_0402_1005Metric"
		(layer "B.Cu")
		(at 140.7 123)
		(descr "Resistor SMD 0402")
		(tags "resistor SMD 0402")
		(property "Reference" "R189"
			(at 2 -1.425 0)
			(layer "B.SilkS")
			(effects
				(font
					(size 0.7 0.7)
					(thickness 0.15)
				)
				(justify left bottom mirror)
			)
		)
		(property "Value" "R_10k_0402"
			(at 0 -1.4 180)
			(layer "B.Fab")
			(effects
				(font
					(size 0.7 0.7)
					(thickness 0.15)
				)
				(justify left bottom mirror)
			)
		)
		(property "Footprint" "antmicro-footprints:R_0402_1005Metric"
			(at 0 0 0)
			(layer "F.Fab")
			(hide yes)
			(effects
				(font
					(size 1.27 1.27)
					(thickness 0.15)
				)
			)
		)
		(property "Datasheet" "https://www.bourns.com/docs/product-datasheets/cr.pdf"
			(at 0 0 0)
			(layer "F.Fab")
			(hide yes)
			(effects
				(font
					(size 1.27 1.27)
					(thickness 0.15)
				)
			)
		)
		(property "Author" "Antmicro"
			(at 0 0 0)
			(layer "B.Fab")
			(hide yes)
			(effects
				(font
					(size 1 1)
					(thickness 0.15)
				)
				(justify mirror)
			)
		)
		(property "License" "Apache-2.0"
			(at 0 0 0)
			(layer "B.Fab")
			(hide yes)
			(effects
				(font
					(size 1 1)
					(thickness 0.15)
				)
				(justify mirror)
			)
		)
		(property "MPN" "CR0402-FX-1002GLF"
			(at 0 0 0)
			(layer "B.Fab")
			(hide yes)
			(effects
				(font
					(size 1 1)
					(thickness 0.15)
				)
				(justify mirror)
			)
		)
		(property "Manufacturer" "Bourns"
			(at 0 0 0)
			(layer "B.Fab")
			(hide yes)
			(effects
				(font
					(size 1 1)
					(thickness 0.15)
				)
				(justify mirror)
			)
		)
		(property "Tolerance" "1%"
			(at 0 0 0)
			(layer "B.Fab")
			(hide yes)
			(effects
				(font
					(size 1 1)
					(thickness 0.15)
				)
				(justify mirror)
			)
		)
		(property "Val" "10k"
			(at 0 0 0)
			(layer "B.Fab")
			(hide yes)
			(effects
				(font
					(size 1 1)
					(thickness 0.15)
				)
				(justify mirror)
			)
		)
		(sheetname "Peripherals")
		(sheetfile "peripherals.kicad_sch")
		(attr smd)
		(fp_rect
			(start -0.925 0.47)
			(end 0.925 -0.47)
			(stroke
				(width 0.05)
				(type default)
			)
			(fill none)
			(layer "B.CrtYd")
		)
		(fp_rect
			(start -0.5 0.25)
			(end 0.5 -0.25)
			(stroke
				(width 0.15)
				(type solid)
			)
			(fill none)
			(layer "B.Fab")
		)
		(fp_text user "Author: Antmicro"
			(at -0.95 -4.169 180)
			(layer "B.Fab")
			(hide yes)
			(effects
				(font
					(size 0.7 0.7)
					(thickness 0.15)
				)
				(justify left bottom mirror)
			)
		)
		(fp_text user "${REFERENCE}"
			(at -0.95 -3.168 180)
			(layer "B.Fab")
			(hide yes)
			(effects
				(font
					(size 0.7 0.7)
					(thickness 0.15)
				)
				(justify left bottom mirror)
			)
		)
		(fp_text user "License: Apache-2.0"
			(at -0.95 -5.169 180)
			(layer "B.Fab")
			(hide yes)
			(effects
				(font
					(size 0.7 0.7)
					(thickness 0.15)
				)
				(justify left bottom mirror)
			)
		)
		(pad "1" smd roundrect
			(at -0.48 0)
			(size 0.59 0.64)
			(layers "B.Cu" "B.Paste" "B.Mask")
			(roundrect_rratio 0.25)
			(net 658 "/Peripherals/I2C_CONN_PEN")
			(pintype "passive")
		)
		(pad "2" smd roundrect
			(at 0.48 0)
			(size 0.59 0.64)
			(layers "B.Cu" "B.Paste" "B.Mask")
			(roundrect_rratio 0.25)
			(net 87 "+3V3")
			(pintype "passive")
		)
	)
	(footprint "antmicro-footprints:R_0402_1005Metric"
		(layer "B.Cu")
		(at 59.34 74.9)
		(descr "Resistor SMD 0402")
		(tags "resistor SMD 0402")
		(property "Reference" "R249"
			(at 22.91 9.23 180)
			(layer "B.SilkS")
			(effects
				(font
					(size 0.7 0.7)
					(thickness 0.15)
				)
				(justify left bottom mirror)
			)
		)
		(property "Value" "R_100k_0402"
			(at 0 -1.4 180)
			(layer "B.Fab")
			(effects
				(font
					(size 0.7 0.7)
					(thickness 0.15)
				)
				(justify left bottom mirror)
			)
		)
		(property "Footprint" "antmicro-footprints:R_0402_1005Metric"
			(at 0 0 0)
			(layer "F.Fab")
			(hide yes)
			(effects
				(font
					(size 1.27 1.27)
					(thickness 0.15)
				)
			)
		)
		(property "Datasheet" "https://www.bourns.com/docs/product-datasheets/cr.pdf"
			(at 0 0 0)
			(layer "F.Fab")
			(hide yes)
			(effects
				(font
					(size 1.27 1.27)
					(thickness 0.15)
				)
			)
		)
		(property "Author" "Antmicro"
			(at 0 0 0)
			(layer "B.Fab")
			(hide yes)
			(effects
				(font
					(size 1 1)
					(thickness 0.15)
				)
				(justify mirror)
			)
		)
		(property "License" "Apache-2.0"
			(at 0 0 0)
			(layer "B.Fab")
			(hide yes)
			(effects
				(font
					(size 1 1)
					(thickness 0.15)
				)
				(justify mirror)
			)
		)
		(property "MPN" "CR0402-FX-1003GLF"
			(at 0 0 0)
			(layer "B.Fab")
			(hide yes)
			(effects
				(font
					(size 1 1)
					(thickness 0.15)
				)
				(justify mirror)
			)
		)
		(property "Manufacturer" "Bourns"
			(at 0 0 0)
			(layer "B.Fab")
			(hide yes)
			(effects
				(font
					(size 1 1)
					(thickness 0.15)
				)
				(justify mirror)
			)
		)
		(property "Tolerance" "1%"
			(at 0 0 0)
			(layer "B.Fab")
			(hide yes)
			(effects
				(font
					(size 1 1)
					(thickness 0.15)
				)
				(justify mirror)
			)
		)
		(property "Val" "100k"
			(at 0 0 0)
			(layer "B.Fab")
			(hide yes)
			(effects
				(font
					(size 1 1)
					(thickness 0.15)
				)
				(justify mirror)
			)
		)
		(sheetname "Supply")
		(sheetfile "supply.kicad_sch")
		(attr smd)
		(fp_rect
			(start -0.925 0.47)
			(end 0.925 -0.47)
			(stroke
				(width 0.05)
				(type default)
			)
			(fill none)
			(layer "B.CrtYd")
		)
		(fp_rect
			(start -0.5 0.25)
			(end 0.5 -0.25)
			(stroke
				(width 0.15)
				(type solid)
			)
			(fill none)
			(layer "B.Fab")
		)
		(fp_text user "License: Apache-2.0"
			(at -0.95 -5.169 180)
			(layer "B.Fab")
			(hide yes)
			(effects
				(font
					(size 0.7 0.7)
					(thickness 0.15)
				)
				(justify left bottom mirror)
			)
		)
		(fp_text user "Author: Antmicro"
			(at -0.95 -4.169 180)
			(layer "B.Fab")
			(hide yes)
			(effects
				(font
					(size 0.7 0.7)
					(thickness 0.15)
				)
				(justify left bottom mirror)
			)
		)
		(fp_text user "${REFERENCE}"
			(at -0.95 -3.168 180)
			(layer "B.Fab")
			(hide yes)
			(effects
				(font
					(size 0.7 0.7)
					(thickness 0.15)
				)
				(justify left bottom mirror)
			)
		)
		(pad "1" smd roundrect
			(at -0.48 0)
			(size 0.59 0.64)
			(layers "B.Cu" "B.Paste" "B.Mask")
			(roundrect_rratio 0.25)
			(net 1 "GND")
			(pintype "passive")
		)
		(pad "2" smd roundrect
			(at 0.48 0)
			(size 0.59 0.64)
			(layers "B.Cu" "B.Paste" "B.Mask")
			(roundrect_rratio 0.25)
			(net 279 "PWR_SOFT")
			(pintype "passive")
		)
	)
	(footprint "antmicro-footprints:C_0603_1608Metric"
		(layer "B.Cu")
		(at 114.5 93 180)
		(descr "Capacitor SMD 0603")
		(tags "capacitor 0603")
		(property "Reference" "C23"
			(at -1.05 -1.4 0)
			(layer "B.SilkS")
			(effects
				(font
					(size 0.7 0.7)
					(thickness 0.15)
				)
				(justify left bottom mirror)
			)
		)
		(property "Value" "C_10u_0603"
			(at 0 -1.6 0)
			(layer "B.Fab")
			(effects
				(font
					(size 0.7 0.7)
					(thickness 0.15)
				)
				(justify left bottom mirror)
			)
		)
		(property "Footprint" "antmicro-footprints:C_0603_1608Metric"
			(at 0 0 180)
			(layer "F.Fab")
			(hide yes)
			(effects
				(font
					(size 1.27 1.27)
					(thickness 0.15)
				)
			)
		)
		(property "Datasheet" "https://www.murata.com/products/productdetail?partno=GRM188R61A106KE69%23"
			(at 0 0 180)
			(layer "F.Fab")
			(hide yes)
			(effects
				(font
					(size 1.27 1.27)
					(thickness 0.15)
				)
			)
		)
		(property "Author" "Antmicro"
			(at 229 186 0)
			(layer "B.Fab")
			(hide yes)
			(effects
				(font
					(size 1 1)
					(thickness 0.15)
				)
				(justify mirror)
			)
		)
		(property "Dielectric" "template_dielectric"
			(at 229 186 0)
			(layer "B.Fab")
			(hide yes)
			(effects
				(font
					(size 1 1)
					(thickness 0.15)
				)
				(justify mirror)
			)
		)
		(property "License" "Apache-2.0"
			(at 229 186 0)
			(layer "B.Fab")
			(hide yes)
			(effects
				(font
					(size 1 1)
					(thickness 0.15)
				)
				(justify mirror)
			)
		)
		(property "MPN" "GRM188R61A106KE69D"
			(at 229 186 0)
			(layer "B.Fab")
			(hide yes)
			(effects
				(font
					(size 1 1)
					(thickness 0.15)
				)
				(justify mirror)
			)
		)
		(property "Manufacturer" "Murata"
			(at 229 186 0)
			(layer "B.Fab")
			(hide yes)
			(effects
				(font
					(size 1 1)
					(thickness 0.15)
				)
				(justify mirror)
			)
		)
		(property "Val" "10u"
			(at 229 186 0)
			(layer "B.Fab")
			(hide yes)
			(effects
				(font
					(size 1 1)
					(thickness 0.15)
				)
				(justify mirror)
			)
		)
		(property "Voltage" ""
			(at 229 186 0)
			(layer "B.Fab")
			(hide yes)
			(effects
				(font
					(size 1 1)
					(thickness 0.15)
				)
				(justify mirror)
			)
		)
		(sheetname "M.2")
		(sheetfile "m-2.kicad_sch")
		(attr smd)
		(fp_line
			(start 0.15 0.4)
			(end -0.15 0.4)
			(stroke
				(width 0.15)
				(type solid)
			)
			(layer "B.SilkS")
		)
		(fp_line
			(start 0.15 -0.4)
			(end -0.15 -0.4)
			(stroke
				(width 0.15)
				(type solid)
			)
			(layer "B.SilkS")
		)
		(fp_rect
			(start -1.25 0.65)
			(end 1.25 -0.65)
			(stroke
				(width 0.05)
				(type solid)
			)
			(fill none)
			(layer "B.CrtYd")
		)
		(fp_rect
			(start -0.8 0.4)
			(end 0.8 -0.4)
			(stroke
				(width 0.15)
				(type solid)
			)
			(fill none)
			(layer "B.Fab")
		)
		(fp_text user "Author: Antmicro"
			(at -1.682 -4.894 0)
			(layer "B.Fab")
			(hide yes)
			(effects
				(font
					(size 0.7 0.7)
					(thickness 0.15)
				)
				(justify left bottom mirror)
			)
		)
		(fp_text user "${REFERENCE}"
			(at -1.682 -3.895 0)
			(layer "B.Fab")
			(hide yes)
			(effects
				(font
					(size 0.7 0.7)
					(thickness 0.15)
				)
				(justify left bottom mirror)
			)
		)
		(fp_text user "License: Apache-2.0"
			(at -1.682 -5.895 0)
			(layer "B.Fab")
			(hide yes)
			(effects
				(font
					(size 0.7 0.7)
					(thickness 0.15)
				)
				(justify left bottom mirror)
			)
		)
		(pad "1" smd roundrect
			(at -0.7 0 180)
			(size 0.8 1)
			(layers "B.Cu" "B.Paste" "B.Mask")
			(roundrect_rratio 0.2)
			(net 635 "/M.2/3V3_M2")
			(pintype "passive")
		)
		(pad "2" smd roundrect
			(at 0.7 0 180)
			(size 0.8 1)
			(layers "B.Cu" "B.Paste" "B.Mask")
			(roundrect_rratio 0.2)
			(net 1 "GND")
			(pintype "passive")
		)
	)
	(footprint "antmicro-footprints:R_0402_1005Metric"
		(layer "B.Cu")
		(at 56.3 76.2)
		(descr "Resistor SMD 0402")
		(tags "resistor SMD 0402")
		(property "Reference" "R257"
			(at 20.08 9.2 0)
			(layer "B.SilkS")
			(effects
				(font
					(size 0.7 0.7)
					(thickness 0.15)
				)
				(justify right bottom mirror)
			)
		)
		(property "Value" "R_200k_0402"
			(at 0 -1.4 0)
			(layer "B.Fab")
			(effects
				(font
					(size 0.7 0.7)
					(thickness 0.15)
				)
				(justify right bottom mirror)
			)
		)
		(property "Footprint" "antmicro-footprints:R_0402_1005Metric"
			(at 0 0 0)
			(layer "F.Fab")
			(hide yes)
			(effects
				(font
					(size 1.27 1.27)
					(thickness 0.15)
				)
			)
		)
		(property "Datasheet" "https://www.bourns.com/docs/product-datasheets/cr.pdf"
			(at 0 0 0)
			(layer "F.Fab")
			(hide yes)
			(effects
				(font
					(size 1.27 1.27)
					(thickness 0.15)
				)
			)
		)
		(property "Author" "Antmicro"
			(at 0 0 0)
			(layer "B.Fab")
			(hide yes)
			(effects
				(font
					(size 1 1)
					(thickness 0.15)
				)
				(justify mirror)
			)
		)
		(property "License" "Apache-2.0"
			(at 0 0 0)
			(layer "B.Fab")
			(hide yes)
			(effects
				(font
					(size 1 1)
					(thickness 0.15)
				)
				(justify mirror)
			)
		)
		(property "MPN" "CR0402-FX-2003GLF"
			(at 0 0 0)
			(layer "B.Fab")
			(hide yes)
			(effects
				(font
					(size 1 1)
					(thickness 0.15)
				)
				(justify mirror)
			)
		)
		(property "Manufacturer" "Bourns"
			(at 0 0 0)
			(layer "B.Fab")
			(hide yes)
			(effects
				(font
					(size 1 1)
					(thickness 0.15)
				)
				(justify mirror)
			)
		)
		(property "Tolerance" "1%"
			(at 0 0 0)
			(layer "B.Fab")
			(hide yes)
			(effects
				(font
					(size 1 1)
					(thickness 0.15)
				)
				(justify mirror)
			)
		)
		(property "Val" "200k"
			(at 0 0 0)
			(layer "B.Fab")
			(hide yes)
			(effects
				(font
					(size 1 1)
					(thickness 0.15)
				)
				(justify mirror)
			)
		)
		(sheetname "Supply")
		(sheetfile "supply.kicad_sch")
		(attr smd)
		(fp_rect
			(start -0.925 0.47)
			(end 0.925 -0.47)
			(stroke
				(width 0.05)
				(type default)
			)
			(fill none)
			(layer "B.CrtYd")
		)
		(fp_rect
			(start -0.5 0.25)
			(end 0.5 -0.25)
			(stroke
				(width 0.15)
				(type solid)
			)
			(fill none)
			(layer "B.Fab")
		)
		(fp_text user "${REFERENCE}"
			(at -0.95 -3.168 0)
			(layer "B.Fab")
			(hide yes)
			(effects
				(font
					(size 0.7 0.7)
					(thickness 0.15)
				)
				(justify right bottom mirror)
			)
		)
		(fp_text user "Author: Antmicro"
			(at -0.95 -4.169 0)
			(layer "B.Fab")
			(hide yes)
			(effects
				(font
					(size 0.7 0.7)
					(thickness 0.15)
				)
				(justify right bottom mirror)
			)
		)
		(fp_text user "License: Apache-2.0"
			(at -0.95 -5.169 0)
			(layer "B.Fab")
			(hide yes)
			(effects
				(font
					(size 0.7 0.7)
					(thickness 0.15)
				)
				(justify right bottom mirror)
			)
		)
		(pad "1" smd roundrect
			(at -0.48 0)
			(size 0.59 0.64)
			(layers "B.Cu" "B.Paste" "B.Mask")
			(roundrect_rratio 0.25)
			(net 530 "Net-(R256-Pad1)")
			(pintype "passive")
		)
		(pad "2" smd roundrect
			(at 0.48 0)
			(size 0.59 0.64)
			(layers "B.Cu" "B.Paste" "B.Mask")
			(roundrect_rratio 0.25)
			(net 174 "Net-(D36-C)")
			(pintype "passive")
		)
	)
	(footprint "antmicro-footprints:SOD-923"
		(layer "B.Cu")
		(at 115.4175 117.825)
		(property "Reference" "D10"
			(at 1.1325 -0.575 0)
			(unlocked yes)
			(layer "B.SilkS")
			(effects
				(font
					(size 0.7 0.7)
					(thickness 0.15)
				)
				(justify left bottom mirror)
			)
		)
		(property "Value" "ESD9X5.0ST5G"
			(at 0 -1.3 180)
			(unlocked yes)
			(layer "B.Fab")
			(effects
				(font
					(size 0.7 0.7)
					(thickness 0.15)
				)
				(justify left bottom mirror)
			)
		)
		(property "Footprint" "antmicro-footprints:SOD-923"
			(at 0 0 0)
			(layer "F.Fab")
			(hide yes)
			(effects
				(font
					(size 1.27 1.27)
					(thickness 0.15)
				)
			)
		)
		(property "Datasheet" "https://www.onsemi.com/pdf/datasheet/esd9x3.3st5g-d.pdf"
			(at 0 0 0)
			(layer "F.Fab")
			(hide yes)
			(effects
				(font
					(size 1.27 1.27)
					(thickness 0.15)
				)
			)
		)
		(property "Author" "Antmicro"
			(at 0 0 0)
			(layer "B.Fab")
			(hide yes)
			(effects
				(font
					(size 1 1)
					(thickness 0.15)
				)
				(justify mirror)
			)
		)
		(property "License" "Apache-2.0"
			(at 0 0 0)
			(layer "B.Fab")
			(hide yes)
			(effects
				(font
					(size 1 1)
					(thickness 0.15)
				)
				(justify mirror)
			)
		)
		(property "MPN" "ESD9X5.0ST5G"
			(at 0 0 0)
			(layer "B.Fab")
			(hide yes)
			(effects
				(font
					(size 1 1)
					(thickness 0.15)
				)
				(justify mirror)
			)
		)
		(property "Manufacturer" "ON Semiconductor"
			(at 0 0 0)
			(layer "B.Fab")
			(hide yes)
			(effects
				(font
					(size 1 1)
					(thickness 0.15)
				)
				(justify mirror)
			)
		)
		(sheetname "USB3")
		(sheetfile "usb3.kicad_sch")
		(attr smd)
		(fp_line
			(start -0.5 -0.3)
			(end -0.5 -0.4)
			(stroke
				(width 0.15)
				(type solid)
			)
			(layer "B.SilkS")
		)
		(fp_line
			(start -0.5 0.4)
			(end -0.5 0.3)
			(stroke
				(width 0.15)
				(type solid)
			)
			(layer "B.SilkS")
		)
		(fp_line
			(start -0.16 -0.4)
			(end -0.16 0.4)
			(stroke
				(width 0.15)
				(type solid)
			)
			(layer "B.SilkS")
		)
		(fp_line
			(start 0.5 -0.4)
			(end -0.5 -0.4)
			(stroke
				(width 0.15)
				(type solid)
			)
			(layer "B.SilkS")
		)
		(fp_line
			(start 0.5 -0.3)
			(end 0.5 -0.4)
			(stroke
				(width 0.15)
				(type solid)
			)
			(layer "B.SilkS")
		)
		(fp_line
			(start 0.5 0.3)
			(end 0.5 0.4)
			(stroke
				(width 0.15)
				(type solid)
			)
			(layer "B.SilkS")
		)
		(fp_line
			(start 0.5 0.4)
			(end -0.5 0.4)
			(stroke
				(width 0.15)
				(type solid)
			)
			(layer "B.SilkS")
		)
		(fp_rect
			(start -0.68 0.41)
			(end 0.68 -0.41)
			(stroke
				(width 0.05)
				(type solid)
			)
			(fill none)
			(layer "B.CrtYd")
		)
		(fp_line
			(start -0.202 -0.298)
			(end -0.202 0.3)
			(stroke
				(width 0.15)
				(type solid)
			)
			(layer "B.Fab")
		)
		(fp_rect
			(start -0.402 0.3)
			(end 0.4 -0.298)
			(stroke
				(width 0.15)
				(type solid)
			)
			(fill none)
			(layer "B.Fab")
		)
		(fp_text user "License: Apache-2.0"
			(at -0.68 -4.5 180)
			(layer "B.Fab")
			(hide yes)
			(effects
				(font
					(size 0.7 0.7)
					(thickness 0.15)
				)
				(justify left bottom mirror)
			)
		)
		(fp_text user "Author: Antmicro"
			(at -0.68 -5.7 180)
			(layer "B.Fab")
			(hide yes)
			(effects
				(font
					(size 0.7 0.7)
					(thickness 0.15)
				)
				(justify left bottom mirror)
			)
		)
		(fp_text user "${REFERENCE}"
			(at -0.68 -3.3 180)
			(unlocked yes)
			(layer "B.Fab")
			(hide yes)
			(effects
				(font
					(size 0.7 0.7)
					(thickness 0.15)
				)
				(justify left bottom mirror)
			)
		)
		(pad "1" smd roundrect
			(at -0.438 0)
			(size 0.4 0.325)
			(layers "B.Cu" "B.Paste" "B.Mask")
			(roundrect_rratio 0.25)
			(net 270 "/USB3/USBC1_VBUS")
			(pinfunction "C")
			(pintype "passive")
		)
		(pad "2" smd roundrect
			(at 0.436 0)
			(size 0.4 0.325)
			(layers "B.Cu" "B.Paste" "B.Mask")
			(roundrect_rratio 0.25)
			(net 1 "GND")
			(pinfunction "A")
			(pintype "passive")
		)
	)
	(footprint "antmicro-footprints:R_0603_1608Metric"
		(layer "B.Cu")
		(at 49.59 77.66)
		(descr "Resistor SMD 0603")
		(tags "resistor SMD 0603")
		(property "Reference" "R175"
			(at 1.41 -0.535 180)
			(layer "B.SilkS")
			(effects
				(font
					(size 0.7 0.7)
					(thickness 0.15)
				)
				(justify left bottom mirror)
			)
		)
		(property "Value" "R_0R_22.4A_0603"
			(at 0 -1.6 180)
			(layer "B.Fab")
			(effects
				(font
					(size 0.7 0.7)
					(thickness 0.15)
				)
				(justify left bottom mirror)
			)
		)
		(property "Footprint" "antmicro-footprints:R_0603_1608Metric"
			(at 0 0 0)
			(layer "F.Fab")
			(hide yes)
			(effects
				(font
					(size 1.27 1.27)
					(thickness 0.15)
				)
			)
		)
		(property "Datasheet" "https://fscdn.rohm.com/en/products/databook/datasheet/passive/resistor/chip_resistor/pmr-jpw-e.pdf"
			(at 0 0 0)
			(layer "F.Fab")
			(hide yes)
			(effects
				(font
					(size 1.27 1.27)
					(thickness 0.15)
				)
			)
		)
		(property "Author" "Antmicro"
			(at 0 0 0)
			(layer "B.Fab")
			(hide yes)
			(effects
				(font
					(size 1 1)
					(thickness 0.15)
				)
				(justify mirror)
			)
		)
		(property "License" "Apache-2.0"
			(at 0 0 0)
			(layer "B.Fab")
			(hide yes)
			(effects
				(font
					(size 1 1)
					(thickness 0.15)
				)
				(justify mirror)
			)
		)
		(property "MPN" "PMR03EZPJ000"
			(at 0 0 0)
			(layer "B.Fab")
			(hide yes)
			(effects
				(font
					(size 1 1)
					(thickness 0.15)
				)
				(justify mirror)
			)
		)
		(property "Manufacturer" "ROHM Semiconductor"
			(at 0 0 0)
			(layer "B.Fab")
			(hide yes)
			(effects
				(font
					(size 1 1)
					(thickness 0.15)
				)
				(justify mirror)
			)
		)
		(property "Max. Curr." "22.4A"
			(at 0 0 0)
			(layer "B.Fab")
			(hide yes)
			(effects
				(font
					(size 1 1)
					(thickness 0.15)
				)
				(justify mirror)
			)
		)
		(property "Tolerance" "template_tolerance"
			(at 0 0 0)
			(layer "B.Fab")
			(hide yes)
			(effects
				(font
					(size 1 1)
					(thickness 0.15)
				)
				(justify mirror)
			)
		)
		(property "Val" "0R"
			(at 0 0 0)
			(layer "B.Fab")
			(hide yes)
			(effects
				(font
					(size 1 1)
					(thickness 0.15)
				)
				(justify mirror)
			)
		)
		(sheetname "Supply")
		(sheetfile "supply.kicad_sch")
		(attr smd exclude_from_pos_files exclude_from_bom dnp)
		(fp_line
			(start 0.15 -0.4)
			(end -0.15 -0.4)
			(stroke
				(width 0.15)
				(type solid)
			)
			(layer "B.SilkS")
		)
		(fp_line
			(start 0.15 0.4)
			(end -0.15 0.4)
			(stroke
				(width 0.15)
				(type solid)
			)
			(layer "B.SilkS")
		)
		(fp_rect
			(start -1.25 0.65)
			(end 1.25 -0.65)
			(stroke
				(width 0.05)
				(type solid)
			)
			(fill none)
			(layer "B.CrtYd")
		)
		(fp_rect
			(start -0.8 0.4)
			(end 0.8 -0.4)
			(stroke
				(width 0.15)
				(type solid)
			)
			(fill none)
			(layer "B.Fab")
		)
		(fp_text user "License: Apache-2.0"
			(at -1.25 -5.9 180)
			(layer "B.Fab")
			(hide yes)
			(effects
				(font
					(size 0.7 0.7)
					(thickness 0.15)
				)
				(justify left bottom mirror)
			)
		)
		(fp_text user "Author: Antmicro"
			(at -1.25 -4.9 180)
			(layer "B.Fab")
			(hide yes)
			(effects
				(font
					(size 0.7 0.7)
					(thickness 0.15)
				)
				(justify left bottom mirror)
			)
		)
		(fp_text user "${REFERENCE}"
			(at -1.25 -3.898 180)
			(layer "B.Fab")
			(hide yes)
			(effects
				(font
					(size 0.7 0.7)
					(thickness 0.15)
				)
				(justify left bottom mirror)
			)
		)
		(pad "1" smd roundrect
			(at -0.7 0)
			(size 0.8 1)
			(layers "B.Cu" "B.Paste" "B.Mask")
			(roundrect_rratio 0.2)
			(net 328 "/Supply/VCC_IN")
			(pintype "passive")
		)
		(pad "2" smd roundrect
			(at 0.7 0)
			(size 0.8 1)
			(layers "B.Cu" "B.Paste" "B.Mask")
			(roundrect_rratio 0.2)
			(net 115 "VCC")
			(pintype "passive")
		)
	)
	(footprint "antmicro-footprints:Bus_M.2_Socket_Key_M_TE_1-2199230-6"
		(layer "B.Cu")
		(at 120.591 86.751 90)
		(property "Reference" "J2"
			(at -10.649 5.259 180)
			(layer "B.SilkS")
			(effects
				(font
					(size 0.7 0.7)
					(thickness 0.15)
				)
				(justify right bottom mirror)
			)
		)
		(property "Value" "Bus_M.2_1-2199230-6"
			(at -11.25 -6.124 90)
			(layer "B.Fab")
			(effects
				(font
					(size 0.7 0.7)
					(thickness 0.15)
				)
				(justify right bottom mirror)
			)
		)
		(property "Footprint" "antmicro-footprints:Bus_M.2_Socket_Key_M_TE_1-2199230-6"
			(at 0 0 90)
			(layer "F.Fab")
			(hide yes)
			(effects
				(font
					(size 1.27 1.27)
					(thickness 0.15)
				)
			)
		)
		(property "Datasheet" "https://www.te.com/commerce/DocumentDelivery/DDEController?Action=srchrtrv&DocNm=2199230&DocType=Customer+Drawing&DocLang=English"
			(at 0 0 90)
			(layer "F.Fab")
			(hide yes)
			(effects
				(font
					(size 1.27 1.27)
					(thickness 0.15)
				)
			)
		)
		(property "Author" "Antmicro"
			(at 207.342 -33.84 0)
			(layer "B.Fab")
			(hide yes)
			(effects
				(font
					(size 1 1)
					(thickness 0.15)
				)
				(justify mirror)
			)
		)
		(property "License" "Apache-2.0"
			(at 207.342 -33.84 0)
			(layer "B.Fab")
			(hide yes)
			(effects
				(font
					(size 1 1)
					(thickness 0.15)
				)
				(justify mirror)
			)
		)
		(property "MPN" "1-2199230-6"
			(at 207.342 -33.84 0)
			(layer "B.Fab")
			(hide yes)
			(effects
				(font
					(size 1 1)
					(thickness 0.15)
				)
				(justify mirror)
			)
		)
		(property "Manufacturer" "TE Connectivity"
			(at 207.342 -33.84 0)
			(layer "B.Fab")
			(hide yes)
			(effects
				(font
					(size 1 1)
					(thickness 0.15)
				)
				(justify mirror)
			)
		)
		(sheetname "M.2")
		(sheetfile "m-2.kicad_sch")
		(attr smd)
		(fp_line
			(start 10.948 -3.999)
			(end 9.448 -3.999)
			(stroke
				(width 0.15)
				(type solid)
			)
			(layer "B.SilkS")
		)
		(fp_line
			(start 7.148 -3.999)
			(end 5.347 -3.999)
			(stroke
				(width 0.15)
				(type solid)
			)
			(layer "B.SilkS")
		)
		(fp_line
			(start -9.352 -3.999)
			(end -10.951 -3.999)
			(stroke
				(width 0.15)
				(type solid)
			)
			(layer "B.SilkS")
		)
		(fp_line
			(start -10.951 -3.999)
			(end -10.951 -2.7)
			(stroke
				(width 0.15)
				(type solid)
			)
			(layer "B.SilkS")
		)
		(fp_line
			(start 10.948 -2.3)
			(end 10.948 -3.999)
			(stroke
				(width 0.15)
				(type solid)
			)
			(layer "B.SilkS")
		)
		(fp_line
			(start -10.951 -0.55)
			(end -10.951 1.401)
			(stroke
				(width 0.15)
				(type solid)
			)
			(layer "B.SilkS")
		)
		(fp_line
			(start 10.948 1.301)
			(end 10.948 -0.449)
			(stroke
				(width 0.15)
				(type solid)
			)
			(layer "B.SilkS")
		)
		(fp_line
			(start 6.898 3.75)
			(end 5.097 3.75)
			(stroke
				(width 0.15)
				(type solid)
			)
			(layer "B.SilkS")
		)
		(fp_circle
			(center -9.25 4.875)
			(end -9.201 4.826)
			(stroke
				(width 0.15)
				(type solid)
			)
			(fill solid)
			(layer "B.SilkS")
		)
		(fp_circle
			(center -9.25 5.651)
			(end -9.2 5.651)
			(stroke
				(width 0.15)
				(type solid)
			)
			(fill solid)
			(layer "B.SilkS")
		)
		(fp_line
			(start 11.15 -4.78)
			(end -11.16 -4.78)
			(stroke
				(width 0.05)
				(type solid)
			)
			(layer "B.CrtYd")
		)
		(fp_line
			(start -11.16 -4.78)
			(end -11.16 4.83)
			(stroke
				(width 0.05)
				(type solid)
			)
			(layer "B.CrtYd")
		)
		(fp_line
			(start 11.15 4.83)
			(end 11.15 -4.78)
			(stroke
				(width 0.05)
				(type solid)
			)
			(layer "B.CrtYd")
		)
		(fp_line
			(start -11.16 4.83)
			(end 11.15 4.83)
			(stroke
				(width 0.05)
				(type solid)
			)
			(layer "B.CrtYd")
		)
		(fp_line
			(start 10.95 -4.2)
			(end 10.95 4.1)
			(stroke
				(width 0.15)
				(type solid)
			)
			(layer "B.Fab")
		)
		(fp_line
			(start -10.949 -4.2)
			(end 10.95 -4.2)
			(stroke
				(width 0.15)
				(type solid)
			)
			(layer "B.Fab")
		)
		(fp_line
			(start -10.949 3.55)
			(end -10.949 -4.2)
			(stroke
				(width 0.15)
				(type solid)
			)
			(layer "B.Fab")
		)
		(fp_line
			(start 10.95 4.1)
			(end -10.4 4.1)
			(stroke
				(width 0.15)
				(type solid)
			)
			(layer "B.Fab")
		)
		(fp_line
			(start -10.4 4.1)
			(end -10.949 3.55)
			(stroke
				(width 0.15)
				(type solid)
			)
			(layer "B.Fab")
		)
		(fp_text user "${REFERENCE}"
			(at -11.35 -8.124 90)
			(layer "B.Fab")
			(hide yes)
			(effects
				(font
					(size 0.7 0.7)
					(thickness 0.15)
				)
				(justify right bottom mirror)
			)
		)
		(fp_text user "License: Apache-2.0"
			(at -11.35 -10.525 90)
			(layer "B.Fab")
			(hide yes)
			(effects
				(font
					(size 0.7 0.7)
					(thickness 0.15)
				)
				(justify right bottom mirror)
			)
		)
		(fp_text user "Author: Antmicro"
			(at -11.35 -9.325 90)
			(layer "B.Fab")
			(hide yes)
			(effects
				(font
					(size 0.7 0.7)
					(thickness 0.15)
				)
				(justify right bottom mirror)
			)
		)
		(pad "" np_thru_hole circle
			(at -10 -1.499 90)
			(size 1.1 1.1)
			(drill 1.1)
			(layers "*.Mask")
		)
		(pad "" np_thru_hole circle
			(at 9.997 -1.499 90)
			(size 1.6 1.6)
			(drill 1.6)
			(layers "*.Mask")
		)
		(pad "1" smd rect
			(at -9.25 3.775 90)
			(size 0.3 1.55)
			(layers "B.Cu" "B.Paste" "B.Mask")
			(net 1 "GND")
			(pinfunction "GND")
			(pintype "power_in")
		)
		(pad "2" smd rect
			(at -9.003 -3.773 90)
			(size 0.3 1.55)
			(layers "B.Cu" "B.Paste" "B.Mask")
			(net 635 "/M.2/3V3_M2")
			(pinfunction "3V3")
			(pintype "passive")
		)
		(pad "3" smd rect
			(at -8.753 3.775 90)
			(size 0.3 1.55)
			(layers "B.Cu" "B.Paste" "B.Mask")
			(net 1 "GND")
			(pinfunction "GND")
			(pintype "passive")
		)
		(pad "4" smd rect
			(at -8.503 -3.773 90)
			(size 0.3 1.55)
			(layers "B.Cu" "B.Paste" "B.Mask")
			(net 635 "/M.2/3V3_M2")
			(pinfunction "3V3")
			(pintype "passive")
		)
		(pad "5" smd rect
			(at -8.253 3.775 90)
			(size 0.3 1.55)
			(layers "B.Cu" "B.Paste" "B.Mask")
			(net 53 "PCIE0_RX3_N")
			(pinfunction "PER3_N")
			(pintype "output")
		)
		(pad "6" smd rect
			(at -8.001 -3.773 90)
			(size 0.3 1.55)
			(layers "B.Cu" "B.Paste" "B.Mask")
			(net 332 "unconnected-(J2-NC-Pad6)")
			(pinfunction "NC")
			(pintype "no_connect")
		)
		(pad "7" smd rect
			(at -7.752 3.775 90)
			(size 0.3 1.55)
			(layers "B.Cu" "B.Paste" "B.Mask")
			(net 54 "PCIE0_RX3_P")
			(pinfunction "PER3_P")
			(pintype "output")
		)
		(pad "8" smd rect
			(at -7.502 -3.773 90)
			(size 0.3 1.55)
			(layers "B.Cu" "B.Paste" "B.Mask")
			(net 341 "unconnected-(J2-NC-Pad8)")
			(pinfunction "NC")
			(pintype "no_connect")
		)
		(pad "9" smd rect
			(at -7.252 3.775 90)
			(size 0.3 1.55)
			(layers "B.Cu" "B.Paste" "B.Mask")
			(net 1 "GND")
			(pinfunction "GND")
			(pintype "passive")
		)
		(pad "10" smd rect
			(at -7.002 -3.773 90)
			(size 0.3 1.55)
			(layers "B.Cu" "B.Paste" "B.Mask")
			(net 140 "Net-(D1-C)")
			(pinfunction "LED")
			(pintype "passive")
		)
		(pad "11" smd rect
			(at -6.752 3.775 90)
			(size 0.3 1.55)
			(layers "B.Cu" "B.Paste" "B.Mask")
			(net 95 "/M.2/C_PCIE0_TX3_N")
			(pinfunction "PET3_N")
			(pintype "input")
		)
		(pad "12" smd rect
			(at -6.502 -3.773 90)
			(size 0.3 1.55)
			(layers "B.Cu" "B.Paste" "B.Mask")
			(net 635 "/M.2/3V3_M2")
			(pinfunction "3V3")
			(pintype "passive")
		)
		(pad "13" smd rect
			(at -6.252 3.775 90)
			(size 0.3 1.55)
			(layers "B.Cu" "B.Paste" "B.Mask")
			(net 94 "/M.2/C_PCIE0_TX3_P")
			(pinfunction "PET3_P")
			(pintype "input")
		)
		(pad "14" smd rect
			(at -6.002 -3.773 90)
			(size 0.3 1.55)
			(layers "B.Cu" "B.Paste" "B.Mask")
			(net 635 "/M.2/3V3_M2")
			(pinfunction "3V3")
			(pintype "passive")
		)
		(pad "15" smd rect
			(at -5.752 3.775 90)
			(size 0.3 1.55)
			(layers "B.Cu" "B.Paste" "B.Mask")
			(net 1 "GND")
			(pinfunction "GND")
			(pintype "passive")
		)
		(pad "16" smd rect
			(at -5.502 -3.773 90)
			(size 0.3 1.55)
			(layers "B.Cu" "B.Paste" "B.Mask")
			(net 635 "/M.2/3V3_M2")
			(pinfunction "3V3")
			(pintype "passive")
		)
		(pad "17" smd rect
			(at -5.252 3.775 90)
			(size 0.3 1.55)
			(layers "B.Cu" "B.Paste" "B.Mask")
			(net 51 "PCIE0_RX2_N")
			(pinfunction "PER2_N")
			(pintype "output")
		)
		(pad "18" smd rect
			(at -5.002 -3.773 90)
			(size 0.3 1.55)
			(layers "B.Cu" "B.Paste" "B.Mask")
			(net 635 "/M.2/3V3_M2")
			(pinfunction "3V3")
			(pintype "passive")
		)
		(pad "19" smd rect
			(at -4.752 3.775 90)
			(size 0.3 1.55)
			(layers "B.Cu" "B.Paste" "B.Mask")
			(net 52 "PCIE0_RX2_P")
			(pinfunction "PER2_P")
			(pintype "output")
		)
		(pad "20" smd rect
			(at -4.502 -3.773 90)
			(size 0.3 1.55)
			(layers "B.Cu" "B.Paste" "B.Mask")
			(net 359 "unconnected-(J2-NC-Pad20)")
			(pinfunction "NC")
			(pintype "no_connect")
		)
		(pad "21" smd rect
			(at -4.252 3.775 90)
			(size 0.3 1.55)
			(layers "B.Cu" "B.Paste" "B.Mask")
			(net 1 "GND")
			(pinfunction "GND")
			(pintype "passive")
		)
		(pad "22" smd rect
			(at -4.002 -3.773 90)
			(size 0.3 1.55)
			(layers "B.Cu" "B.Paste" "B.Mask")
			(net 431 "unconnected-(J2-NC-Pad22)")
			(pinfunction "NC")
			(pintype "no_connect")
		)
		(pad "23" smd rect
			(at -3.751 3.775 90)
			(size 0.3 1.55)
			(layers "B.Cu" "B.Paste" "B.Mask")
			(net 93 "/M.2/C_PCIE0_TX2_N")
			(pinfunction "PET2_N")
			(pintype "input")
		)
		(pad "24" smd rect
			(at -3.501 -3.773 90)
			(size 0.3 1.55)
			(layers "B.Cu" "B.Paste" "B.Mask")
			(net 432 "unconnected-(J2-NC-Pad24)")
			(pinfunction "NC")
			(pintype "no_connect")
		)
		(pad "25" smd rect
			(at -3.251 3.775 90)
			(size 0.3 1.55)
			(layers "B.Cu" "B.Paste" "B.Mask")
			(net 92 "/M.2/C_PCIE0_TX2_P")
			(pinfunction "PET2_P")
			(pintype "input")
		)
		(pad "26" smd rect
			(at -3.001 -3.773 90)
			(size 0.3 1.55)
			(layers "B.Cu" "B.Paste" "B.Mask")
			(net 435 "unconnected-(J2-NC-Pad26)")
			(pinfunction "NC")
			(pintype "no_connect")
		)
		(pad "27" smd rect
			(at -2.751 3.775 90)
			(size 0.3 1.55)
			(layers "B.Cu" "B.Paste" "B.Mask")
			(net 1 "GND")
			(pinfunction "GND")
			(pintype "passive")
		)
		(pad "28" smd rect
			(at -2.501 -3.773 90)
			(size 0.3 1.55)
			(layers "B.Cu" "B.Paste" "B.Mask")
			(net 458 "unconnected-(J2-NC-Pad28)")
			(pinfunction "NC")
			(pintype "no_connect")
		)
		(pad "29" smd rect
			(at -2.251 3.775 90)
			(size 0.3 1.55)
			(layers "B.Cu" "B.Paste" "B.Mask")
			(net 49 "PCIE0_RX1_N")
			(pinfunction "PER1_N")
			(pintype "output")
		)
		(pad "30" smd rect
			(at -2.001 -3.773 90)
			(size 0.3 1.55)
			(layers "B.Cu" "B.Paste" "B.Mask")
			(net 462 "unconnected-(J2-NC-Pad30)")
			(pinfunction "NC")
			(pintype "no_connect")
		)
		(pad "31" smd rect
			(at -1.752 3.775 90)
			(size 0.3 1.55)
			(layers "B.Cu" "B.Paste" "B.Mask")
			(net 50 "PCIE0_RX1_P")
			(pinfunction "PER1_P")
			(pintype "output")
		)
		(pad "32" smd rect
			(at -1.502 -3.773 90)
			(size 0.3 1.55)
			(layers "B.Cu" "B.Paste" "B.Mask")
			(net 464 "unconnected-(J2-NC-Pad32)")
			(pinfunction "NC")
			(pintype "no_connect")
		)
		(pad "33" smd rect
			(at -1.252 3.775 90)
			(size 0.3 1.55)
			(layers "B.Cu" "B.Paste" "B.Mask")
			(net 1 "GND")
			(pinfunction "GND")
			(pintype "passive")
		)
		(pad "34" smd rect
			(at -1.002 -3.773 90)
			(size 0.3 1.55)
			(layers "B.Cu" "B.Paste" "B.Mask")
			(net 466 "unconnected-(J2-NC-Pad34)")
			(pinfunction "NC")
			(pintype "no_connect")
		)
		(pad "35" smd rect
			(at -0.751 3.775 90)
			(size 0.3 1.55)
			(layers "B.Cu" "B.Paste" "B.Mask")
			(net 91 "/M.2/C_PCIE0_TX1_N")
			(pinfunction "PET1_N")
			(pintype "input")
		)
		(pad "36" smd rect
			(at -0.501 -3.773 90)
			(size 0.3 1.55)
			(layers "B.Cu" "B.Paste" "B.Mask")
			(net 503 "unconnected-(J2-NC-Pad36)")
			(pinfunction "NC")
			(pintype "no_connect")
		)
		(pad "37" smd rect
			(at -0.251 3.775 90)
			(size 0.3 1.55)
			(layers "B.Cu" "B.Paste" "B.Mask")
			(net 90 "/M.2/C_PCIE0_TX1_P")
			(pinfunction "PET1_P")
			(pintype "input")
		)
		(pad "38" smd rect
			(at -0.001 -3.773 90)
			(size 0.3 1.55)
			(layers "B.Cu" "B.Paste" "B.Mask")
			(net 504 "unconnected-(J2-NC-Pad38)")
			(pinfunction "NC")
			(pintype "no_connect")
		)
		(pad "39" smd rect
			(at 0.248 3.775 90)
			(size 0.3 1.55)
			(layers "B.Cu" "B.Paste" "B.Mask")
			(net 1 "GND")
			(pinfunction "GND")
			(pintype "passive")
		)
		(pad "40" smd rect
			(at 0.498 -3.773 90)
			(size 0.3 1.55)
			(layers "B.Cu" "B.Paste" "B.Mask")
			(net 244 "/M.2/M2_M_SMB_CLK")
			(pinfunction "SMB_CLK")
			(pintype "input")
		)
		(pad "41" smd rect
			(at 0.748 3.775 90)
			(size 0.3 1.55)
			(layers "B.Cu" "B.Paste" "B.Mask")
			(net 47 "PCIE0_RX0_N")
			(pinfunction "PER0_N")
			(pintype "output")
		)
		(pad "42" smd rect
			(at 0.998 -3.773 90)
			(size 0.3 1.55)
			(layers "B.Cu" "B.Paste" "B.Mask")
			(net 245 "/M.2/M2_M_SMB_DATA")
			(pinfunction "SMB_DATA")
			(pintype "bidirectional")
		)
		(pad "43" smd rect
			(at 1.249 3.775 90)
			(size 0.3 1.55)
			(layers "B.Cu" "B.Paste" "B.Mask")
			(net 48 "PCIE0_RX0_P")
			(pinfunction "PER0_P")
			(pintype "output")
		)
		(pad "44" smd rect
			(at 1.499 -3.773 90)
			(size 0.3 1.55)
			(layers "B.Cu" "B.Paste" "B.Mask")
			(net 246 "/M.2/~{M2_M_ALERT}")
			(pinfunction "ALERT")
			(pintype "output")
		)
		(pad "45" smd rect
			(at 1.749 3.775 90)
			(size 0.3 1.55)
			(layers "B.Cu" "B.Paste" "B.Mask")
			(net 1 "GND")
			(pinfunction "GND")
			(pintype "passive")
		)
		(pad "46" smd rect
			(at 1.999 -3.773 90)
			(size 0.3 1.55)
			(layers "B.Cu" "B.Paste" "B.Mask")
			(net 506 "unconnected-(J2-NC-Pad46)")
			(pinfunction "NC")
			(pintype "no_connect")
		)
		(pad "47" smd rect
			(at 2.249 3.775 90)
			(size 0.3 1.55)
			(layers "B.Cu" "B.Paste" "B.Mask")
			(net 89 "/M.2/C_PCIE0_TX0_N")
			(pinfunction "PET0_N")
			(pintype "input")
		)
		(pad "48" smd rect
			(at 2.499 -3.773 90)
			(size 0.3 1.55)
			(layers "B.Cu" "B.Paste" "B.Mask")
			(net 507 "unconnected-(J2-NC-Pad48)")
			(pinfunction "NC")
			(pintype "no_connect")
		)
		(pad "49" smd rect
			(at 2.749 3.775 90)
			(size 0.3 1.55)
			(layers "B.Cu" "B.Paste" "B.Mask")
			(net 88 "/M.2/C_PCIE0_TX0_P")
			(pinfunction "PET0_P")
			(pintype "input")
		)
		(pad "50" smd rect
			(at 2.999 -3.773 90)
			(size 0.3 1.55)
			(layers "B.Cu" "B.Paste" "B.Mask")
			(net 247 "/M.2/~{M2_M_PERST}")
			(pinfunction "~{PERST}")
			(pintype "input")
		)
		(pad "51" smd rect
			(at 3.249 3.775 90)
			(size 0.3 1.55)
			(layers "B.Cu" "B.Paste" "B.Mask")
			(net 1 "GND")
			(pinfunction "GND")
			(pintype "passive")
		)
		(pad "52" smd rect
			(at 3.499 -3.773 90)
			(size 0.3 1.55)
			(layers "B.Cu" "B.Paste" "B.Mask")
			(net 248 "/M.2/~{M2_M_CLKREQ0}")
			(pinfunction "~{CLKREQ}")
			(pintype "output")
		)
		(pad "53" smd rect
			(at 3.749 3.775 90)
			(size 0.3 1.55)
			(layers "B.Cu" "B.Paste" "B.Mask")
			(net 55 "PCIE0_CLK_N")
			(pinfunction "REFCLK_N")
			(pintype "input")
		)
		(pad "54" smd rect
			(at 3.999 -3.773 90)
			(size 0.3 1.55)
			(layers "B.Cu" "B.Paste" "B.Mask")
			(net 249 "/M.2/~{M2_M_PEWAKE0}")
			(pinfunction "~{PEWAKE}")
			(pintype "input")
		)
		(pad "55" smd rect
			(at 4.248 3.775 90)
			(size 0.3 1.55)
			(layers "B.Cu" "B.Paste" "B.Mask")
			(net 57 "PCIE0_CLK_P")
			(pinfunction "REFCLK_P")
			(pintype "input")
		)
		(pad "56" smd rect
			(at 4.498 -3.773 90)
			(size 0.3 1.55)
			(layers "B.Cu" "B.Paste" "B.Mask")
			(net 509 "unconnected-(J2-NC-Pad56)")
			(pinfunction "NC")
			(pintype "no_connect")
		)
		(pad "57" smd rect
			(at 4.748 3.775 90)
			(size 0.3 1.55)
			(layers "B.Cu" "B.Paste" "B.Mask")
			(net 1 "GND")
			(pinfunction "GND")
			(pintype "passive")
		)
		(pad "58" smd rect
			(at 4.998 -3.773 90)
			(size 0.3 1.55)
			(layers "B.Cu" "B.Paste" "B.Mask")
			(net 510 "unconnected-(J2-NC-Pad58)")
			(pinfunction "NC")
			(pintype "no_connect")
		)
		(pad "67" smd rect
			(at 7.248 3.775 90)
			(size 0.3 1.55)
			(layers "B.Cu" "B.Paste" "B.Mask")
			(net 531 "unconnected-(J2-NC-Pad67)")
			(pinfunction "NC")
			(pintype "no_connect")
		)
		(pad "68" smd rect
			(at 7.498 -3.773 90)
			(size 0.3 1.55)
			(layers "B.Cu" "B.Paste" "B.Mask")
			(net 250 "/M.2/M2_M_SUSCLK")
			(pinfunction "SUSCLK")
			(pintype "input")
		)
		(pad "69" smd rect
			(at 7.748 3.775 90)
			(size 0.3 1.55)
			(layers "B.Cu" "B.Paste" "B.Mask")
			(net 532 "unconnected-(J2-NC-Pad69)")
			(pinfunction "NC")
			(pintype "no_connect")
		)
		(pad "70" smd rect
			(at 7.998 -3.773 90)
			(size 0.3 1.55)
			(layers "B.Cu" "B.Paste" "B.Mask")
			(net 635 "/M.2/3V3_M2")
			(pinfunction "3V3")
			(pintype "passive")
		)
		(pad "71" smd rect
			(at 8.247 3.775 90)
			(size 0.3 1.55)
			(layers "B.Cu" "B.Paste" "B.Mask")
			(net 1 "GND")
			(pinfunction "GND")
			(pintype "passive")
		)
		(pad "72" smd rect
			(at 8.497 -3.773 90)
			(size 0.3 1.55)
			(layers "B.Cu" "B.Paste" "B.Mask")
			(net 635 "/M.2/3V3_M2")
			(pinfunction "3V3")
			(pintype "passive")
		)
		(pad "73" smd rect
			(at 8.747 3.775 90)
			(size 0.3 1.55)
			(layers "B.Cu" "B.Paste" "B.Mask")
			(net 1 "GND")
			(pinfunction "GND")
			(pintype "passive")
		)
		(pad "74" smd rect
			(at 8.997 -3.773 90)
			(size 0.3 1.55)
			(layers "B.Cu" "B.Paste" "B.Mask")
			(net 635 "/M.2/3V3_M2")
			(pinfunction "3V3")
			(pintype "passive")
		)
		(pad "75" smd rect
			(at 9.247 3.775 90)
			(size 0.3 1.55)
			(layers "B.Cu" "B.Paste" "B.Mask")
			(net 1 "GND")
			(pinfunction "GND")
			(pintype "passive")
		)
		(pad "MP1" smd rect
			(at -10.352 3 90)
			(size 1.2 2.75)
			(layers "B.Cu" "B.Paste" "B.Mask")
			(net 1 "GND")
			(pinfunction "MP")
			(pintype "passive")
		)
		(pad "MP2" smd rect
			(at 10.349 3 90)
			(size 1.2 2.75)
			(layers "B.Cu" "B.Paste" "B.Mask")
			(net 1 "GND")
			(pinfunction "MP")
			(pintype "passive")
		)
	)
	(footprint "antmicro-footprints:C_0603_1608Metric"
		(layer "B.Cu")
		(at 45.175 124.245 90)
		(descr "Capacitor SMD 0603")
		(tags "capacitor 0603")
		(property "Reference" "C32"
			(at 3.255 -0.175 -90)
			(layer "B.SilkS")
			(effects
				(font
					(size 0.7 0.7)
					(thickness 0.15)
				)
				(justify left bottom mirror)
			)
		)
		(property "Value" "C_10u_25V_0603"
			(at 0 -1.6 -90)
			(layer "B.Fab")
			(effects
				(font
					(size 0.7 0.7)
					(thickness 0.15)
				)
				(justify left bottom mirror)
			)
		)
		(property "Footprint" "antmicro-footprints:C_0603_1608Metric"
			(at 0 0 90)
			(layer "F.Fab")
			(hide yes)
			(effects
				(font
					(size 1.27 1.27)
					(thickness 0.15)
				)
			)
		)
		(property "Datasheet" "https://product.tdk.com/en/search/capacitor/ceramic/mlcc/info?part_no=C1608X5R1E106M080AC"
			(at 0 0 90)
			(layer "F.Fab")
			(hide yes)
			(effects
				(font
					(size 1.27 1.27)
					(thickness 0.15)
				)
			)
		)
		(property "Author" "Antmicro"
			(at 169.42 79.07 0)
			(layer "B.Fab")
			(hide yes)
			(effects
				(font
					(size 1 1)
					(thickness 0.15)
				)
				(justify mirror)
			)
		)
		(property "Dielectric" ""
			(at 169.42 79.07 0)
			(layer "B.Fab")
			(hide yes)
			(effects
				(font
					(size 1 1)
					(thickness 0.15)
				)
				(justify mirror)
			)
		)
		(property "License" "Apache-2.0"
			(at 169.42 79.07 0)
			(layer "B.Fab")
			(hide yes)
			(effects
				(font
					(size 1 1)
					(thickness 0.15)
				)
				(justify mirror)
			)
		)
		(property "MPN" "C1608X5R1E106M080AC"
			(at 169.42 79.07 0)
			(layer "B.Fab")
			(hide yes)
			(effects
				(font
					(size 1 1)
					(thickness 0.15)
				)
				(justify mirror)
			)
		)
		(property "Manufacturer" "TDK"
			(at 169.42 79.07 0)
			(layer "B.Fab")
			(hide yes)
			(effects
				(font
					(size 1 1)
					(thickness 0.15)
				)
				(justify mirror)
			)
		)
		(property "Val" "10u"
			(at 169.42 79.07 0)
			(layer "B.Fab")
			(hide yes)
			(effects
				(font
					(size 1 1)
					(thickness 0.15)
				)
				(justify mirror)
			)
		)
		(property "Voltage" "25V"
			(at 169.42 79.07 0)
			(layer "B.Fab")
			(hide yes)
			(effects
				(font
					(size 1 1)
					(thickness 0.15)
				)
				(justify mirror)
			)
		)
		(sheetname "USB Debug, DP")
		(sheetfile "usb.kicad_sch")
		(attr smd)
		(fp_line
			(start 0.15 -0.4)
			(end -0.15 -0.4)
			(stroke
				(width 0.15)
				(type solid)
			)
			(layer "B.SilkS")
		)
		(fp_line
			(start 0.15 0.4)
			(end -0.15 0.4)
			(stroke
				(width 0.15)
				(type solid)
			)
			(layer "B.SilkS")
		)
		(fp_rect
			(start -1.25 0.65)
			(end 1.25 -0.65)
			(stroke
				(width 0.05)
				(type solid)
			)
			(fill none)
			(layer "B.CrtYd")
		)
		(fp_rect
			(start -0.8 0.4)
			(end 0.8 -0.4)
			(stroke
				(width 0.15)
				(type solid)
			)
			(fill none)
			(layer "B.Fab")
		)
		(fp_text user "License: Apache-2.0"
			(at -1.682 -5.895 -90)
			(layer "B.Fab")
			(hide yes)
			(effects
				(font
					(size 0.7 0.7)
					(thickness 0.15)
				)
				(justify left bottom mirror)
			)
		)
		(fp_text user "Author: Antmicro"
			(at -1.682 -4.894 -90)
			(layer "B.Fab")
			(hide yes)
			(effects
				(font
					(size 0.7 0.7)
					(thickness 0.15)
				)
				(justify left bottom mirror)
			)
		)
		(fp_text user "${REFERENCE}"
			(at -1.682 -3.895 -90)
			(layer "B.Fab")
			(hide yes)
			(effects
				(font
					(size 0.7 0.7)
					(thickness 0.15)
				)
				(justify left bottom mirror)
			)
		)
		(pad "1" smd roundrect
			(at -0.7 0 90)
			(size 0.8 1)
			(layers "B.Cu" "B.Paste" "B.Mask")
			(roundrect_rratio 0.2)
			(net 196 "/USB Debug, DP/USBC3_VBUS")
			(pintype "passive")
		)
		(pad "2" smd roundrect
			(at 0.7 0 90)
			(size 0.8 1)
			(layers "B.Cu" "B.Paste" "B.Mask")
			(roundrect_rratio 0.2)
			(net 1 "GND")
			(pintype "passive")
		)
	)
	(footprint "antmicro-footprints:VQFN-16-1EP_3x3mm_P0.5mm_EP1.68x1.68mm"
		(layer "B.Cu")
		(at 89.5 109.5 -90)
		(property "Reference" "U34"
			(at -1.56 -2.7 90)
			(layer "B.SilkS")
			(effects
				(font
					(size 0.7 0.7)
					(thickness 0.15)
				)
				(justify left bottom mirror)
			)
		)
		(property "Value" "PCAL6408A_VQFN"
			(at 0 -2.999 90)
			(layer "B.Fab")
			(effects
				(font
					(size 0.7 0.7)
					(thickness 0.15)
				)
				(justify left bottom mirror)
			)
		)
		(property "Footprint" "antmicro-footprints:VQFN-16-1EP_3x3mm_P0.5mm_EP1.68x1.68mm"
			(at 0 0 -90)
			(layer "F.Fab")
			(hide yes)
			(effects
				(font
					(size 1.27 1.27)
					(thickness 0.15)
				)
			)
		)
		(property "Datasheet" "https://eu.mouser.com/datasheet/2/302/PCAL6408A-3139197.pdf"
			(at 0 0 -90)
			(layer "F.Fab")
			(hide yes)
			(effects
				(font
					(size 1.27 1.27)
					(thickness 0.15)
				)
			)
		)
		(property "Author" "Antmicro"
			(at -20 199 0)
			(layer "B.Fab")
			(hide yes)
			(effects
				(font
					(size 1 1)
					(thickness 0.15)
				)
				(justify mirror)
			)
		)
		(property "License" "Apache-2.0"
			(at -20 199 0)
			(layer "B.Fab")
			(hide yes)
			(effects
				(font
					(size 1 1)
					(thickness 0.15)
				)
				(justify mirror)
			)
		)
		(property "MPN" "PCAL6408ABSHP"
			(at -20 199 0)
			(layer "B.Fab")
			(hide yes)
			(effects
				(font
					(size 1 1)
					(thickness 0.15)
				)
				(justify mirror)
			)
		)
		(property "Manufacturer" "NXP"
			(at -20 199 0)
			(layer "B.Fab")
			(hide yes)
			(effects
				(font
					(size 1 1)
					(thickness 0.15)
				)
				(justify mirror)
			)
		)
		(sheetname "Peripherals")
		(sheetfile "peripherals.kicad_sch")
		(attr smd)
		(fp_line
			(start -1.5 1.5)
			(end -0.95 1.501)
			(stroke
				(width 0.15)
				(type solid)
			)
			(layer "B.SilkS")
		)
		(fp_line
			(start 0.95 1.5)
			(end 1.499 1.5)
			(stroke
				(width 0.15)
				(type solid)
			)
			(layer "B.SilkS")
		)
		(fp_line
			(start 1.499 1.5)
			(end 1.5 0.95)
			(stroke
				(width 0.15)
				(type solid)
			)
			(layer "B.SilkS")
		)
		(fp_line
			(start -1.5 0.951)
			(end -1.5 1.5)
			(stroke
				(width 0.15)
				(type solid)
			)
			(layer "B.SilkS")
		)
		(fp_line
			(start -1.5 -0.95)
			(end -1.5 -1.499)
			(stroke
				(width 0.15)
				(type solid)
			)
			(layer "B.SilkS")
		)
		(fp_line
			(start -0.951 -1.499)
			(end -1.5 -1.499)
			(stroke
				(width 0.15)
				(type solid)
			)
			(layer "B.SilkS")
		)
		(fp_line
			(start 1.499 -1.499)
			(end 1.499 -0.95)
			(stroke
				(width 0.15)
				(type solid)
			)
			(layer "B.SilkS")
		)
		(fp_line
			(start 1.499 -1.499)
			(end 0.95 -1.499)
			(stroke
				(width 0.15)
				(type solid)
			)
			(layer "B.SilkS")
		)
		(fp_circle
			(center -1.75 1.07071)
			(end -1.7 1.07071)
			(stroke
				(width 0.15)
				(type solid)
			)
			(fill solid)
			(layer "B.SilkS")
		)
		(fp_rect
			(start -1.75 1.75)
			(end 1.75 -1.75)
			(stroke
				(width 0.05)
				(type solid)
			)
			(fill none)
			(layer "B.CrtYd")
		)
		(fp_line
			(start -1.2 1.5)
			(end -1.5 1.2)
			(stroke
				(width 0.15)
				(type solid)
			)
			(layer "B.Fab")
		)
		(fp_line
			(start 1.499 1.5)
			(end -1.2 1.5)
			(stroke
				(width 0.15)
				(type solid)
			)
			(layer "B.Fab")
		)
		(fp_line
			(start 1.499 1.5)
			(end 1.499 -1.499)
			(stroke
				(width 0.15)
				(type solid)
			)
			(layer "B.Fab")
		)
		(fp_line
			(start -1.5 -1.499)
			(end -1.5 1.2)
			(stroke
				(width 0.15)
				(type solid)
			)
			(layer "B.Fab")
		)
		(fp_line
			(start -1.5 -1.499)
			(end 1.499 -1.499)
			(stroke
				(width 0.15)
				(type solid)
			)
			(layer "B.Fab")
		)
		(fp_text user "${REFERENCE}"
			(at -1.901 -4.998 90)
			(layer "B.Fab")
			(hide yes)
			(effects
				(font
					(size 0.7 0.7)
					(thickness 0.15)
				)
				(justify left bottom mirror)
			)
		)
		(fp_text user "License: Apache-2.0"
			(at -1.901 -7.4 90)
			(layer "B.Fab")
			(hide yes)
			(effects
				(font
					(size 0.7 0.7)
					(thickness 0.15)
				)
				(justify left bottom mirror)
			)
		)
		(fp_text user "Author: Antmicro"
			(at -1.901 -6.2 90)
			(layer "B.Fab")
			(hide yes)
			(effects
				(font
					(size 0.7 0.7)
					(thickness 0.15)
				)
				(justify left bottom mirror)
			)
		)
		(pad "1" smd roundrect
			(at -1.4 0.75 270)
			(size 0.6 0.25)
			(layers "B.Cu" "B.Paste" "B.Mask")
			(roundrect_rratio 0.2)
			(net 351 "/Peripherals/GPIOEX_RESET")
			(pinfunction "~{RESET}")
			(pintype "input")
		)
		(pad "2" smd roundrect
			(at -1.4 0.25 270)
			(size 0.6 0.25)
			(layers "B.Cu" "B.Paste" "B.Mask")
			(roundrect_rratio 0.2)
			(net 353 "/Peripherals/GPIOEX_P0_0")
			(pinfunction "P0")
			(pintype "bidirectional")
		)
		(pad "3" smd roundrect
			(at -1.4 -0.25 270)
			(size 0.6 0.25)
			(layers "B.Cu" "B.Paste" "B.Mask")
			(roundrect_rratio 0.2)
			(net 354 "/Peripherals/GPIOEX_P0_1")
			(pinfunction "P1")
			(pintype "bidirectional")
		)
		(pad "4" smd roundrect
			(at -1.4 -0.75 270)
			(size 0.6 0.25)
			(layers "B.Cu" "B.Paste" "B.Mask")
			(roundrect_rratio 0.2)
			(net 355 "/Peripherals/GPIOEX_P0_2")
			(pinfunction "P2")
			(pintype "bidirectional")
		)
		(pad "5" smd roundrect
			(at -0.75 -1.4 180)
			(size 0.6 0.25)
			(layers "B.Cu" "B.Paste" "B.Mask")
			(roundrect_rratio 0.2)
			(net 356 "/Peripherals/GPIOEX_P0_3")
			(pinfunction "P3")
			(pintype "bidirectional")
		)
		(pad "6" smd roundrect
			(at -0.25 -1.4 180)
			(size 0.6 0.25)
			(layers "B.Cu" "B.Paste" "B.Mask")
			(roundrect_rratio 0.2)
			(net 1 "GND")
			(pinfunction "V_{ss}")
			(pintype "power_in")
		)
		(pad "7" smd roundrect
			(at 0.25 -1.4 180)
			(size 0.6 0.25)
			(layers "B.Cu" "B.Paste" "B.Mask")
			(roundrect_rratio 0.2)
			(net 605 "/Peripherals/GPIOEX_P0_4")
			(pinfunction "P4")
			(pintype "bidirectional")
		)
		(pad "8" smd roundrect
			(at 0.75 -1.4 180)
			(size 0.6 0.25)
			(layers "B.Cu" "B.Paste" "B.Mask")
			(roundrect_rratio 0.2)
			(net 604 "/Peripherals/GPIOEX_P0_5")
			(pinfunction "P5")
			(pintype "bidirectional")
		)
		(pad "9" smd roundrect
			(at 1.4 -0.75 90)
			(size 0.6 0.25)
			(layers "B.Cu" "B.Paste" "B.Mask")
			(roundrect_rratio 0.2)
			(net 546 "/Peripherals/GPIOEX_P0_6")
			(pinfunction "P6")
			(pintype "bidirectional")
		)
		(pad "10" smd roundrect
			(at 1.4 -0.25 90)
			(size 0.6 0.25)
			(layers "B.Cu" "B.Paste" "B.Mask")
			(roundrect_rratio 0.2)
			(net 545 "/Peripherals/GPIOEX_P0_7")
			(pinfunction "P7")
			(pintype "bidirectional")
		)
		(pad "11" smd roundrect
			(at 1.4 0.25 90)
			(size 0.6 0.25)
			(layers "B.Cu" "B.Paste" "B.Mask")
			(roundrect_rratio 0.2)
			(net 281 "~{GPIO_INT}")
			(pinfunction "~{INT}")
			(pintype "output")
		)
		(pad "12" smd roundrect
			(at 1.4 0.75 90)
			(size 0.6 0.25)
			(layers "B.Cu" "B.Paste" "B.Mask")
			(roundrect_rratio 0.2)
			(net 350 "/Peripherals/GPIOEX_I2C_SCL")
			(pinfunction "SCL")
			(pintype "input")
		)
		(pad "13" smd roundrect
			(at 0.75 1.4)
			(size 0.6 0.25)
			(layers "B.Cu" "B.Paste" "B.Mask")
			(roundrect_rratio 0.2)
			(net 349 "/Peripherals/GPIOEX_I2C_SDA")
			(pinfunction "SDA")
			(pintype "bidirectional")
		)
		(pad "14" smd roundrect
			(at 0.25 1.4)
			(size 0.6 0.25)
			(layers "B.Cu" "B.Paste" "B.Mask")
			(roundrect_rratio 0.2)
			(net 87 "+3V3")
			(pinfunction "VDD_{(P)}")
			(pintype "power_in")
		)
		(pad "15" smd roundrect
			(at -0.25 1.4)
			(size 0.6 0.25)
			(layers "B.Cu" "B.Paste" "B.Mask")
			(roundrect_rratio 0.2)
			(net 87 "+3V3")
			(pinfunction "VDD_{(I2C)}")
			(pintype "power_in")
		)
		(pad "16" smd roundrect
			(at -0.75 1.4)
			(size 0.6 0.25)
			(layers "B.Cu" "B.Paste" "B.Mask")
			(roundrect_rratio 0.2)
			(net 352 "/Peripherals/GPIOEX_ADDR")
			(pinfunction "ADDR")
			(pintype "passive")
		)
		(pad "17" smd roundrect
			(at 0 0 270)
			(size 1.68 1.68)
			(layers "B.Cu" "B.Paste" "B.Mask")
			(roundrect_rratio 0.02976190476)
			(net 716 "unconnected-(U34-EP-Pad17)")
			(pinfunction "EP")
			(pintype "power_in+no_connect")
		)
	)
	(footprint "antmicro-footprints:R_0402_1005Metric"
		(layer "B.Cu")
		(at 46.841428 81.615 180)
		(descr "Resistor SMD 0402")
		(tags "resistor SMD 0402")
		(property "Reference" "R165"
			(at 0.781428 -0.425 180)
			(layer "B.SilkS")
			(effects
				(font
					(size 0.7 0.7)
					(thickness 0.15)
				)
				(justify left bottom mirror)
			)
		)
		(property "Value" "R_4k7_0402"
			(at 0 -1.4 0)
			(layer "B.Fab")
			(effects
				(font
					(size 0.7 0.7)
					(thickness 0.15)
				)
				(justify left bottom mirror)
			)
		)
		(property "Footprint" "antmicro-footprints:R_0402_1005Metric"
			(at 0 0 180)
			(layer "F.Fab")
			(hide yes)
			(effects
				(font
					(size 1.27 1.27)
					(thickness 0.15)
				)
			)
		)
		(property "Datasheet" "https://www.bourns.com/docs/product-datasheets/cr.pdf"
			(at 0 0 180)
			(layer "F.Fab")
			(hide yes)
			(effects
				(font
					(size 1.27 1.27)
					(thickness 0.15)
				)
			)
		)
		(property "Author" "Antmicro"
			(at 95.982856 163.23 0)
			(layer "B.Fab")
			(hide yes)
			(effects
				(font
					(size 1 1)
					(thickness 0.15)
				)
				(justify mirror)
			)
		)
		(property "License" "Apache-2.0"
			(at 95.982856 163.23 0)
			(layer "B.Fab")
			(hide yes)
			(effects
				(font
					(size 1 1)
					(thickness 0.15)
				)
				(justify mirror)
			)
		)
		(property "MPN" "CR0402-FX-4701GLF"
			(at 95.982856 163.23 0)
			(layer "B.Fab")
			(hide yes)
			(effects
				(font
					(size 1 1)
					(thickness 0.15)
				)
				(justify mirror)
			)
		)
		(property "Manufacturer" "Bourns"
			(at 95.982856 163.23 0)
			(layer "B.Fab")
			(hide yes)
			(effects
				(font
					(size 1 1)
					(thickness 0.15)
				)
				(justify mirror)
			)
		)
		(property "Tolerance" "1%"
			(at 95.982856 163.23 0)
			(layer "B.Fab")
			(hide yes)
			(effects
				(font
					(size 1 1)
					(thickness 0.15)
				)
				(justify mirror)
			)
		)
		(property "Val" "4k7"
			(at 95.982856 163.23 0)
			(layer "B.Fab")
			(hide yes)
			(effects
				(font
					(size 1 1)
					(thickness 0.15)
				)
				(justify mirror)
			)
		)
		(sheetname "Supply")
		(sheetfile "supply.kicad_sch")
		(attr smd)
		(fp_rect
			(start -0.925 0.47)
			(end 0.925 -0.47)
			(stroke
				(width 0.05)
				(type default)
			)
			(fill none)
			(layer "B.CrtYd")
		)
		(fp_rect
			(start -0.5 0.25)
			(end 0.5 -0.25)
			(stroke
				(width 0.15)
				(type solid)
			)
			(fill none)
			(layer "B.Fab")
		)
		(fp_text user "${REFERENCE}"
			(at -0.95 -3.168 0)
			(layer "B.Fab")
			(hide yes)
			(effects
				(font
					(size 0.7 0.7)
					(thickness 0.15)
				)
				(justify left bottom mirror)
			)
		)
		(fp_text user "Author: Antmicro"
			(at -0.95 -4.169 0)
			(layer "B.Fab")
			(hide yes)
			(effects
				(font
					(size 0.7 0.7)
					(thickness 0.15)
				)
				(justify left bottom mirror)
			)
		)
		(fp_text user "License: Apache-2.0"
			(at -0.95 -5.169 0)
			(layer "B.Fab")
			(hide yes)
			(effects
				(font
					(size 0.7 0.7)
					(thickness 0.15)
				)
				(justify left bottom mirror)
			)
		)
		(pad "1" smd roundrect
			(at -0.48 0 180)
			(size 0.59 0.64)
			(layers "B.Cu" "B.Paste" "B.Mask")
			(roundrect_rratio 0.25)
			(net 1 "GND")
			(pintype "passive")
		)
		(pad "2" smd roundrect
			(at 0.48 0 180)
			(size 0.59 0.64)
			(layers "B.Cu" "B.Paste" "B.Mask")
			(roundrect_rratio 0.25)
			(net 135 "Net-(Q18-G)")
			(pintype "passive")
		)
	)
	(footprint "antmicro-footprints:R_0603_1608Metric"
		(layer "B.Cu")
		(at 119.56 99.99 -90)
		(descr "Resistor SMD 0603")
		(tags "resistor SMD 0603")
		(property "Reference" "R143"
			(at -1.44 0.66 90)
			(layer "B.SilkS")
			(effects
				(font
					(size 0.7 0.7)
					(thickness 0.15)
				)
				(justify left bottom mirror)
			)
		)
		(property "Value" "R_0R_22.4A_0603"
			(at 0 -1.6 90)
			(layer "B.Fab")
			(effects
				(font
					(size 0.7 0.7)
					(thickness 0.15)
				)
				(justify left bottom mirror)
			)
		)
		(property "Footprint" "antmicro-footprints:R_0603_1608Metric"
			(at 0 0 -90)
			(layer "F.Fab")
			(hide yes)
			(effects
				(font
					(size 1.27 1.27)
					(thickness 0.15)
				)
			)
		)
		(property "Datasheet" "https://fscdn.rohm.com/en/products/databook/datasheet/passive/resistor/chip_resistor/pmr-jpw-e.pdf"
			(at 0 0 -90)
			(layer "F.Fab")
			(hide yes)
			(effects
				(font
					(size 1.27 1.27)
					(thickness 0.15)
				)
			)
		)
		(property "Author" "Antmicro"
			(at 19.57 219.55 0)
			(layer "B.Fab")
			(hide yes)
			(effects
				(font
					(size 1 1)
					(thickness 0.15)
				)
				(justify mirror)
			)
		)
		(property "License" "Apache-2.0"
			(at 19.57 219.55 0)
			(layer "B.Fab")
			(hide yes)
			(effects
				(font
					(size 1 1)
					(thickness 0.15)
				)
				(justify mirror)
			)
		)
		(property "MPN" "PMR03EZPJ000"
			(at 19.57 219.55 0)
			(layer "B.Fab")
			(hide yes)
			(effects
				(font
					(size 1 1)
					(thickness 0.15)
				)
				(justify mirror)
			)
		)
		(property "Manufacturer" "ROHM Semiconductor"
			(at 19.57 219.55 0)
			(layer "B.Fab")
			(hide yes)
			(effects
				(font
					(size 1 1)
					(thickness 0.15)
				)
				(justify mirror)
			)
		)
		(property "Max. Curr." "22.4A"
			(at 19.57 219.55 0)
			(layer "B.Fab")
			(hide yes)
			(effects
				(font
					(size 1 1)
					(thickness 0.15)
				)
				(justify mirror)
			)
		)
		(property "Tolerance" "template_tolerance"
			(at 19.57 219.55 0)
			(layer "B.Fab")
			(hide yes)
			(effects
				(font
					(size 1 1)
					(thickness 0.15)
				)
				(justify mirror)
			)
		)
		(property "Val" "0R"
			(at 19.57 219.55 0)
			(layer "B.Fab")
			(hide yes)
			(effects
				(font
					(size 1 1)
					(thickness 0.15)
				)
				(justify mirror)
			)
		)
		(sheetname "M.2")
		(sheetfile "m-2.kicad_sch")
		(attr smd)
		(fp_line
			(start 0.15 0.4)
			(end -0.15 0.4)
			(stroke
				(width 0.15)
				(type solid)
			)
			(layer "B.SilkS")
		)
		(fp_line
			(start 0.15 -0.4)
			(end -0.15 -0.4)
			(stroke
				(width 0.15)
				(type solid)
			)
			(layer "B.SilkS")
		)
		(fp_rect
			(start -1.25 0.65)
			(end 1.25 -0.65)
			(stroke
				(width 0.05)
				(type solid)
			)
			(fill none)
			(layer "B.CrtYd")
		)
		(fp_rect
			(start -0.8 0.4)
			(end 0.8 -0.4)
			(stroke
				(width 0.15)
				(type solid)
			)
			(fill none)
			(layer "B.Fab")
		)
		(fp_text user "Author: Antmicro"
			(at -1.25 -4.9 90)
			(layer "B.Fab")
			(hide yes)
			(effects
				(font
					(size 0.7 0.7)
					(thickness 0.15)
				)
				(justify left bottom mirror)
			)
		)
		(fp_text user "${REFERENCE}"
			(at -1.25 -3.898 90)
			(layer "B.Fab")
			(hide yes)
			(effects
				(font
					(size 0.7 0.7)
					(thickness 0.15)
				)
				(justify left bottom mirror)
			)
		)
		(fp_text user "License: Apache-2.0"
			(at -1.25 -5.9 90)
			(layer "B.Fab")
			(hide yes)
			(effects
				(font
					(size 0.7 0.7)
					(thickness 0.15)
				)
				(justify left bottom mirror)
			)
		)
		(pad "1" smd roundrect
			(at -0.7 0 270)
			(size 0.8 1)
			(layers "B.Cu" "B.Paste" "B.Mask")
			(roundrect_rratio 0.2)
			(net 635 "/M.2/3V3_M2")
			(pintype "passive")
		)
		(pad "2" smd roundrect
			(at 0.7 0 270)
			(size 0.8 1)
			(layers "B.Cu" "B.Paste" "B.Mask")
			(roundrect_rratio 0.2)
			(net 87 "+3V3")
			(pintype "passive")
		)
	)
	(footprint "antmicro-footprints:LED_0603_1608Metric_G"
		(layer "B.Cu")
		(at 44.2 126.95 180)
		(descr "LED SMD 0603 Green")
		(tags "LED SMD 0603 Green")
		(property "Reference" "D3"
			(at 4.55 -1.3 0)
			(layer "B.SilkS")
			(effects
				(font
					(size 0.7 0.7)
					(thickness 0.15)
				)
				(justify left bottom mirror)
			)
		)
		(property "Value" "LED_G_0603_LTST-C190GKT"
			(at -0.001 -1.599 0)
			(layer "B.Fab")
			(effects
				(font
					(size 0.7 0.7)
					(thickness 0.15)
				)
				(justify left bottom mirror)
			)
		)
		(property "Footprint" "antmicro-footprints:LED_0603_1608Metric_G"
			(at 0 0 180)
			(layer "F.Fab")
			(hide yes)
			(effects
				(font
					(size 1.27 1.27)
					(thickness 0.15)
				)
			)
		)
		(property "Datasheet" "https://media.digikey.com/pdf/Data%20Sheets/Lite-On%20PDFs/LTST-C190GKT.pdf"
			(at 0 0 180)
			(layer "F.Fab")
			(hide yes)
			(effects
				(font
					(size 1.27 1.27)
					(thickness 0.15)
				)
			)
		)
		(property "Author" "Antmicro"
			(at 88.4 253.9 0)
			(layer "B.Fab")
			(hide yes)
			(effects
				(font
					(size 1 1)
					(thickness 0.15)
				)
				(justify mirror)
			)
		)
		(property "Color" "Green"
			(at 88.4 253.9 0)
			(layer "B.Fab")
			(hide yes)
			(effects
				(font
					(size 1 1)
					(thickness 0.15)
				)
				(justify mirror)
			)
		)
		(property "License" "Apache-2.0"
			(at 88.4 253.9 0)
			(layer "B.Fab")
			(hide yes)
			(effects
				(font
					(size 1 1)
					(thickness 0.15)
				)
				(justify mirror)
			)
		)
		(property "MPN" "LTST-C190GKT"
			(at 88.4 253.9 0)
			(layer "B.Fab")
			(hide yes)
			(effects
				(font
					(size 1 1)
					(thickness 0.15)
				)
				(justify mirror)
			)
		)
		(property "Manufacturer" "Lite-On"
			(at 88.4 253.9 0)
			(layer "B.Fab")
			(hide yes)
			(effects
				(font
					(size 1 1)
					(thickness 0.15)
				)
				(justify mirror)
			)
		)
		(sheetname "USB Debug, DP")
		(sheetfile "usb.kicad_sch")
		(attr smd)
		(fp_line
			(start 0.24 -0.001)
			(end 0.105328 -0.001008)
			(stroke
				(width 0.1)
				(type solid)
			)
			(layer "B.SilkS")
		)
		(fp_line
			(start 0.105328 0.198992)
			(end 0.105328 -0.201008)
			(stroke
				(width 0.1)
				(type solid)
			)
			(layer "B.SilkS")
		)
		(fp_line
			(start 0.105328 0.198992)
			(end -0.094672 -0.001008)
			(stroke
				(width 0.1)
				(type solid)
			)
			(layer "B.SilkS")
		)
		(fp_line
			(start -0.094672 0.198992)
			(end -0.094672 -0.201008)
			(stroke
				(width 0.1)
				(type solid)
			)
			(layer "B.SilkS")
		)
		(fp_line
			(start -0.094672 -0.001008)
			(end 0.105328 -0.201008)
			(stroke
				(width 0.1)
				(type solid)
			)
			(layer "B.SilkS")
		)
		(fp_line
			(start -0.22 0.35)
			(end 0.22 0.35)
			(stroke
				(width 0.15)
				(type solid)
			)
			(layer "B.SilkS")
		)
		(fp_line
			(start -0.22 -0.35)
			(end 0.22 -0.35)
			(stroke
				(width 0.15)
				(type solid)
			)
			(layer "B.SilkS")
		)
		(fp_line
			(start -0.24 -0.001008)
			(end -0.094672 -0.001008)
			(stroke
				(width 0.1)
				(type solid)
			)
			(layer "B.SilkS")
		)
		(fp_line
			(start -1.18 -0.321)
			(end -1.18 0.319)
			(stroke
				(width 0.15)
				(type solid)
			)
			(layer "B.SilkS")
		)
		(fp_rect
			(start 1.25 -0.65)
			(end -1.25 0.65)
			(stroke
				(width 0.05)
				(type solid)
			)
			(fill none)
			(layer "B.CrtYd")
		)
		(fp_line
			(start 0.201 0.202)
			(end 0.201 0)
			(stroke
				(width 0.15)
				(type solid)
			)
			(layer "B.Fab")
		)
		(fp_line
			(start 0.201 0)
			(end 0.599 0)
			(stroke
				(width 0.15)
				(type solid)
			)
			(layer "B.Fab")
		)
		(fp_line
			(start 0.201 0)
			(end 0.201 -0.2)
			(stroke
				(width 0.15)
				(type solid)
			)
			(layer "B.Fab")
		)
		(fp_line
			(start 0.201 -0.2)
			(end -0.101 0)
			(stroke
				(width 0.15)
				(type solid)
			)
			(layer "B.Fab")
		)
		(fp_line
			(start -0.101 0)
			(end 0.201 0.202)
			(stroke
				(width 0.15)
				(type solid)
			)
			(layer "B.Fab")
		)
		(fp_line
			(start -0.199 -0.1)
			(end -0.199 0.202)
			(stroke
				(width 0.15)
				(type solid)
			)
			(layer "B.Fab")
		)
		(fp_line
			(start -0.199 -0.1)
			(end -0.199 -0.2)
			(stroke
				(width 0.15)
				(type solid)
			)
			(layer "B.Fab")
		)
		(fp_line
			(start -0.597 0)
			(end -0.199 0)
			(stroke
				(width 0.15)
				(type solid)
			)
			(layer "B.Fab")
		)
		(fp_rect
			(start 0.848 -0.4)
			(end -0.85 0.402)
			(stroke
				(width 0.15)
				(type solid)
			)
			(fill none)
			(layer "B.Fab")
		)
		(fp_text user "Author: Antmicro"
			(at -1.4224 -4.799 0)
			(layer "B.Fab")
			(hide yes)
			(effects
				(font
					(size 0.7 0.7)
					(thickness 0.15)
				)
				(justify left bottom mirror)
			)
		)
		(fp_text user "License: Apache-2.0"
			(at -1.4224 -3.599 0)
			(layer "B.Fab")
			(hide yes)
			(effects
				(font
					(size 0.7 0.7)
					(thickness 0.15)
				)
				(justify left bottom mirror)
			)
		)
		(fp_text user "${REFERENCE}"
			(at -1.4224 -5.999 0)
			(layer "B.Fab")
			(hide yes)
			(effects
				(font
					(size 0.7 0.7)
					(thickness 0.15)
				)
				(justify left bottom mirror)
			)
		)
		(pad "1" smd roundrect
			(at -0.7 0)
			(size 0.8 1)
			(layers "B.Cu" "B.Paste" "B.Mask")
			(roundrect_rratio 0.2)
			(net 272 "/USB Debug, DP/FTDI_LED_RX")
			(pinfunction "C")
			(pintype "passive")
		)
		(pad "2" smd roundrect
			(at 0.7 0)
			(size 0.8 1)
			(layers "B.Cu" "B.Paste" "B.Mask")
			(roundrect_rratio 0.2)
			(net 143 "Net-(D3-A)")
			(pinfunction "A")
			(pintype "passive")
		)
	)
	(footprint "antmicro-footprints:DFN-6-1EP_2x2mm_P0.65mm_EP1x1.6mm"
		(layer "B.Cu")
		(at 139.53 124.82)
		(descr "6-Lead Plastic Dual Flat, No Lead Package - 2x2x0.9 mm Body")
		(tags "DFN")
		(property "Reference" "U35"
			(at 2.42 0.08 90)
			(layer "B.SilkS")
			(effects
				(font
					(size 0.7 0.7)
					(thickness 0.15)
				)
				(justify left bottom mirror)
			)
		)
		(property "Value" "AP22653_DFN"
			(at 0 -2.1 180)
			(layer "B.Fab")
			(effects
				(font
					(size 0.7 0.7)
					(thickness 0.15)
				)
				(justify left bottom mirror)
			)
		)
		(property "Footprint" "antmicro-footprints:DFN-6-1EP_2x2mm_P0.65mm_EP1x1.6mm"
			(at 0 0 0)
			(layer "F.Fab")
			(hide yes)
			(effects
				(font
					(size 1.27 1.27)
					(thickness 0.15)
				)
			)
		)
		(property "Datasheet" "https://www.mouser.com/datasheet/2/115/DIOD_S_A0010880137_1-2543666.pdf"
			(at 0 0 0)
			(layer "F.Fab")
			(hide yes)
			(effects
				(font
					(size 1.27 1.27)
					(thickness 0.15)
				)
			)
		)
		(property "Author" "Antmicro"
			(at 0 0 0)
			(layer "B.Fab")
			(hide yes)
			(effects
				(font
					(size 1 1)
					(thickness 0.15)
				)
				(justify mirror)
			)
		)
		(property "License" "Apache-2.0"
			(at 0 0 0)
			(layer "B.Fab")
			(hide yes)
			(effects
				(font
					(size 1 1)
					(thickness 0.15)
				)
				(justify mirror)
			)
		)
		(property "MPN" "AP22653FDZ-7"
			(at 0 0 0)
			(layer "B.Fab")
			(hide yes)
			(effects
				(font
					(size 1 1)
					(thickness 0.15)
				)
				(justify mirror)
			)
		)
		(property "Manufacturer" "Diodes Incorporated"
			(at 0 0 0)
			(layer "B.Fab")
			(hide yes)
			(effects
				(font
					(size 1 1)
					(thickness 0.15)
				)
				(justify mirror)
			)
		)
		(sheetname "Peripherals")
		(sheetfile "peripherals.kicad_sch")
		(attr smd)
		(fp_line
			(start -1.075 -1.1125)
			(end -1.075 -0.9375)
			(stroke
				(width 0.15)
				(type solid)
			)
			(layer "B.SilkS")
		)
		(fp_line
			(start -1.075 0.925)
			(end -1.075 1.1)
			(stroke
				(width 0.15)
				(type solid)
			)
			(layer "B.SilkS")
		)
		(fp_line
			(start 1.075 -1.1125)
			(end -1.075 -1.1125)
			(stroke
				(width 0.15)
				(type solid)
			)
			(layer "B.SilkS")
		)
		(fp_line
			(start 1.075 -1.1125)
			(end 1.075 -0.9375)
			(stroke
				(width 0.15)
				(type solid)
			)
			(layer "B.SilkS")
		)
		(fp_line
			(start 1.075 0.925)
			(end 1.075 1.1)
			(stroke
				(width 0.15)
				(type solid)
			)
			(layer "B.SilkS")
		)
		(fp_line
			(start 1.075 1.1)
			(end -1.075 1.1)
			(stroke
				(width 0.15)
				(type solid)
			)
			(layer "B.SilkS")
		)
		(fp_circle
			(center -1.325 1.04571)
			(end -1.275 1.04571)
			(stroke
				(width 0.15)
				(type solid)
			)
			(fill solid)
			(layer "B.SilkS")
		)
		(fp_rect
			(start -1.405 1.25)
			(end 1.405 -1.225)
			(stroke
				(width 0.05)
				(type solid)
			)
			(fill none)
			(layer "B.CrtYd")
		)
		(fp_line
			(start -0.5 1)
			(end -1 0.5)
			(stroke
				(width 0.15)
				(type solid)
			)
			(layer "B.Fab")
		)
		(fp_rect
			(start 1 -1)
			(end -1 1)
			(stroke
				(width 0.15)
				(type solid)
			)
			(fill none)
			(layer "B.Fab")
		)
		(fp_text user "License: Apache-2.0"
			(at -1.405 -5.799 180)
			(layer "B.Fab")
			(hide yes)
			(effects
				(font
					(size 0.7 0.7)
					(thickness 0.15)
				)
				(justify left bottom mirror)
			)
		)
		(fp_text user "${REFERENCE}"
			(at -1.405 -3.4 180)
			(layer "B.Fab")
			(hide yes)
			(effects
				(font
					(size 0.7 0.7)
					(thickness 0.15)
				)
				(justify left bottom mirror)
			)
		)
		(fp_text user "Author: Antmicro"
			(at -1.405 -4.6 180)
			(layer "B.Fab")
			(hide yes)
			(effects
				(font
					(size 0.7 0.7)
					(thickness 0.15)
				)
				(justify left bottom mirror)
			)
		)
		(pad "" smd rect
			(at 0 -0.4)
			(size 0.82 0.63)
			(layers "B.Paste")
		)
		(pad "" smd rect
			(at 0 0.402)
			(size 0.82 0.63)
			(layers "B.Paste")
		)
		(pad "1" smd rect
			(at -1.051 0.652)
			(size 0.65 0.35)
			(layers "B.Cu" "B.Paste" "B.Mask")
			(net 662 "/Peripherals/I2C_CONN_3V3")
			(pinfunction "OUT")
			(pintype "power_out")
		)
		(pad "2" smd rect
			(at -1.051 0)
			(size 0.65 0.35)
			(layers "B.Cu" "B.Paste" "B.Mask")
			(net 685 "Net-(U35-ISET)")
			(pinfunction "ISET")
			(pintype "passive")
		)
		(pad "3" smd rect
			(at -1.051 -0.65)
			(size 0.65 0.35)
			(layers "B.Cu" "B.Paste" "B.Mask")
			(net 719 "unconnected-(U35-FLG-Pad3)")
			(pinfunction "FLG")
			(pintype "output+no_connect")
		)
		(pad "4" smd rect
			(at 1.05 -0.65)
			(size 0.65 0.35)
			(layers "B.Cu" "B.Paste" "B.Mask")
			(net 658 "/Peripherals/I2C_CONN_PEN")
			(pinfunction "EN")
			(pintype "input")
		)
		(pad "5" smd rect
			(at 1.05 0)
			(size 0.65 0.35)
			(layers "B.Cu" "B.Paste" "B.Mask")
			(net 1 "GND")
			(pinfunction "GND")
			(pintype "power_in")
		)
		(pad "6" smd rect
			(at 1.05 0.652)
			(size 0.65 0.35)
			(layers "B.Cu" "B.Paste" "B.Mask")
			(net 87 "+3V3")
			(pinfunction "IN")
			(pintype "power_in")
		)
		(pad "7" smd rect
			(at 0 0)
			(size 1 1.6)
			(layers "B.Cu" "B.Mask")
			(net 1 "GND")
			(pinfunction "EP")
			(pintype "power_in")
		)
	)
	(footprint "antmicro-footprints:R_0402_1005Metric"
		(layer "B.Cu")
		(at 58.65 86.77 90)
		(descr "Resistor SMD 0402")
		(tags "resistor SMD 0402")
		(property "Reference" "R268"
			(at -1.47 -0.44 90)
			(layer "B.SilkS")
			(effects
				(font
					(size 0.7 0.7)
					(thickness 0.15)
				)
				(justify right bottom mirror)
			)
		)
		(property "Value" "R_0R_0402"
			(at 0 -1.4 90)
			(layer "B.Fab")
			(effects
				(font
					(size 0.7 0.7)
					(thickness 0.15)
				)
				(justify right bottom mirror)
			)
		)
		(property "Footprint" "antmicro-footprints:R_0402_1005Metric"
			(at 0 0 90)
			(layer "F.Fab")
			(hide yes)
			(effects
				(font
					(size 1.27 1.27)
					(thickness 0.15)
				)
			)
		)
		(property "Datasheet" "https://industrial.panasonic.com/cdbs/www-data/pdf/RDA0000/AOA0000C301.pdf"
			(at 0 0 90)
			(layer "F.Fab")
			(hide yes)
			(effects
				(font
					(size 1.27 1.27)
					(thickness 0.15)
				)
			)
		)
		(property "Author" "Antmicro"
			(at 145.36 28.18 0)
			(layer "B.Fab")
			(hide yes)
			(effects
				(font
					(size 1 1)
					(thickness 0.15)
				)
				(justify mirror)
			)
		)
		(property "Current" "1A"
			(at 145.36 28.18 0)
			(layer "B.Fab")
			(hide yes)
			(effects
				(font
					(size 1 1)
					(thickness 0.15)
				)
				(justify mirror)
			)
		)
		(property "License" "Apache-2.0"
			(at 145.36 28.18 0)
			(layer "B.Fab")
			(hide yes)
			(effects
				(font
					(size 1 1)
					(thickness 0.15)
				)
				(justify mirror)
			)
		)
		(property "MPN" "ERJ2GE0R00X"
			(at 145.36 28.18 0)
			(layer "B.Fab")
			(hide yes)
			(effects
				(font
					(size 1 1)
					(thickness 0.15)
				)
				(justify mirror)
			)
		)
		(property "Manufacturer" "Panasonic"
			(at 145.36 28.18 0)
			(layer "B.Fab")
			(hide yes)
			(effects
				(font
					(size 1 1)
					(thickness 0.15)
				)
				(justify mirror)
			)
		)
		(property "Tolerance" ""
			(at 145.36 28.18 0)
			(layer "B.Fab")
			(hide yes)
			(effects
				(font
					(size 1 1)
					(thickness 0.15)
				)
				(justify mirror)
			)
		)
		(property "Val" "0R"
			(at 145.36 28.18 0)
			(layer "B.Fab")
			(hide yes)
			(effects
				(font
					(size 1 1)
					(thickness 0.15)
				)
				(justify mirror)
			)
		)
		(sheetname "Supply")
		(sheetfile "supply.kicad_sch")
		(attr smd)
		(fp_rect
			(start -0.925 0.47)
			(end 0.925 -0.47)
			(stroke
				(width 0.05)
				(type default)
			)
			(fill none)
			(layer "B.CrtYd")
		)
		(fp_rect
			(start -0.5 0.25)
			(end 0.5 -0.25)
			(stroke
				(width 0.15)
				(type solid)
			)
			(fill none)
			(layer "B.Fab")
		)
		(fp_text user "Author: Antmicro"
			(at -0.95 -4.169 90)
			(layer "B.Fab")
			(hide yes)
			(effects
				(font
					(size 0.7 0.7)
					(thickness 0.15)
				)
				(justify right bottom mirror)
			)
		)
		(fp_text user "License: Apache-2.0"
			(at -0.95 -5.169 90)
			(layer "B.Fab")
			(hide yes)
			(effects
				(font
					(size 0.7 0.7)
					(thickness 0.15)
				)
				(justify right bottom mirror)
			)
		)
		(fp_text user "${REFERENCE}"
			(at -0.95 -3.168 90)
			(layer "B.Fab")
			(hide yes)
			(effects
				(font
					(size 0.7 0.7)
					(thickness 0.15)
				)
				(justify right bottom mirror)
			)
		)
		(pad "1" smd roundrect
			(at -0.48 0 90)
			(size 0.59 0.64)
			(layers "B.Cu" "B.Paste" "B.Mask")
			(roundrect_rratio 0.25)
			(net 86 "~{RESET}")
			(pintype "passive")
		)
		(pad "2" smd roundrect
			(at 0.48 0 90)
			(size 0.59 0.64)
			(layers "B.Cu" "B.Paste" "B.Mask")
			(roundrect_rratio 0.25)
			(net 690 "Net-(U42-EN)")
			(pintype "passive")
		)
	)
	(footprint "antmicro-footprints:C_0402_1005Metric"
		(layer "B.Cu")
		(at 114.6 80.4)
		(descr "Capacitor SMD 0402")
		(tags "capacitor SMD 0402")
		(property "Reference" "C25"
			(at 1.15 -0.4 180)
			(layer "B.SilkS")
			(effects
				(font
					(size 0.7 0.7)
					(thickness 0.15)
				)
				(justify left bottom mirror)
			)
		)
		(property "Value" "C_100n_0402"
			(at 0 -1.4 180)
			(layer "B.Fab")
			(effects
				(font
					(size 0.7 0.7)
					(thickness 0.15)
				)
				(justify left bottom mirror)
			)
		)
		(property "Footprint" "antmicro-footprints:C_0402_1005Metric"
			(at 0 0 0)
			(layer "F.Fab")
			(hide yes)
			(effects
				(font
					(size 1.27 1.27)
					(thickness 0.15)
				)
			)
		)
		(property "Datasheet" "https://www.murata.com/products/productdetail?partno=GRM155R61H104KE14%23"
			(at 0 0 0)
			(layer "F.Fab")
			(hide yes)
			(effects
				(font
					(size 1.27 1.27)
					(thickness 0.15)
				)
			)
		)
		(property "Author" "Antmicro"
			(at 0 0 0)
			(layer "B.Fab")
			(hide yes)
			(effects
				(font
					(size 1 1)
					(thickness 0.15)
				)
				(justify mirror)
			)
		)
		(property "Dielectric" "X5R"
			(at 0 0 0)
			(layer "B.Fab")
			(hide yes)
			(effects
				(font
					(size 1 1)
					(thickness 0.15)
				)
				(justify mirror)
			)
		)
		(property "License" "Apache-2.0"
			(at 0 0 0)
			(layer "B.Fab")
			(hide yes)
			(effects
				(font
					(size 1 1)
					(thickness 0.15)
				)
				(justify mirror)
			)
		)
		(property "MPN" "GRM155R61H104KE14D"
			(at 0 0 0)
			(layer "B.Fab")
			(hide yes)
			(effects
				(font
					(size 1 1)
					(thickness 0.15)
				)
				(justify mirror)
			)
		)
		(property "Manufacturer" "Murata"
			(at 0 0 0)
			(layer "B.Fab")
			(hide yes)
			(effects
				(font
					(size 1 1)
					(thickness 0.15)
				)
				(justify mirror)
			)
		)
		(property "Val" "100n"
			(at 0 0 0)
			(layer "B.Fab")
			(hide yes)
			(effects
				(font
					(size 1 1)
					(thickness 0.15)
				)
				(justify mirror)
			)
		)
		(property "Voltage" "50V"
			(at 0 0 0)
			(layer "B.Fab")
			(hide yes)
			(effects
				(font
					(size 1 1)
					(thickness 0.15)
				)
				(justify mirror)
			)
		)
		(sheetname "M.2")
		(sheetfile "m-2.kicad_sch")
		(attr smd)
		(fp_rect
			(start -0.925 0.47)
			(end 0.925 -0.47)
			(stroke
				(width 0.05)
				(type default)
			)
			(fill none)
			(layer "B.CrtYd")
		)
		(fp_line
			(start -0.494 -0.248)
			(end 0.504 -0.248)
			(stroke
				(width 0.15)
				(type solid)
			)
			(layer "B.Fab")
		)
		(fp_line
			(start -0.494 0.25)
			(end -0.494 -0.248)
			(stroke
				(width 0.15)
				(type solid)
			)
			(layer "B.Fab")
		)
		(fp_line
			(start 0.504 -0.248)
			(end 0.504 0.25)
			(stroke
				(width 0.15)
				(type solid)
			)
			(layer "B.Fab")
		)
		(fp_line
			(start 0.504 0.25)
			(end -0.494 0.25)
			(stroke
				(width 0.15)
				(type solid)
			)
			(layer "B.Fab")
		)
		(fp_text user "License: Apache-2.0"
			(at -0.932 -5.17 180)
			(layer "B.Fab")
			(hide yes)
			(effects
				(font
					(size 0.7 0.7)
					(thickness 0.15)
				)
				(justify left bottom mirror)
			)
		)
		(fp_text user "Author: Antmicro"
			(at -0.932 -4.17 180)
			(layer "B.Fab")
			(hide yes)
			(effects
				(font
					(size 0.7 0.7)
					(thickness 0.15)
				)
				(justify left bottom mirror)
			)
		)
		(fp_text user "${REFERENCE}"
			(at -0.932 -3.168 180)
			(layer "B.Fab")
			(hide yes)
			(effects
				(font
					(size 0.7 0.7)
					(thickness 0.15)
				)
				(justify left bottom mirror)
			)
		)
		(pad "1" smd roundrect
			(at -0.48 0)
			(size 0.59 0.64)
			(layers "B.Cu" "B.Paste" "B.Mask")
			(roundrect_rratio 0.25)
			(net 87 "+3V3")
			(pintype "passive")
		)
		(pad "2" smd roundrect
			(at 0.48 0)
			(size 0.59 0.64)
			(layers "B.Cu" "B.Paste" "B.Mask")
			(roundrect_rratio 0.25)
			(net 1 "GND")
			(pintype "passive")
		)
	)
	(footprint "antmicro-footprints:R_0603_1608Metric"
		(layer "B.Cu")
		(at 63.65 109.9 -90)
		(descr "Resistor SMD 0603")
		(tags "resistor SMD 0603")
		(property "Reference" "R252"
			(at 1.22 -0.22 90)
			(layer "B.SilkS")
			(effects
				(font
					(size 0.7 0.7)
					(thickness 0.15)
				)
				(justify left bottom mirror)
			)
		)
		(property "Value" "R_0R_22.4A_0603"
			(at 0 -1.6 90)
			(layer "B.Fab")
			(effects
				(font
					(size 0.7 0.7)
					(thickness 0.15)
				)
				(justify left bottom mirror)
			)
		)
		(property "Footprint" "antmicro-footprints:R_0603_1608Metric"
			(at 0 0 -90)
			(layer "F.Fab")
			(hide yes)
			(effects
				(font
					(size 1.27 1.27)
					(thickness 0.15)
				)
			)
		)
		(property "Datasheet" "https://fscdn.rohm.com/en/products/databook/datasheet/passive/resistor/chip_resistor/pmr-jpw-e.pdf"
			(at 0 0 -90)
			(layer "F.Fab")
			(hide yes)
			(effects
				(font
					(size 1.27 1.27)
					(thickness 0.15)
				)
			)
		)
		(property "Author" "Antmicro"
			(at -46.25 173.55 0)
			(layer "B.Fab")
			(hide yes)
			(effects
				(font
					(size 1 1)
					(thickness 0.15)
				)
				(justify mirror)
			)
		)
		(property "License" "Apache-2.0"
			(at -46.25 173.55 0)
			(layer "B.Fab")
			(hide yes)
			(effects
				(font
					(size 1 1)
					(thickness 0.15)
				)
				(justify mirror)
			)
		)
		(property "MPN" "PMR03EZPJ000"
			(at -46.25 173.55 0)
			(layer "B.Fab")
			(hide yes)
			(effects
				(font
					(size 1 1)
					(thickness 0.15)
				)
				(justify mirror)
			)
		)
		(property "Manufacturer" "ROHM Semiconductor"
			(at -46.25 173.55 0)
			(layer "B.Fab")
			(hide yes)
			(effects
				(font
					(size 1 1)
					(thickness 0.15)
				)
				(justify mirror)
			)
		)
		(property "Max. Curr." "22.4A"
			(at -46.25 173.55 0)
			(layer "B.Fab")
			(hide yes)
			(effects
				(font
					(size 1 1)
					(thickness 0.15)
				)
				(justify mirror)
			)
		)
		(property "Tolerance" "template_tolerance"
			(at -46.25 173.55 0)
			(layer "B.Fab")
			(hide yes)
			(effects
				(font
					(size 1 1)
					(thickness 0.15)
				)
				(justify mirror)
			)
		)
		(property "Val" "0R"
			(at -46.25 173.55 0)
			(layer "B.Fab")
			(hide yes)
			(effects
				(font
					(size 1 1)
					(thickness 0.15)
				)
				(justify mirror)
			)
		)
		(sheetname "Supply")
		(sheetfile "supply.kicad_sch")
		(attr smd)
		(fp_line
			(start 0.15 0.4)
			(end -0.15 0.4)
			(stroke
				(width 0.15)
				(type solid)
			)
			(layer "B.SilkS")
		)
		(fp_line
			(start 0.15 -0.4)
			(end -0.15 -0.4)
			(stroke
				(width 0.15)
				(type solid)
			)
			(layer "B.SilkS")
		)
		(fp_rect
			(start -1.25 0.65)
			(end 1.25 -0.65)
			(stroke
				(width 0.05)
				(type solid)
			)
			(fill none)
			(layer "B.CrtYd")
		)
		(fp_rect
			(start -0.8 0.4)
			(end 0.8 -0.4)
			(stroke
				(width 0.15)
				(type solid)
			)
			(fill none)
			(layer "B.Fab")
		)
		(fp_text user "${REFERENCE}"
			(at -1.25 -3.898 90)
			(layer "B.Fab")
			(hide yes)
			(effects
				(font
					(size 0.7 0.7)
					(thickness 0.15)
				)
				(justify left bottom mirror)
			)
		)
		(fp_text user "Author: Antmicro"
			(at -1.25 -4.9 90)
			(layer "B.Fab")
			(hide yes)
			(effects
				(font
					(size 0.7 0.7)
					(thickness 0.15)
				)
				(justify left bottom mirror)
			)
		)
		(fp_text user "License: Apache-2.0"
			(at -1.25 -5.9 90)
			(layer "B.Fab")
			(hide yes)
			(effects
				(font
					(size 0.7 0.7)
					(thickness 0.15)
				)
				(justify left bottom mirror)
			)
		)
		(pad "1" smd roundrect
			(at -0.7 0 270)
			(size 0.8 1)
			(layers "B.Cu" "B.Paste" "B.Mask")
			(roundrect_rratio 0.2)
			(net 480 "USBPD1_HV")
			(pintype "passive")
		)
		(pad "2" smd roundrect
			(at 0.7 0 270)
			(size 0.8 1)
			(layers "B.Cu" "B.Paste" "B.Mask")
			(roundrect_rratio 0.2)
			(net 328 "/Supply/VCC_IN")
			(pintype "passive")
		)
	)
	(footprint "antmicro-footprints:C_0402_1005Metric"
		(layer "B.Cu")
		(at 56.3 77.2)
		(descr "Capacitor SMD 0402")
		(tags "capacitor SMD 0402")
		(property "Reference" "C117"
			(at 20.11 9.22 0)
			(layer "B.SilkS")
			(effects
				(font
					(size 0.7 0.7)
					(thickness 0.15)
				)
				(justify right bottom mirror)
			)
		)
		(property "Value" "C_10u_0402"
			(at 0 -1.4 0)
			(layer "B.Fab")
			(effects
				(font
					(size 0.7 0.7)
					(thickness 0.15)
				)
				(justify right bottom mirror)
			)
		)
		(property "Footprint" "antmicro-footprints:C_0402_1005Metric"
			(at 0 0 0)
			(layer "F.Fab")
			(hide yes)
			(effects
				(font
					(size 1.27 1.27)
					(thickness 0.15)
				)
			)
		)
		(property "Datasheet" "https://www.yageo.com/en/Chart/Download/pdf/CC0402MRX5R5BB106"
			(at 0 0 0)
			(layer "F.Fab")
			(hide yes)
			(effects
				(font
					(size 1.27 1.27)
					(thickness 0.15)
				)
			)
		)
		(property "Author" "Antmicro"
			(at 0 0 0)
			(layer "B.Fab")
			(hide yes)
			(effects
				(font
					(size 1 1)
					(thickness 0.15)
				)
				(justify mirror)
			)
		)
		(property "Dielectric" ""
			(at 0 0 0)
			(layer "B.Fab")
			(hide yes)
			(effects
				(font
					(size 1 1)
					(thickness 0.15)
				)
				(justify mirror)
			)
		)
		(property "License" "Apache-2.0"
			(at 0 0 0)
			(layer "B.Fab")
			(hide yes)
			(effects
				(font
					(size 1 1)
					(thickness 0.15)
				)
				(justify mirror)
			)
		)
		(property "MPN" "CC0402MRX5R5BB106"
			(at 0 0 0)
			(layer "B.Fab")
			(hide yes)
			(effects
				(font
					(size 1 1)
					(thickness 0.15)
				)
				(justify mirror)
			)
		)
		(property "Manufacturer" "YAGEO"
			(at 0 0 0)
			(layer "B.Fab")
			(hide yes)
			(effects
				(font
					(size 1 1)
					(thickness 0.15)
				)
				(justify mirror)
			)
		)
		(property "Val" "10u"
			(at 0 0 0)
			(layer "B.Fab")
			(hide yes)
			(effects
				(font
					(size 1 1)
					(thickness 0.15)
				)
				(justify mirror)
			)
		)
		(property "Voltage" ""
			(at 0 0 0)
			(layer "B.Fab")
			(hide yes)
			(effects
				(font
					(size 1 1)
					(thickness 0.15)
				)
				(justify mirror)
			)
		)
		(sheetname "Supply")
		(sheetfile "supply.kicad_sch")
		(attr smd)
		(fp_rect
			(start -0.925 0.47)
			(end 0.925 -0.47)
			(stroke
				(width 0.05)
				(type default)
			)
			(fill none)
			(layer "B.CrtYd")
		)
		(fp_line
			(start -0.494 -0.248)
			(end 0.504 -0.248)
			(stroke
				(width 0.15)
				(type solid)
			)
			(layer "B.Fab")
		)
		(fp_line
			(start -0.494 0.25)
			(end -0.494 -0.248)
			(stroke
				(width 0.15)
				(type solid)
			)
			(layer "B.Fab")
		)
		(fp_line
			(start 0.504 -0.248)
			(end 0.504 0.25)
			(stroke
				(width 0.15)
				(type solid)
			)
			(layer "B.Fab")
		)
		(fp_line
			(start 0.504 0.25)
			(end -0.494 0.25)
			(stroke
				(width 0.15)
				(type solid)
			)
			(layer "B.Fab")
		)
		(fp_text user "License: Apache-2.0"
			(at -0.932 -5.17 0)
			(layer "B.Fab")
			(hide yes)
			(effects
				(font
					(size 0.7 0.7)
					(thickness 0.15)
				)
				(justify right bottom mirror)
			)
		)
		(fp_text user "${REFERENCE}"
			(at -0.932 -3.168 0)
			(layer "B.Fab")
			(hide yes)
			(effects
				(font
					(size 0.7 0.7)
					(thickness 0.15)
				)
				(justify right bottom mirror)
			)
		)
		(fp_text user "Author: Antmicro"
			(at -0.932 -4.17 0)
			(layer "B.Fab")
			(hide yes)
			(effects
				(font
					(size 0.7 0.7)
					(thickness 0.15)
				)
				(justify right bottom mirror)
			)
		)
		(pad "1" smd roundrect
			(at -0.48 0)
			(size 0.59 0.64)
			(layers "B.Cu" "B.Paste" "B.Mask")
			(roundrect_rratio 0.25)
			(net 1 "GND")
			(pintype "passive")
		)
		(pad "2" smd roundrect
			(at 0.48 0)
			(size 0.59 0.64)
			(layers "B.Cu" "B.Paste" "B.Mask")
			(roundrect_rratio 0.25)
			(net 174 "Net-(D36-C)")
			(pintype "passive")
		)
	)
	(footprint "antmicro-footprints:R_0402_1005Metric"
		(layer "B.Cu")
		(at 68.2 110.25 90)
		(descr "Resistor SMD 0402")
		(tags "resistor SMD 0402")
		(property "Reference" "R43"
			(at -0.98 0.35 -90)
			(layer "B.SilkS")
			(effects
				(font
					(size 0.7 0.7)
					(thickness 0.15)
				)
				(justify left bottom mirror)
			)
		)
		(property "Value" "R_100k_0402"
			(at 0 -1.4 -90)
			(layer "B.Fab")
			(effects
				(font
					(size 0.7 0.7)
					(thickness 0.15)
				)
				(justify left bottom mirror)
			)
		)
		(property "Footprint" "antmicro-footprints:R_0402_1005Metric"
			(at 0 0 90)
			(layer "F.Fab")
			(hide yes)
			(effects
				(font
					(size 1.27 1.27)
					(thickness 0.15)
				)
			)
		)
		(property "Datasheet" "https://www.bourns.com/docs/product-datasheets/cr.pdf"
			(at 0 0 90)
			(layer "F.Fab")
			(hide yes)
			(effects
				(font
					(size 1.27 1.27)
					(thickness 0.15)
				)
			)
		)
		(property "Author" "Antmicro"
			(at 178.45 42.05 0)
			(layer "B.Fab")
			(hide yes)
			(effects
				(font
					(size 1 1)
					(thickness 0.15)
				)
				(justify mirror)
			)
		)
		(property "License" "Apache-2.0"
			(at 178.45 42.05 0)
			(layer "B.Fab")
			(hide yes)
			(effects
				(font
					(size 1 1)
					(thickness 0.15)
				)
				(justify mirror)
			)
		)
		(property "MPN" "CR0402-FX-1003GLF"
			(at 178.45 42.05 0)
			(layer "B.Fab")
			(hide yes)
			(effects
				(font
					(size 1 1)
					(thickness 0.15)
				)
				(justify mirror)
			)
		)
		(property "Manufacturer" "Bourns"
			(at 178.45 42.05 0)
			(layer "B.Fab")
			(hide yes)
			(effects
				(font
					(size 1 1)
					(thickness 0.15)
				)
				(justify mirror)
			)
		)
		(property "Tolerance" "1%"
			(at 178.45 42.05 0)
			(layer "B.Fab")
			(hide yes)
			(effects
				(font
					(size 1 1)
					(thickness 0.15)
				)
				(justify mirror)
			)
		)
		(property "Val" "100k"
			(at 178.45 42.05 0)
			(layer "B.Fab")
			(hide yes)
			(effects
				(font
					(size 1 1)
					(thickness 0.15)
				)
				(justify mirror)
			)
		)
		(sheetname "USB Debug, DP")
		(sheetfile "usb.kicad_sch")
		(attr smd)
		(fp_rect
			(start -0.925 0.47)
			(end 0.925 -0.47)
			(stroke
				(width 0.05)
				(type default)
			)
			(fill none)
			(layer "B.CrtYd")
		)
		(fp_rect
			(start -0.5 0.25)
			(end 0.5 -0.25)
			(stroke
				(width 0.15)
				(type solid)
			)
			(fill none)
			(layer "B.Fab")
		)
		(fp_text user "Author: Antmicro"
			(at -0.95 -4.169 -90)
			(layer "B.Fab")
			(hide yes)
			(effects
				(font
					(size 0.7 0.7)
					(thickness 0.15)
				)
				(justify left bottom mirror)
			)
		)
		(fp_text user "License: Apache-2.0"
			(at -0.95 -5.169 -90)
			(layer "B.Fab")
			(hide yes)
			(effects
				(font
					(size 0.7 0.7)
					(thickness 0.15)
				)
				(justify left bottom mirror)
			)
		)
		(fp_text user "${REFERENCE}"
			(at -0.95 -3.168 -90)
			(layer "B.Fab")
			(hide yes)
			(effects
				(font
					(size 0.7 0.7)
					(thickness 0.15)
				)
				(justify left bottom mirror)
			)
		)
		(pad "1" smd roundrect
			(at -0.48 0 90)
			(size 0.59 0.64)
			(layers "B.Cu" "B.Paste" "B.Mask")
			(roundrect_rratio 0.25)
			(net 1 "GND")
			(pintype "passive")
		)
		(pad "2" smd roundrect
			(at 0.48 0 90)
			(size 0.59 0.64)
			(layers "B.Cu" "B.Paste" "B.Mask")
			(roundrect_rratio 0.25)
			(net 286 "/USB Debug, DP/PDC_ADCIN1")
			(pintype "passive")
		)
	)
	(footprint "antmicro-footprints:TP_SMD_0.75mm"
		(layer "B.Cu")
		(at 130.085 86.7192)
		(property "Reference" "TP10"
			(at 0.395 0.365001 0)
			(layer "B.SilkS")
			(effects
				(font
					(size 0.7 0.7)
					(thickness 0.15)
				)
				(justify right bottom mirror)
			)
		)
		(property "Value" "TP_0.75mm_SMD"
			(at 0 -1.2 0)
			(layer "B.Fab")
			(effects
				(font
					(size 0.7 0.7)
					(thickness 0.15)
				)
				(justify right bottom mirror)
			)
		)
		(property "Footprint" "antmicro-footprints:TP_SMD_0.75mm"
			(at 0 0 0)
			(layer "F.Fab")
			(hide yes)
			(effects
				(font
					(size 1.27 1.27)
					(thickness 0.15)
				)
			)
		)
		(property "Author" "Antmicro"
			(at 0 0 0)
			(layer "B.Fab")
			(hide yes)
			(effects
				(font
					(size 1 1)
					(thickness 0.15)
				)
				(justify mirror)
			)
		)
		(property "License" "Apache-2.0"
			(at 0 0 0)
			(layer "B.Fab")
			(hide yes)
			(effects
				(font
					(size 1 1)
					(thickness 0.15)
				)
				(justify mirror)
			)
		)
		(property "MPN" ""
			(at 0 0 0)
			(layer "B.Fab")
			(hide yes)
			(effects
				(font
					(size 1 1)
					(thickness 0.15)
				)
				(justify mirror)
			)
		)
		(property "Manufacturer" ""
			(at 0 0 0)
			(layer "B.Fab")
			(hide yes)
			(effects
				(font
					(size 1 1)
					(thickness 0.15)
				)
				(justify mirror)
			)
		)
		(sheetname "M.2")
		(sheetfile "m-2.kicad_sch")
		(attr exclude_from_pos_files exclude_from_bom)
		(fp_circle
			(center 0 0)
			(end 0.475 0)
			(stroke
				(width 0.05)
				(type default)
			)
			(fill none)
			(layer "B.CrtYd")
		)
		(fp_text user "${REFERENCE}"
			(at -0.4 -2.7 0)
			(layer "B.Fab")
			(hide yes)
			(effects
				(font
					(size 0.7 0.7)
					(thickness 0.15)
				)
				(justify right bottom mirror)
			)
		)
		(fp_text user "License: Apache-2.0"
			(at -0.4 -5.101 0)
			(layer "B.Fab")
			(hide yes)
			(effects
				(font
					(size 0.7 0.7)
					(thickness 0.15)
				)
				(justify right bottom mirror)
			)
		)
		(fp_text user "Author: Antmicro"
			(at -0.4 -3.901 0)
			(layer "B.Fab")
			(hide yes)
			(effects
				(font
					(size 0.7 0.7)
					(thickness 0.15)
				)
				(justify right bottom mirror)
			)
		)
		(pad "1" smd circle
			(at 0 0)
			(size 0.75 0.75)
			(layers "B.Cu" "B.Mask")
			(net 246 "/M.2/~{M2_M_ALERT}")
			(pinfunction "1")
			(pintype "passive")
		)
	)
	(footprint "antmicro-footprints:WSON-6-1EP_2x2mm_P0.65mm"
		(layer "B.Cu")
		(at 73.8 80.1)
		(property "Reference" "U41"
			(at 1.02 2.02 180)
			(layer "B.SilkS")
			(effects
				(font
					(size 0.7 0.7)
					(thickness 0.15)
				)
				(justify left bottom mirror)
			)
		)
		(property "Value" "NCP730BMT330_WSON"
			(at 0 -2.2 180)
			(layer "B.Fab")
			(effects
				(font
					(size 0.7 0.7)
					(thickness 0.15)
				)
				(justify left bottom mirror)
			)
		)
		(property "Footprint" "antmicro-footprints:WSON-6-1EP_2x2mm_P0.65mm"
			(at 0 0 0)
			(layer "F.Fab")
			(hide yes)
			(effects
				(font
					(size 1.27 1.27)
					(thickness 0.15)
				)
			)
		)
		(property "Datasheet" "https://www.onsemi.com/download/data-sheet/pdf/ncp730-d.pdf"
			(at 0 0 0)
			(layer "F.Fab")
			(hide yes)
			(effects
				(font
					(size 1.27 1.27)
					(thickness 0.15)
				)
			)
		)
		(property "Author" "Antmicro"
			(at 0 0 0)
			(layer "B.Fab")
			(hide yes)
			(effects
				(font
					(size 1 1)
					(thickness 0.15)
				)
				(justify mirror)
			)
		)
		(property "License" "Apache-2.0"
			(at 0 0 0)
			(layer "B.Fab")
			(hide yes)
			(effects
				(font
					(size 1 1)
					(thickness 0.15)
				)
				(justify mirror)
			)
		)
		(property "MPN" "NCP730BMT330TBG"
			(at 0 0 0)
			(layer "B.Fab")
			(hide yes)
			(effects
				(font
					(size 1 1)
					(thickness 0.15)
				)
				(justify mirror)
			)
		)
		(property "Manufacturer" "ON Semiconductor"
			(at 0 0 0)
			(layer "B.Fab")
			(hide yes)
			(effects
				(font
					(size 1 1)
					(thickness 0.15)
				)
				(justify mirror)
			)
		)
		(sheetname "Supply")
		(sheetfile "supply.kicad_sch")
		(attr smd)
		(fp_line
			(start -1.05 1)
			(end 1 1)
			(stroke
				(width 0.12)
				(type solid)
			)
			(layer "B.SilkS")
		)
		(fp_line
			(start 1 -1)
			(end -1 -1)
			(stroke
				(width 0.12)
				(type solid)
			)
			(layer "B.SilkS")
		)
		(fp_circle
			(center -1.275 1.075)
			(end -1.224 1.075)
			(stroke
				(width 0.15)
				(type solid)
			)
			(fill solid)
			(layer "B.SilkS")
		)
		(fp_rect
			(start -1.45 1.25)
			(end 1.45 -1.25)
			(stroke
				(width 0.05)
				(type solid)
			)
			(fill none)
			(layer "B.CrtYd")
		)
		(fp_text user "License: Apache-2.0"
			(at -1.01 -6.4 180)
			(layer "B.Fab")
			(hide yes)
			(effects
				(font
					(size 0.7 0.7)
					(thickness 0.15)
				)
				(justify left bottom mirror)
			)
		)
		(fp_text user "Author: Antmicro"
			(at -1.01 -5.2 180)
			(layer "B.Fab")
			(hide yes)
			(effects
				(font
					(size 0.7 0.7)
					(thickness 0.15)
				)
				(justify left bottom mirror)
			)
		)
		(fp_text user "${REFERENCE}"
			(at -1.01 -3.999 180)
			(layer "B.Fab")
			(hide yes)
			(effects
				(font
					(size 0.7 0.7)
					(thickness 0.15)
				)
				(justify left bottom mirror)
			)
		)
		(pad "1" smd roundrect
			(at -0.975 0.652)
			(size 0.45 0.4)
			(layers "B.Cu" "B.Paste" "B.Mask")
			(roundrect_rratio 0.25)
			(net 138 "/Supply/3V3_LDO")
			(pinfunction "V_{OUT}")
			(pintype "power_out")
		)
		(pad "2" smd roundrect
			(at -0.975 0)
			(size 0.45 0.4)
			(layers "B.Cu" "B.Paste" "B.Mask")
			(roundrect_rratio 0.25)
			(net 725 "unconnected-(U41-NC-Pad2)")
			(pinfunction "NC")
			(pintype "no_connect")
		)
		(pad "3" smd roundrect
			(at -0.975 -0.65)
			(size 0.45 0.4)
			(layers "B.Cu" "B.Paste" "B.Mask")
			(roundrect_rratio 0.25)
			(net 1 "GND")
			(pinfunction "GND")
			(pintype "power_in")
		)
		(pad "4" smd roundrect
			(at 0.973 -0.65)
			(size 0.45 0.4)
			(layers "B.Cu" "B.Paste" "B.Mask")
			(roundrect_rratio 0.25)
			(net 115 "VCC")
			(pinfunction "EN")
			(pintype "input")
		)
		(pad "5" smd roundrect
			(at 0.973 0)
			(size 0.45 0.4)
			(layers "B.Cu" "B.Paste" "B.Mask")
			(roundrect_rratio 0.25)
			(net 1 "GND")
			(pinfunction "PG")
			(pintype "open_collector")
		)
		(pad "6" smd roundrect
			(at 0.973 0.652)
			(size 0.45 0.4)
			(layers "B.Cu" "B.Paste" "B.Mask")
			(roundrect_rratio 0.25)
			(net 115 "VCC")
			(pinfunction "V_{IN}")
			(pintype "power_in")
		)
		(pad "7" smd roundrect
			(at 0 0)
			(size 1.12 1.72)
			(layers "B.Cu" "B.Paste" "B.Mask")
			(roundrect_rratio 0.1)
			(net 1 "GND")
			(pinfunction "GND")
			(pintype "passive")
		)
	)
	(footprint "antmicro-footprints:R_Array_4x0201_Panasonic_EXB18V"
		(layer "B.Cu")
		(at 91.6 112.25 180)
		(property "Reference" "R195"
			(at 0.25 0.75 0)
			(layer "B.SilkS")
			(effects
				(font
					(size 0.7 0.7)
					(thickness 0.15)
				)
				(justify right bottom mirror)
			)
		)
		(property "Value" "R_4x0R_0201_array"
			(at -1.1 -1.8 0)
			(layer "B.Fab")
			(effects
				(font
					(size 0.7 0.7)
					(thickness 0.15)
				)
				(justify left bottom mirror)
			)
		)
		(property "Footprint" "antmicro-footprints:R_Array_4x0201_Panasonic_EXB18V"
			(at 0 0 180)
			(layer "F.Fab")
			(hide yes)
			(effects
				(font
					(size 1.27 1.27)
					(thickness 0.15)
				)
			)
		)
		(property "Datasheet" "http://industrial.panasonic.com/cdbs/www-data/pdf/AOC0000/AOC0000C14.pdf"
			(at 0 0 180)
			(layer "F.Fab")
			(hide yes)
			(effects
				(font
					(size 1.27 1.27)
					(thickness 0.15)
				)
			)
		)
		(property "Author" "Antmicro"
			(at 183.2 224.5 0)
			(layer "B.Fab")
			(hide yes)
			(effects
				(font
					(size 1 1)
					(thickness 0.15)
				)
				(justify mirror)
			)
		)
		(property "License" "Apache-2.0"
			(at 183.2 224.5 0)
			(layer "B.Fab")
			(hide yes)
			(effects
				(font
					(size 1 1)
					(thickness 0.15)
				)
				(justify mirror)
			)
		)
		(property "MPN" "EXB-18VR000X"
			(at 183.2 224.5 0)
			(layer "B.Fab")
			(hide yes)
			(effects
				(font
					(size 1 1)
					(thickness 0.15)
				)
				(justify mirror)
			)
		)
		(property "Manufacturer" "Panasonic"
			(at 183.2 224.5 0)
			(layer "B.Fab")
			(hide yes)
			(effects
				(font
					(size 1 1)
					(thickness 0.15)
				)
				(justify mirror)
			)
		)
		(property "Val" "4x0R_0201"
			(at 183.2 224.5 0)
			(layer "B.Fab")
			(hide yes)
			(effects
				(font
					(size 1 1)
					(thickness 0.15)
				)
				(justify mirror)
			)
		)
		(sheetname "Peripherals")
		(sheetfile "peripherals.kicad_sch")
		(attr smd)
		(fp_line
			(start 0.8 -0.45)
			(end 0.8 0.45)
			(stroke
				(width 0.12)
				(type solid)
			)
			(layer "B.SilkS")
		)
		(fp_line
			(start -0.8 -0.45)
			(end -0.8 0.45)
			(stroke
				(width 0.12)
				(type solid)
			)
			(layer "B.SilkS")
		)
		(fp_rect
			(start -0.898 0.66)
			(end 0.898 -0.65)
			(stroke
				(width 0.05)
				(type solid)
			)
			(fill none)
			(layer "B.CrtYd")
		)
		(fp_text user "Author: Antmicro"
			(at -1.051 -4.599 0)
			(layer "B.Fab")
			(hide yes)
			(effects
				(font
					(size 0.7 0.7)
					(thickness 0.15)
				)
				(justify left bottom mirror)
			)
		)
		(fp_text user "License: Apache-2.0"
			(at -1.051 -6 0)
			(layer "B.Fab")
			(hide yes)
			(effects
				(font
					(size 0.7 0.7)
					(thickness 0.15)
				)
				(justify left bottom mirror)
			)
		)
		(fp_text user "${REFERENCE}"
			(at -1.051 -3.2 0)
			(layer "B.Fab")
			(hide yes)
			(effects
				(font
					(size 0.7 0.7)
					(thickness 0.15)
				)
				(justify left bottom mirror)
			)
		)
		(pad "1" smd roundrect
			(at -0.6 -0.298 180)
			(size 0.2 0.4)
			(layers "B.Cu" "B.Paste" "B.Mask")
			(roundrect_rratio 0.25)
			(net 311 "CSIA_FLG")
			(pinfunction "R1.1")
			(pintype "passive")
		)
		(pad "2" smd roundrect
			(at -0.202 -0.298 180)
			(size 0.2 0.4)
			(layers "B.Cu" "B.Paste" "B.Mask")
			(roundrect_rratio 0.25)
			(net 393 "CSIB_FLG")
			(pinfunction "R2.1")
			(pintype "passive")
		)
		(pad "3" smd roundrect
			(at 0.2 -0.298 180)
			(size 0.2 0.4)
			(layers "B.Cu" "B.Paste" "B.Mask")
			(roundrect_rratio 0.25)
			(net 508 "USBC1_FLG")
			(pinfunction "R3.1")
			(pintype "passive")
		)
		(pad "4" smd roundrect
			(at 0.598 -0.298 180)
			(size 0.2 0.4)
			(layers "B.Cu" "B.Paste" "B.Mask")
			(roundrect_rratio 0.25)
			(net 505 "USBC0_FLG")
			(pinfunction "R4.1")
			(pintype "passive")
		)
		(pad "5" smd roundrect
			(at 0.598 0.3 180)
			(size 0.2 0.4)
			(layers "B.Cu" "B.Paste" "B.Mask")
			(roundrect_rratio 0.25)
			(net 545 "/Peripherals/GPIOEX_P0_7")
			(pinfunction "R4.2")
			(pintype "passive")
		)
		(pad "6" smd roundrect
			(at 0.2 0.3 180)
			(size 0.2 0.4)
			(layers "B.Cu" "B.Paste" "B.Mask")
			(roundrect_rratio 0.25)
			(net 546 "/Peripherals/GPIOEX_P0_6")
			(pinfunction "R3.2")
			(pintype "passive")
		)
		(pad "7" smd roundrect
			(at -0.202 0.3 180)
			(size 0.2 0.4)
			(layers "B.Cu" "B.Paste" "B.Mask")
			(roundrect_rratio 0.25)
			(net 604 "/Peripherals/GPIOEX_P0_5")
			(pinfunction "R2.2")
			(pintype "passive")
		)
		(pad "8" smd roundrect
			(at -0.6 0.3 180)
			(size 0.2 0.4)
			(layers "B.Cu" "B.Paste" "B.Mask")
			(roundrect_rratio 0.25)
			(net 605 "/Peripherals/GPIOEX_P0_4")
			(pinfunction "R1.2")
			(pintype "passive")
		)
	)
	(footprint "antmicro-footprints:R_0402_1005Metric"
		(layer "B.Cu")
		(at 45.15 119.925)
		(descr "Resistor SMD 0402")
		(tags "resistor SMD 0402")
		(property "Reference" "R271"
			(at -1.71 1.015 90)
			(layer "B.SilkS")
			(effects
				(font
					(size 0.7 0.7)
					(thickness 0.15)
				)
				(justify right bottom mirror)
			)
		)
		(property "Value" "R_10M_0402"
			(at -1.011843 -1.772047 0)
			(layer "B.Fab")
			(effects
				(font
					(size 0.7 0.7)
					(thickness 0.15)
				)
				(justify right bottom mirror)
			)
		)
		(property "Footprint" "antmicro-footprints:R_0402_1005Metric"
			(at 0 0 0)
			(layer "F.Fab")
			(hide yes)
			(effects
				(font
					(size 1.27 1.27)
					(thickness 0.15)
				)
			)
		)
		(property "Datasheet" "https://www.bourns.com/docs/product-datasheets/cr.pdf"
			(at 0 0 0)
			(layer "F.Fab")
			(hide yes)
			(effects
				(font
					(size 1.27 1.27)
					(thickness 0.15)
				)
			)
		)
		(property "Author" "Antmicro"
			(at 0 0 0)
			(layer "B.Fab")
			(hide yes)
			(effects
				(font
					(size 1 1)
					(thickness 0.15)
				)
				(justify mirror)
			)
		)
		(property "License" "Apache-2.0"
			(at 0 0 0)
			(layer "B.Fab")
			(hide yes)
			(effects
				(font
					(size 1 1)
					(thickness 0.15)
				)
				(justify mirror)
			)
		)
		(property "MPN" "CR0402-FX-1005GLF"
			(at 0 0 0)
			(layer "B.Fab")
			(hide yes)
			(effects
				(font
					(size 1 1)
					(thickness 0.15)
				)
				(justify mirror)
			)
		)
		(property "Manufacturer" "Bourns"
			(at 0 0 0)
			(layer "B.Fab")
			(hide yes)
			(effects
				(font
					(size 1 1)
					(thickness 0.15)
				)
				(justify mirror)
			)
		)
		(property "Tolerance" "1%"
			(at 0 0 0)
			(layer "B.Fab")
			(hide yes)
			(effects
				(font
					(size 1 1)
					(thickness 0.15)
				)
				(justify mirror)
			)
		)
		(property "Val" "10M"
			(at 0 0 0)
			(layer "B.Fab")
			(hide yes)
			(effects
				(font
					(size 1 1)
					(thickness 0.15)
				)
				(justify mirror)
			)
		)
		(sheetname "USB Debug, DP")
		(sheetfile "usb.kicad_sch")
		(attr smd exclude_from_pos_files exclude_from_bom dnp)
		(fp_rect
			(start -0.925 0.47)
			(end 0.925 -0.47)
			(stroke
				(width 0.05)
				(type default)
			)
			(fill none)
			(layer "B.CrtYd")
		)
		(fp_rect
			(start -0.5 0.25)
			(end 0.5 -0.25)
			(stroke
				(width 0.15)
				(type solid)
			)
			(fill none)
			(layer "B.Fab")
		)
		(fp_text user "${REFERENCE}"
			(at -0.95 -3.168 0)
			(layer "B.Fab")
			(hide yes)
			(effects
				(font
					(size 0.7 0.7)
					(thickness 0.15)
				)
				(justify right bottom mirror)
			)
		)
		(fp_text user "License: Apache-2.0"
			(at -0.95 -5.169 0)
			(layer "B.Fab")
			(hide yes)
			(effects
				(font
					(size 0.7 0.7)
					(thickness 0.15)
				)
				(justify right bottom mirror)
			)
		)
		(fp_text user "Author: Antmicro"
			(at -0.95 -4.169 0)
			(layer "B.Fab")
			(hide yes)
			(effects
				(font
					(size 0.7 0.7)
					(thickness 0.15)
				)
				(justify right bottom mirror)
			)
		)
		(pad "1" smd roundrect
			(at -0.48 0)
			(size 0.59 0.64)
			(layers "B.Cu" "B.Paste" "B.Mask")
			(roundrect_rratio 0.25)
			(net 1 "GND")
			(pintype "passive")
		)
		(pad "2" smd roundrect
			(at 0.48 0)
			(size 0.59 0.64)
			(layers "B.Cu" "B.Paste" "B.Mask")
			(roundrect_rratio 0.25)
			(net 86 "~{RESET}")
			(pintype "passive")
		)
	)
	(footprint "antmicro-footprints:Fiducial_1mm_Mask2mm"
		(layer "B.Cu")
		(at 31.25 127.25 180)
		(descr "Circular Fiducial, 1mm bare copper, 3mm soldermask opening")
		(tags "fiducial")
		(property "Reference" "FID5"
			(at 0 1.4 0)
			(layer "B.SilkS")
			(hide yes)
			(effects
				(font
					(size 0.7 0.7)
					(thickness 0.15)
				)
				(justify left bottom mirror)
			)
		)
		(property "Value" "Fiducial_1mm_Mask2mm"
			(at 0 -2.2 0)
			(layer "B.Fab")
			(effects
				(font
					(size 0.7 0.7)
					(thickness 0.15)
				)
				(justify left bottom mirror)
			)
		)
		(property "Footprint" "antmicro-footprints:Fiducial_1mm_Mask2mm"
			(at 0 0 180)
			(layer "F.Fab")
			(hide yes)
			(effects
				(font
					(size 1.27 1.27)
					(thickness 0.15)
				)
			)
		)
		(attr board_only exclude_from_pos_files exclude_from_bom)
		(fp_circle
			(center 0 0)
			(end 1.24 0)
			(stroke
				(width 0.05)
				(type solid)
			)
			(fill none)
			(layer "B.CrtYd")
		)
		(fp_circle
			(center 0 0)
			(end 0.999 0)
			(stroke
				(width 0.15)
				(type solid)
			)
			(fill none)
			(layer "B.Fab")
		)
		(fp_text user "${REFERENCE}"
			(at -1.25 -4.603 0)
			(layer "B.Fab")
			(hide yes)
			(effects
				(font
					(size 0.7 0.7)
					(thickness 0.15)
				)
				(justify left bottom mirror)
			)
		)
		(fp_text user "Author: Antmicro"
			(at -1.25 -5.803 0)
			(layer "B.Fab")
			(hide yes)
			(effects
				(font
					(size 0.7 0.7)
					(thickness 0.15)
				)
				(justify left bottom mirror)
			)
		)
		(fp_text user "License: Apache-2.0"
			(at -1.25 -7.003 0)
			(layer "B.Fab")
			(hide yes)
			(effects
				(font
					(size 0.7 0.7)
					(thickness 0.15)
				)
				(justify left bottom mirror)
			)
		)
		(pad "" smd circle
			(at 0 0 180)
			(size 1 1)
			(layers "B.Cu" "B.Mask")
			(solder_mask_margin 0.5)
			(clearance 0.5)
		)
	)
	(footprint "antmicro-footprints:C_0402_1005Metric"
		(layer "B.Cu")
		(at 49.75 113.75 180)
		(descr "Capacitor SMD 0402")
		(tags "capacitor SMD 0402")
		(property "Reference" "C27"
			(at 13.12 -9.78 0)
			(layer "B.SilkS")
			(effects
				(font
					(size 0.7 0.7)
					(thickness 0.15)
				)
				(justify left bottom mirror)
			)
		)
		(property "Value" "C_100n_0402"
			(at 0 -1.4 0)
			(layer "B.Fab")
			(effects
				(font
					(size 0.7 0.7)
					(thickness 0.15)
				)
				(justify left bottom mirror)
			)
		)
		(property "Footprint" "antmicro-footprints:C_0402_1005Metric"
			(at 0 0 180)
			(layer "F.Fab")
			(hide yes)
			(effects
				(font
					(size 1.27 1.27)
					(thickness 0.15)
				)
			)
		)
		(property "Datasheet" "https://www.murata.com/products/productdetail?partno=GRM155R61H104KE14%23"
			(at 0 0 180)
			(layer "F.Fab")
			(hide yes)
			(effects
				(font
					(size 1.27 1.27)
					(thickness 0.15)
				)
			)
		)
		(property "Author" "Antmicro"
			(at 99.5 227.5 0)
			(layer "B.Fab")
			(hide yes)
			(effects
				(font
					(size 1 1)
					(thickness 0.15)
				)
				(justify mirror)
			)
		)
		(property "Dielectric" "X5R"
			(at 99.5 227.5 0)
			(layer "B.Fab")
			(hide yes)
			(effects
				(font
					(size 1 1)
					(thickness 0.15)
				)
				(justify mirror)
			)
		)
		(property "License" "Apache-2.0"
			(at 99.5 227.5 0)
			(layer "B.Fab")
			(hide yes)
			(effects
				(font
					(size 1 1)
					(thickness 0.15)
				)
				(justify mirror)
			)
		)
		(property "MPN" "GRM155R61H104KE14D"
			(at 99.5 227.5 0)
			(layer "B.Fab")
			(hide yes)
			(effects
				(font
					(size 1 1)
					(thickness 0.15)
				)
				(justify mirror)
			)
		)
		(property "Manufacturer" "Murata"
			(at 99.5 227.5 0)
			(layer "B.Fab")
			(hide yes)
			(effects
				(font
					(size 1 1)
					(thickness 0.15)
				)
				(justify mirror)
			)
		)
		(property "Val" "100n"
			(at 99.5 227.5 0)
			(layer "B.Fab")
			(hide yes)
			(effects
				(font
					(size 1 1)
					(thickness 0.15)
				)
				(justify mirror)
			)
		)
		(property "Voltage" "50V"
			(at 99.5 227.5 0)
			(layer "B.Fab")
			(hide yes)
			(effects
				(font
					(size 1 1)
					(thickness 0.15)
				)
				(justify mirror)
			)
		)
		(sheetname "USB Debug, DP")
		(sheetfile "usb.kicad_sch")
		(attr smd)
		(fp_rect
			(start -0.925 0.47)
			(end 0.925 -0.47)
			(stroke
				(width 0.05)
				(type default)
			)
			(fill none)
			(layer "B.CrtYd")
		)
		(fp_line
			(start 0.504 0.25)
			(end -0.494 0.25)
			(stroke
				(width 0.15)
				(type solid)
			)
			(layer "B.Fab")
		)
		(fp_line
			(start 0.504 -0.248)
			(end 0.504 0.25)
			(stroke
				(width 0.15)
				(type solid)
			)
			(layer "B.Fab")
		)
		(fp_line
			(start -0.494 0.25)
			(end -0.494 -0.248)
			(stroke
				(width 0.15)
				(type solid)
			)
			(layer "B.Fab")
		)
		(fp_line
			(start -0.494 -0.248)
			(end 0.504 -0.248)
			(stroke
				(width 0.15)
				(type solid)
			)
			(layer "B.Fab")
		)
		(fp_text user "${REFERENCE}"
			(at -0.932 -3.168 0)
			(layer "B.Fab")
			(hide yes)
			(effects
				(font
					(size 0.7 0.7)
					(thickness 0.15)
				)
				(justify left bottom mirror)
			)
		)
		(fp_text user "Author: Antmicro"
			(at -0.932 -4.17 0)
			(layer "B.Fab")
			(hide yes)
			(effects
				(font
					(size 0.7 0.7)
					(thickness 0.15)
				)
				(justify left bottom mirror)
			)
		)
		(fp_text user "License: Apache-2.0"
			(at -0.932 -5.17 0)
			(layer "B.Fab")
			(hide yes)
			(effects
				(font
					(size 0.7 0.7)
					(thickness 0.15)
				)
				(justify left bottom mirror)
			)
		)
		(pad "1" smd roundrect
			(at -0.48 0 180)
			(size 0.59 0.64)
			(layers "B.Cu" "B.Paste" "B.Mask")
			(roundrect_rratio 0.25)
			(net 185 "/USB Debug, DP/FTDI_3V3")
			(pintype "passive")
		)
		(pad "2" smd roundrect
			(at 0.48 0 180)
			(size 0.59 0.64)
			(layers "B.Cu" "B.Paste" "B.Mask")
			(roundrect_rratio 0.25)
			(net 1 "GND")
			(pintype "passive")
		)
	)
	(footprint "antmicro-footprints:R_0402_1005Metric"
		(layer "B.Cu")
		(at 142 112.4 180)
		(descr "Resistor SMD 0402")
		(tags "resistor SMD 0402")
		(property "Reference" "R197"
			(at -1.25 0.4 0)
			(layer "B.SilkS")
			(effects
				(font
					(size 0.7 0.7)
					(thickness 0.15)
				)
				(justify left bottom mirror)
			)
		)
		(property "Value" "R_470R_0402"
			(at 0 -1.4 0)
			(layer "B.Fab")
			(effects
				(font
					(size 0.7 0.7)
					(thickness 0.15)
				)
				(justify left bottom mirror)
			)
		)
		(property "Footprint" "antmicro-footprints:R_0402_1005Metric"
			(at 0 0 180)
			(layer "F.Fab")
			(hide yes)
			(effects
				(font
					(size 1.27 1.27)
					(thickness 0.15)
				)
			)
		)
		(property "Datasheet" "https://www.bourns.com/docs/product-datasheets/cr.pdf"
			(at 0 0 180)
			(layer "F.Fab")
			(hide yes)
			(effects
				(font
					(size 1.27 1.27)
					(thickness 0.15)
				)
			)
		)
		(property "Author" "Antmicro"
			(at 284 224.8 0)
			(layer "B.Fab")
			(hide yes)
			(effects
				(font
					(size 1 1)
					(thickness 0.15)
				)
				(justify mirror)
			)
		)
		(property "License" "Apache-2.0"
			(at 284 224.8 0)
			(layer "B.Fab")
			(hide yes)
			(effects
				(font
					(size 1 1)
					(thickness 0.15)
				)
				(justify mirror)
			)
		)
		(property "MPN" "CR0402-FX-4700GLF"
			(at 284 224.8 0)
			(layer "B.Fab")
			(hide yes)
			(effects
				(font
					(size 1 1)
					(thickness 0.15)
				)
				(justify mirror)
			)
		)
		(property "Manufacturer" "Bourns"
			(at 284 224.8 0)
			(layer "B.Fab")
			(hide yes)
			(effects
				(font
					(size 1 1)
					(thickness 0.15)
				)
				(justify mirror)
			)
		)
		(property "Tolerance" "1%"
			(at 284 224.8 0)
			(layer "B.Fab")
			(hide yes)
			(effects
				(font
					(size 1 1)
					(thickness 0.15)
				)
				(justify mirror)
			)
		)
		(property "Val" "470R"
			(at 284 224.8 0)
			(layer "B.Fab")
			(hide yes)
			(effects
				(font
					(size 1 1)
					(thickness 0.15)
				)
				(justify mirror)
			)
		)
		(sheetname "CSI")
		(sheetfile "csi.kicad_sch")
		(attr smd)
		(fp_rect
			(start -0.925 0.47)
			(end 0.925 -0.47)
			(stroke
				(width 0.05)
				(type default)
			)
			(fill none)
			(layer "B.CrtYd")
		)
		(fp_rect
			(start -0.5 0.25)
			(end 0.5 -0.25)
			(stroke
				(width 0.15)
				(type solid)
			)
			(fill none)
			(layer "B.Fab")
		)
		(fp_text user "Author: Antmicro"
			(at -0.95 -4.169 0)
			(layer "B.Fab")
			(hide yes)
			(effects
				(font
					(size 0.7 0.7)
					(thickness 0.15)
				)
				(justify left bottom mirror)
			)
		)
		(fp_text user "License: Apache-2.0"
			(at -0.95 -5.169 0)
			(layer "B.Fab")
			(hide yes)
			(effects
				(font
					(size 0.7 0.7)
					(thickness 0.15)
				)
				(justify left bottom mirror)
			)
		)
		(fp_text user "${REFERENCE}"
			(at -0.95 -3.168 0)
			(layer "B.Fab")
			(hide yes)
			(effects
				(font
					(size 0.7 0.7)
					(thickness 0.15)
				)
				(justify left bottom mirror)
			)
		)
		(pad "1" smd roundrect
			(at -0.48 0 180)
			(size 0.59 0.64)
			(layers "B.Cu" "B.Paste" "B.Mask")
			(roundrect_rratio 0.25)
			(net 160 "Net-(D20-A)")
			(pintype "passive")
		)
		(pad "2" smd roundrect
			(at 0.48 0 180)
			(size 0.59 0.64)
			(layers "B.Cu" "B.Paste" "B.Mask")
			(roundrect_rratio 0.25)
			(net 109 "/CSI/CSIA_5V")
			(pintype "passive")
		)
	)
	(footprint "antmicro-footprints:C_0402_1005Metric"
		(layer "B.Cu")
		(at 47.8 112.68 180)
		(descr "Capacitor SMD 0402")
		(tags "capacitor SMD 0402")
		(property "Reference" "C159"
			(at 0.9 -0.22 0)
			(layer "B.SilkS")
			(effects
				(font
					(size 0.7 0.7)
					(thickness 0.15)
				)
				(justify left bottom mirror)
			)
		)
		(property "Value" "C_100n_0402"
			(at -1.022927 -2.155213 0)
			(layer "B.Fab")
			(effects
				(font
					(size 0.7 0.7)
					(thickness 0.15)
				)
				(justify left bottom mirror)
			)
		)
		(property "Footprint" "antmicro-footprints:C_0402_1005Metric"
			(at 0 0 180)
			(layer "F.Fab")
			(hide yes)
			(effects
				(font
					(size 1.27 1.27)
					(thickness 0.15)
				)
			)
		)
		(property "Datasheet" "https://www.murata.com/products/productdetail?partno=GRM155R61H104KE14%23"
			(at 0 0 180)
			(layer "F.Fab")
			(hide yes)
			(effects
				(font
					(size 1.27 1.27)
					(thickness 0.15)
				)
			)
		)
		(property "Author" "Antmicro"
			(at 95.6 225.36 0)
			(layer "B.Fab")
			(hide yes)
			(effects
				(font
					(size 1 1)
					(thickness 0.15)
				)
				(justify mirror)
			)
		)
		(property "Dielectric" "X5R"
			(at 95.6 225.36 0)
			(layer "B.Fab")
			(hide yes)
			(effects
				(font
					(size 1 1)
					(thickness 0.15)
				)
				(justify mirror)
			)
		)
		(property "License" "Apache-2.0"
			(at 95.6 225.36 0)
			(layer "B.Fab")
			(hide yes)
			(effects
				(font
					(size 1 1)
					(thickness 0.15)
				)
				(justify mirror)
			)
		)
		(property "MPN" "GRM155R61H104KE14D"
			(at 95.6 225.36 0)
			(layer "B.Fab")
			(hide yes)
			(effects
				(font
					(size 1 1)
					(thickness 0.15)
				)
				(justify mirror)
			)
		)
		(property "Manufacturer" "Murata"
			(at 95.6 225.36 0)
			(layer "B.Fab")
			(hide yes)
			(effects
				(font
					(size 1 1)
					(thickness 0.15)
				)
				(justify mirror)
			)
		)
		(property "Val" "100n"
			(at 95.6 225.36 0)
			(layer "B.Fab")
			(hide yes)
			(effects
				(font
					(size 1 1)
					(thickness 0.15)
				)
				(justify mirror)
			)
		)
		(property "Voltage" "50V"
			(at 95.6 225.36 0)
			(layer "B.Fab")
			(hide yes)
			(effects
				(font
					(size 1 1)
					(thickness 0.15)
				)
				(justify mirror)
			)
		)
		(sheetname "USB Debug, DP")
		(sheetfile "usb.kicad_sch")
		(attr smd)
		(fp_rect
			(start -0.925 0.47)
			(end 0.925 -0.47)
			(stroke
				(width 0.05)
				(type default)
			)
			(fill none)
			(layer "B.CrtYd")
		)
		(fp_line
			(start 0.504 0.25)
			(end -0.494 0.25)
			(stroke
				(width 0.15)
				(type solid)
			)
			(layer "B.Fab")
		)
		(fp_line
			(start 0.504 -0.248)
			(end 0.504 0.25)
			(stroke
				(width 0.15)
				(type solid)
			)
			(layer "B.Fab")
		)
		(fp_line
			(start -0.494 0.25)
			(end -0.494 -0.248)
			(stroke
				(width 0.15)
				(type solid)
			)
			(layer "B.Fab")
		)
		(fp_line
			(start -0.494 -0.248)
			(end 0.504 -0.248)
			(stroke
				(width 0.15)
				(type solid)
			)
			(layer "B.Fab")
		)
		(fp_text user "Author: Antmicro"
			(at -0.939 -3.399 0)
			(layer "B.Fab")
			(hide yes)
			(effects
				(font
					(size 0.7 0.7)
					(thickness 0.15)
				)
				(justify left bottom mirror)
			)
		)
		(fp_text user "License: Apache-2.0"
			(at -0.939 -5.799 0)
			(layer "B.Fab")
			(hide yes)
			(effects
				(font
					(size 0.7 0.7)
					(thickness 0.15)
				)
				(justify left bottom mirror)
			)
		)
		(fp_text user "${REFERENCE}"
			(at -0.939 -4.599 0)
			(layer "B.Fab")
			(hide yes)
			(effects
				(font
					(size 0.7 0.7)
					(thickness 0.15)
				)
				(justify left bottom mirror)
			)
		)
		(pad "1" smd roundrect
			(at -0.48 0 180)
			(size 0.59 0.64)
			(layers "B.Cu" "B.Paste" "B.Mask")
			(roundrect_rratio 0.25)
			(net 185 "/USB Debug, DP/FTDI_3V3")
			(pintype "passive")
		)
		(pad "2" smd roundrect
			(at 0.48 0 180)
			(size 0.59 0.64)
			(layers "B.Cu" "B.Paste" "B.Mask")
			(roundrect_rratio 0.25)
			(net 1 "GND")
			(pintype "passive")
		)
	)
	(footprint "antmicro-footprints:C_0402_1005Metric"
		(layer "B.Cu")
		(at 35.985 69.5 180)
		(descr "Capacitor SMD 0402")
		(tags "capacitor SMD 0402")
		(property "Reference" "C52"
			(at 0.835 -0.5 0)
			(layer "B.SilkS")
			(effects
				(font
					(size 0.7 0.7)
					(thickness 0.15)
				)
				(justify left bottom mirror)
			)
		)
		(property "Value" "C_100n_0402"
			(at 0 -1.4 0)
			(layer "B.Fab")
			(effects
				(font
					(size 0.7 0.7)
					(thickness 0.15)
				)
				(justify left bottom mirror)
			)
		)
		(property "Footprint" "antmicro-footprints:C_0402_1005Metric"
			(at 0 0 180)
			(layer "F.Fab")
			(hide yes)
			(effects
				(font
					(size 1.27 1.27)
					(thickness 0.15)
				)
			)
		)
		(property "Datasheet" "https://www.murata.com/products/productdetail?partno=GRM155R61H104KE14%23"
			(at 0 0 180)
			(layer "F.Fab")
			(hide yes)
			(effects
				(font
					(size 1.27 1.27)
					(thickness 0.15)
				)
			)
		)
		(property "Author" "Antmicro"
			(at 71.97 139 0)
			(layer "B.Fab")
			(hide yes)
			(effects
				(font
					(size 1 1)
					(thickness 0.15)
				)
				(justify mirror)
			)
		)
		(property "Dielectric" "X5R"
			(at 71.97 139 0)
			(layer "B.Fab")
			(hide yes)
			(effects
				(font
					(size 1 1)
					(thickness 0.15)
				)
				(justify mirror)
			)
		)
		(property "License" "Apache-2.0"
			(at 71.97 139 0)
			(layer "B.Fab")
			(hide yes)
			(effects
				(font
					(size 1 1)
					(thickness 0.15)
				)
				(justify mirror)
			)
		)
		(property "MPN" "GRM155R61H104KE14D"
			(at 71.97 139 0)
			(layer "B.Fab")
			(hide yes)
			(effects
				(font
					(size 1 1)
					(thickness 0.15)
				)
				(justify mirror)
			)
		)
		(property "Manufacturer" "Murata"
			(at 71.97 139 0)
			(layer "B.Fab")
			(hide yes)
			(effects
				(font
					(size 1 1)
					(thickness 0.15)
				)
				(justify mirror)
			)
		)
		(property "Val" "100n"
			(at 71.97 139 0)
			(layer "B.Fab")
			(hide yes)
			(effects
				(font
					(size 1 1)
					(thickness 0.15)
				)
				(justify mirror)
			)
		)
		(property "Voltage" "50V"
			(at 71.97 139 0)
			(layer "B.Fab")
			(hide yes)
			(effects
				(font
					(size 1 1)
					(thickness 0.15)
				)
				(justify mirror)
			)
		)
		(sheetname "Ethernet")
		(sheetfile "ethernet.kicad_sch")
		(attr smd)
		(fp_rect
			(start -0.925 0.47)
			(end 0.925 -0.47)
			(stroke
				(width 0.05)
				(type default)
			)
			(fill none)
			(layer "B.CrtYd")
		)
		(fp_line
			(start 0.504 0.25)
			(end -0.494 0.25)
			(stroke
				(width 0.15)
				(type solid)
			)
			(layer "B.Fab")
		)
		(fp_line
			(start 0.504 -0.248)
			(end 0.504 0.25)
			(stroke
				(width 0.15)
				(type solid)
			)
			(layer "B.Fab")
		)
		(fp_line
			(start -0.494 0.25)
			(end -0.494 -0.248)
			(stroke
				(width 0.15)
				(type solid)
			)
			(layer "B.Fab")
		)
		(fp_line
			(start -0.494 -0.248)
			(end 0.504 -0.248)
			(stroke
				(width 0.15)
				(type solid)
			)
			(layer "B.Fab")
		)
		(fp_text user "${REFERENCE}"
			(at -0.932 -3.168 0)
			(layer "B.Fab")
			(hide yes)
			(effects
				(font
					(size 0.7 0.7)
					(thickness 0.15)
				)
				(justify left bottom mirror)
			)
		)
		(fp_text user "Author: Antmicro"
			(at -0.932 -4.17 0)
			(layer "B.Fab")
			(hide yes)
			(effects
				(font
					(size 0.7 0.7)
					(thickness 0.15)
				)
				(justify left bottom mirror)
			)
		)
		(fp_text user "License: Apache-2.0"
			(at -0.932 -5.17 0)
			(layer "B.Fab")
			(hide yes)
			(effects
				(font
					(size 0.7 0.7)
					(thickness 0.15)
				)
				(justify left bottom mirror)
			)
		)
		(pad "1" smd roundrect
			(at -0.48 0 180)
			(size 0.59 0.64)
			(layers "B.Cu" "B.Paste" "B.Mask")
			(roundrect_rratio 0.25)
			(net 500 "POE_OUTPUT")
			(pintype "passive")
		)
		(pad "2" smd roundrect
			(at 0.48 0 180)
			(size 0.59 0.64)
			(layers "B.Cu" "B.Paste" "B.Mask")
			(roundrect_rratio 0.25)
			(net 1 "GND")
			(pintype "passive")
		)
	)
	(footprint "antmicro-footprints:LED_0603_1608Metric_G"
		(layer "B.Cu")
		(at 77.25 105.45 90)
		(descr "LED SMD 0603 Green")
		(tags "LED SMD 0603 Green")
		(property "Reference" "D5"
			(at 1.2 -0.8 180)
			(layer "B.SilkS")
			(effects
				(font
					(size 0.7 0.7)
					(thickness 0.15)
				)
				(justify right bottom mirror)
			)
		)
		(property "Value" "LED_G_0603_LTST-C190GKT"
			(at -0.001 -1.599 90)
			(layer "B.Fab")
			(effects
				(font
					(size 0.7 0.7)
					(thickness 0.15)
				)
				(justify right bottom mirror)
			)
		)
		(property "Footprint" "antmicro-footprints:LED_0603_1608Metric_G"
			(at 0 0 90)
			(layer "F.Fab")
			(hide yes)
			(effects
				(font
					(size 1.27 1.27)
					(thickness 0.15)
				)
			)
		)
		(property "Datasheet" "https://media.digikey.com/pdf/Data%20Sheets/Lite-On%20PDFs/LTST-C190GKT.pdf"
			(at 0 0 90)
			(layer "F.Fab")
			(hide yes)
			(effects
				(font
					(size 1.27 1.27)
					(thickness 0.15)
				)
			)
		)
		(property "Author" "Antmicro"
			(at 182.7 28.2 0)
			(layer "B.Fab")
			(hide yes)
			(effects
				(font
					(size 1 1)
					(thickness 0.15)
				)
				(justify mirror)
			)
		)
		(property "Color" "Green"
			(at 182.7 28.2 0)
			(layer "B.Fab")
			(hide yes)
			(effects
				(font
					(size 1 1)
					(thickness 0.15)
				)
				(justify mirror)
			)
		)
		(property "License" "Apache-2.0"
			(at 182.7 28.2 0)
			(layer "B.Fab")
			(hide yes)
			(effects
				(font
					(size 1 1)
					(thickness 0.15)
				)
				(justify mirror)
			)
		)
		(property "MPN" "LTST-C190GKT"
			(at 182.7 28.2 0)
			(layer "B.Fab")
			(hide yes)
			(effects
				(font
					(size 1 1)
					(thickness 0.15)
				)
				(justify mirror)
			)
		)
		(property "Manufacturer" "Lite-On"
			(at 182.7 28.2 0)
			(layer "B.Fab")
			(hide yes)
			(effects
				(font
					(size 1 1)
					(thickness 0.15)
				)
				(justify mirror)
			)
		)
		(sheetname "USB Debug, DP")
		(sheetfile "usb.kicad_sch")
		(attr smd)
		(fp_line
			(start -0.22 -0.35)
			(end 0.22 -0.35)
			(stroke
				(width 0.15)
				(type solid)
			)
			(layer "B.SilkS")
		)
		(fp_line
			(start -1.18 -0.321)
			(end -1.18 0.319)
			(stroke
				(width 0.15)
				(type solid)
			)
			(layer "B.SilkS")
		)
		(fp_line
			(start -0.094672 -0.001008)
			(end 0.105328 -0.201008)
			(stroke
				(width 0.1)
				(type solid)
			)
			(layer "B.SilkS")
		)
		(fp_line
			(start -0.24 -0.001008)
			(end -0.094672 -0.001008)
			(stroke
				(width 0.1)
				(type solid)
			)
			(layer "B.SilkS")
		)
		(fp_line
			(start 0.24 -0.001)
			(end 0.105328 -0.001008)
			(stroke
				(width 0.1)
				(type solid)
			)
			(layer "B.SilkS")
		)
		(fp_line
			(start 0.105328 0.198992)
			(end 0.105328 -0.201008)
			(stroke
				(width 0.1)
				(type solid)
			)
			(layer "B.SilkS")
		)
		(fp_line
			(start 0.105328 0.198992)
			(end -0.094672 -0.001008)
			(stroke
				(width 0.1)
				(type solid)
			)
			(layer "B.SilkS")
		)
		(fp_line
			(start -0.094672 0.198992)
			(end -0.094672 -0.201008)
			(stroke
				(width 0.1)
				(type solid)
			)
			(layer "B.SilkS")
		)
		(fp_line
			(start -0.22 0.35)
			(end 0.22 0.35)
			(stroke
				(width 0.15)
				(type solid)
			)
			(layer "B.SilkS")
		)
		(fp_rect
			(start 1.25 -0.65)
			(end -1.25 0.65)
			(stroke
				(width 0.05)
				(type solid)
			)
			(fill none)
			(layer "B.CrtYd")
		)
		(fp_line
			(start 0.201 -0.2)
			(end -0.101 0)
			(stroke
				(width 0.15)
				(type solid)
			)
			(layer "B.Fab")
		)
		(fp_line
			(start -0.199 -0.1)
			(end -0.199 -0.2)
			(stroke
				(width 0.15)
				(type solid)
			)
			(layer "B.Fab")
		)
		(fp_line
			(start -0.199 -0.1)
			(end -0.199 0.202)
			(stroke
				(width 0.15)
				(type solid)
			)
			(layer "B.Fab")
		)
		(fp_line
			(start 0.201 0)
			(end 0.201 -0.2)
			(stroke
				(width 0.15)
				(type solid)
			)
			(layer "B.Fab")
		)
		(fp_line
			(start 0.201 0)
			(end 0.599 0)
			(stroke
				(width 0.15)
				(type solid)
			)
			(layer "B.Fab")
		)
		(fp_line
			(start -0.101 0)
			(end 0.201 0.202)
			(stroke
				(width 0.15)
				(type solid)
			)
			(layer "B.Fab")
		)
		(fp_line
			(start -0.597 0)
			(end -0.199 0)
			(stroke
				(width 0.15)
				(type solid)
			)
			(layer "B.Fab")
		)
		(fp_line
			(start 0.201 0.202)
			(end 0.201 0)
			(stroke
				(width 0.15)
				(type solid)
			)
			(layer "B.Fab")
		)
		(fp_rect
			(start 0.848 -0.4)
			(end -0.85 0.402)
			(stroke
				(width 0.15)
				(type solid)
			)
			(fill none)
			(layer "B.Fab")
		)
		(fp_text user "${REFERENCE}"
			(at -1.4224 -5.999 90)
			(layer "B.Fab")
			(hide yes)
			(effects
				(font
					(size 0.7 0.7)
					(thickness 0.15)
				)
				(justify right bottom mirror)
			)
		)
		(fp_text user "Author: Antmicro"
			(at -1.4224 -4.799 90)
			(layer "B.Fab")
			(hide yes)
			(effects
				(font
					(size 0.7 0.7)
					(thickness 0.15)
				)
				(justify right bottom mirror)
			)
		)
		(fp_text user "License: Apache-2.0"
			(at -1.4224 -3.599 90)
			(layer "B.Fab")
			(hide yes)
			(effects
				(font
					(size 0.7 0.7)
					(thickness 0.15)
				)
				(justify right bottom mirror)
			)
		)
		(pad "1" smd roundrect
			(at -0.7 0 270)
			(size 0.8 1)
			(layers "B.Cu" "B.Paste" "B.Mask")
			(roundrect_rratio 0.2)
			(net 1 "GND")
			(pinfunction "C")
			(pintype "passive")
		)
		(pad "2" smd roundrect
			(at 0.7 0 270)
			(size 0.8 1)
			(layers "B.Cu" "B.Paste" "B.Mask")
			(roundrect_rratio 0.2)
			(net 145 "Net-(D5-A)")
			(pinfunction "A")
			(pintype "passive")
		)
	)
	(footprint "antmicro-footprints:VQFN-HR-10_2x2mm"
		(layer "B.Cu")
		(at 52.875 81.075 -90)
		(property "Reference" "U48"
			(at -1.525 0.175 180)
			(layer "B.SilkS")
			(effects
				(font
					(size 0.7 0.7)
					(thickness 0.15)
				)
				(justify left bottom mirror)
			)
		)
		(property "Value" "TPS259474"
			(at 0 -2.8 90)
			(layer "B.Fab")
			(effects
				(font
					(size 0.7 0.7)
					(thickness 0.15)
				)
				(justify left bottom mirror)
			)
		)
		(property "Footprint" "antmicro-footprints:VQFN-HR-10_2x2mm"
			(at 0 0.045 90)
			(layer "B.Fab")
			(hide yes)
			(effects
				(font
					(size 1.27 1.27)
					(thickness 0.15)
				)
				(justify mirror)
			)
		)
		(property "Datasheet" "https://www.ti.com/lit/ds/symlink/tps25947.pdf"
			(at 0 0.045 90)
			(layer "B.Fab")
			(hide yes)
			(effects
				(font
					(size 1.27 1.27)
					(thickness 0.15)
				)
				(justify mirror)
			)
		)
		(property "Description" "Reverse Current Blocking eFuse with Input Reverse Polarity Protection, 5.5A, 23V, -40 to 125 Deg C, VQFN-HR-10"
			(at -0.05 -3.75 90)
			(layer "B.Fab")
			(hide yes)
			(effects
				(font
					(size 0.7 0.7)
					(thickness 0.15)
				)
				(justify mirror)
			)
		)
		(property "MPN" "TPS259474ARPWR"
			(at 0 0 90)
			(unlocked yes)
			(layer "B.Fab")
			(hide yes)
			(effects
				(font
					(size 1 1)
					(thickness 0.15)
				)
				(justify mirror)
			)
		)
		(property "Manufacturer" "Texas Instruments"
			(at 0 0 90)
			(unlocked yes)
			(layer "B.Fab")
			(hide yes)
			(effects
				(font
					(size 1 1)
					(thickness 0.15)
				)
				(justify mirror)
			)
		)
		(property "Author" "Antmicro"
			(at 0 0 90)
			(unlocked yes)
			(layer "B.Fab")
			(hide yes)
			(effects
				(font
					(size 1 1)
					(thickness 0.15)
				)
				(justify mirror)
			)
		)
		(property "License" "Apache-2.0"
			(at 0 0 90)
			(unlocked yes)
			(layer "B.Fab")
			(hide yes)
			(effects
				(font
					(size 1 1)
					(thickness 0.15)
				)
				(justify mirror)
			)
		)
		(sheetname "Supply")
		(sheetfile "supply.kicad_sch")
		(attr smd)
		(fp_circle
			(center -1.2 1.195)
			(end -1.15 1.195)
			(stroke
				(width 0.15)
				(type solid)
			)
			(fill solid)
			(layer "B.SilkS")
		)
		(fp_rect
			(start -1.45 1.45)
			(end 1.45 -1.45)
			(stroke
				(width 0.05)
				(type default)
			)
			(fill none)
			(layer "B.CrtYd")
		)
		(fp_line
			(start 1 1)
			(end -0.5 1)
			(stroke
				(width 0.1)
				(type default)
			)
			(layer "B.Fab")
		)
		(fp_line
			(start -1 0.5)
			(end -0.5 1)
			(stroke
				(width 0.1)
				(type default)
			)
			(layer "B.Fab")
		)
		(fp_line
			(start -1 0.5)
			(end -1 -1)
			(stroke
				(width 0.1)
				(type default)
			)
			(layer "B.Fab")
		)
		(fp_line
			(start -1 -1)
			(end 1 -1)
			(stroke
				(width 0.1)
				(type default)
			)
			(layer "B.Fab")
		)
		(fp_line
			(start 1 -1)
			(end 1 1)
			(stroke
				(width 0.1)
				(type default)
			)
			(layer "B.Fab")
		)
		(fp_text user "${REFERENCE}"
			(at -2.851 -5.45 90)
			(layer "B.Fab")
			(hide yes)
			(effects
				(font
					(size 0.7 0.7)
					(thickness 0.15)
				)
				(justify left bottom mirror)
			)
		)
		(fp_text user "Author: Antmicro"
			(at -2.851 -6.65 90)
			(layer "B.Fab")
			(hide yes)
			(effects
				(font
					(size 0.7 0.7)
					(thickness 0.15)
				)
				(justify left bottom mirror)
			)
		)
		(fp_text user "License: Apache-2.0"
			(at -2.851 -7.85 90)
			(layer "B.Fab")
			(hide yes)
			(effects
				(font
					(size 0.7 0.7)
					(thickness 0.15)
				)
				(justify left bottom mirror)
			)
		)
		(pad "" smd roundrect
			(at -0.9 -0.6875 270)
			(size 0.6 0.275)
			(layers "B.Paste")
			(roundrect_rratio 0.1818181818)
			(thermal_bridge_angle 45)
		)
		(pad "" smd roundrect
			(at -0.9 0.6875 270)
			(size 0.6 0.275)
			(layers "B.Paste")
			(roundrect_rratio 0.1818181818)
			(thermal_bridge_angle 45)
		)
		(pad "" smd roundrect
			(at -0.7125 -0.875 270)
			(size 0.225 0.65)
			(layers "B.Paste")
			(roundrect_rratio 0.2222222222)
			(thermal_bridge_angle 45)
		)
		(pad "" smd roundrect
			(at -0.7125 0.875 270)
			(size 0.225 0.65)
			(layers "B.Paste")
			(roundrect_rratio 0.2222222222)
			(thermal_bridge_angle 45)
		)
		(pad "" smd roundrect
			(at -0.25 -0.63 270)
			(size 0.28 1.06)
			(layers "B.Paste")
			(roundrect_rratio 0.1785714286)
			(thermal_bridge_angle 45)
		)
		(pad "" smd roundrect
			(at -0.25 0.63 270)
			(size 0.28 1.06)
			(layers "B.Paste")
			(roundrect_rratio 0.1785714286)
			(thermal_bridge_angle 45)
		)
		(pad "" smd roundrect
			(at 0.25 -0.63 270)
			(size 0.28 1.06)
			(layers "B.Paste")
			(roundrect_rratio 0.1785714286)
			(thermal_bridge_angle 45)
		)
		(pad "" smd roundrect
			(at 0.25 0.63 270)
			(size 0.28 1.06)
			(layers "B.Paste")
			(roundrect_rratio 0.1785714286)
			(thermal_bridge_angle 45)
		)
		(pad "" smd roundrect
			(at 0.7125 -0.875 270)
			(size 0.225 0.65)
			(layers "B.Paste")
			(roundrect_rratio 0.2222222222)
			(thermal_bridge_angle 45)
		)
		(pad "" smd roundrect
			(at 0.7125 0.875 270)
			(size 0.225 0.65)
			(layers "B.Paste")
			(roundrect_rratio 0.2222222222)
			(thermal_bridge_angle 45)
		)
		(pad "" smd roundrect
			(at 0.9 -0.6875 270)
			(size 0.6 0.275)
			(layers "B.Paste")
			(roundrect_rratio 0.1818181818)
			(thermal_bridge_angle 45)
		)
		(pad "" smd roundrect
			(at 0.9 0.6875 270)
			(size 0.6 0.275)
			(layers "B.Paste")
			(roundrect_rratio 0.1818181818)
			(thermal_bridge_angle 45)
		)
		(pad "1" smd roundrect
			(at -0.9 0.7 270)
			(size 0.6 0.3)
			(layers "B.Cu" "B.Mask")
			(roundrect_rratio 0.1666666667)
			(net 789 "MODULE_ID")
			(pinfunction "EN/UVLO")
			(pintype "input")
			(thermal_bridge_angle 45)
		)
		(pad "1" smd roundrect
			(at -0.725 0.875 90)
			(size 0.25 0.65)
			(layers "B.Cu" "B.Mask")
			(roundrect_rratio 0.2)
			(net 789 "MODULE_ID")
			(pinfunction "EN/UVLO")
			(pintype "input")
			(thermal_bridge_angle 45)
		)
		(pad "2" smd roundrect
			(at -0.9 0.225 270)
			(size 0.6 0.25)
			(layers "B.Cu" "B.Paste" "B.Mask")
			(roundrect_rratio 0.2)
			(net 1 "GND")
			(pinfunction "OVLO")
			(pintype "input")
			(thermal_bridge_angle 45)
		)
		(pad "3" smd roundrect
			(at -0.9 -0.225 270)
			(size 0.6 0.25)
			(layers "B.Cu" "B.Paste" "B.Mask")
			(roundrect_rratio 0.2)
			(net 799 "/Supply/PG_{HP}")
			(pinfunction "PG")
			(pintype "output")
			(thermal_bridge_angle 45)
		)
		(pad "4" smd roundrect
			(at -0.9 -0.7 270)
			(size 0.6 0.3)
			(layers "B.Cu" "B.Mask")
			(roundrect_rratio 0.1666666667)
			(net 789 "MODULE_ID")
			(pinfunction "PGTH")
			(pintype "input")
			(thermal_bridge_angle 45)
		)
		(pad "4" smd roundrect
			(at -0.725 -0.875 90)
			(size 0.25 0.65)
			(layers "B.Cu" "B.Mask")
			(roundrect_rratio 0.2)
			(net 789 "MODULE_ID")
			(pinfunction "PGTH")
			(pintype "input")
			(thermal_bridge_angle 45)
		)
		(pad "5" smd roundrect
			(at -0.25 0 270)
			(size 0.3 2.4)
			(layers "B.Cu" "B.Mask")
			(roundrect_rratio 0.25)
			(net 115 "VCC")
			(pinfunction "IN")
			(pintype "power_in")
			(thermal_bridge_angle 45)
		)
		(pad "6" smd roundrect
			(at 0.25 0 270)
			(size 0.3 2.4)
			(layers "B.Cu" "B.Mask")
			(roundrect_rratio 0.25)
			(net 788 "VDD_SoM")
			(pinfunction "OUT")
			(pintype "power_out")
			(thermal_bridge_angle 45)
		)
		(pad "7" smd roundrect
			(at 0.725 -0.875 90)
			(size 0.25 0.65)
			(layers "B.Cu" "B.Mask")
			(roundrect_rratio 0.2)
			(net 644 "Net-(U48-DVDT)")
			(pinfunction "DVDT")
			(pintype "output")
			(thermal_bridge_angle 45)
		)
		(pad "7" smd roundrect
			(at 0.9 -0.7 90)
			(size 0.6 0.3)
			(layers "B.Cu" "B.Mask")
			(roundrect_rratio 0.1666666667)
			(net 644 "Net-(U48-DVDT)")
			(pinfunction "DVDT")
			(pintype "output")
			(thermal_bridge_angle 45)
		)
		(pad "8" smd roundrect
			(at 0.9 -0.225 90)
			(size 0.6 0.25)
			(layers "B.Cu" "B.Paste" "B.Mask")
			(roundrect_rratio 0.2)
			(net 1 "GND")
			(pinfunction "GND")
			(pintype "power_in")
			(thermal_bridge_angle 45)
		)
		(pad "9" smd roundrect
			(at 0.9 0.225 90)
			(size 0.6 0.25)
			(layers "B.Cu" "B.Paste" "B.Mask")
			(roundrect_rratio 0.2)
			(net 791 "Net-(U48-ILIM)")
			(pinfunction "ILIM")
			(pintype "output")
			(thermal_bridge_angle 45)
		)
		(pad "10" smd roundrect
			(at 0.725 0.875 90)
			(size 0.25 0.65)
			(layers "B.Cu" "B.Mask")
			(roundrect_rratio 0.2)
			(net 797 "unconnected-(U48-ITIMER-Pad10)_1")
			(pinfunction "ITIMER")
			(pintype "output+no_connect")
			(thermal_bridge_angle 45)
		)
		(pad "10" smd roundrect
			(at 0.9 0.7 90)
			(size 0.6 0.3)
			(layers "B.Cu" "B.Mask")
			(roundrect_rratio 0.1666666667)
			(net 796 "unconnected-(U48-ITIMER-Pad10)")
			(pinfunction "ITIMER")
			(pintype "output+no_connect")
			(thermal_bridge_angle 45)
		)
	)
	(footprint "antmicro-footprints:TP_SMD_0.75mm"
		(layer "B.Cu")
		(at 111.9 104.1)
		(property "Reference" "TP32"
			(at 3.01 0.39 180)
			(layer "B.SilkS")
			(effects
				(font
					(size 0.7 0.7)
					(thickness 0.15)
				)
				(justify left bottom mirror)
			)
		)
		(property "Value" "TP_0.75mm_SMD"
			(at 0 -1.2 180)
			(layer "B.Fab")
			(effects
				(font
					(size 0.7 0.7)
					(thickness 0.15)
				)
				(justify left bottom mirror)
			)
		)
		(property "Footprint" "antmicro-footprints:TP_SMD_0.75mm"
			(at 0 0 0)
			(layer "F.Fab")
			(hide yes)
			(effects
				(font
					(size 1.27 1.27)
					(thickness 0.15)
				)
			)
		)
		(property "Author" "Antmicro"
			(at 0 0 0)
			(layer "B.Fab")
			(hide yes)
			(effects
				(font
					(size 1 1)
					(thickness 0.15)
				)
				(justify mirror)
			)
		)
		(property "License" "Apache-2.0"
			(at 0 0 0)
			(layer "B.Fab")
			(hide yes)
			(effects
				(font
					(size 1 1)
					(thickness 0.15)
				)
				(justify mirror)
			)
		)
		(property "MPN" ""
			(at 0 0 0)
			(layer "B.Fab")
			(hide yes)
			(effects
				(font
					(size 1 1)
					(thickness 0.15)
				)
				(justify mirror)
			)
		)
		(property "Manufacturer" ""
			(at 0 0 0)
			(layer "B.Fab")
			(hide yes)
			(effects
				(font
					(size 1 1)
					(thickness 0.15)
				)
				(justify mirror)
			)
		)
		(sheetname "USB3")
		(sheetfile "usb3.kicad_sch")
		(attr exclude_from_pos_files exclude_from_bom)
		(fp_circle
			(center 0 0)
			(end 0.475 0)
			(stroke
				(width 0.05)
				(type default)
			)
			(fill none)
			(layer "B.CrtYd")
		)
		(fp_text user "${REFERENCE}"
			(at -0.4 -2.7 180)
			(layer "B.Fab")
			(hide yes)
			(effects
				(font
					(size 0.7 0.7)
					(thickness 0.15)
				)
				(justify left bottom mirror)
			)
		)
		(fp_text user "License: Apache-2.0"
			(at -0.4 -5.101 180)
			(layer "B.Fab")
			(hide yes)
			(effects
				(font
					(size 0.7 0.7)
					(thickness 0.15)
				)
				(justify left bottom mirror)
			)
		)
		(fp_text user "Author: Antmicro"
			(at -0.4 -3.901 180)
			(layer "B.Fab")
			(hide yes)
			(effects
				(font
					(size 0.7 0.7)
					(thickness 0.15)
				)
				(justify left bottom mirror)
			)
		)
		(pad "1" smd circle
			(at 0 0)
			(size 0.75 0.75)
			(layers "B.Cu" "B.Mask")
			(net 391 "/USB3/USBC1_FAULT_N")
			(pinfunction "1")
			(pintype "passive")
		)
	)
	(footprint "antmicro-footprints:SOD-923"
		(layer "B.Cu")
		(at 63.58 84.14 180)
		(property "Reference" "D31"
			(at -2.87 -0.4 0)
			(unlocked yes)
			(layer "B.SilkS")
			(effects
				(font
					(size 0.7 0.7)
					(thickness 0.15)
				)
				(justify left bottom mirror)
			)
		)
		(property "Value" "ESD9X5.0ST5G"
			(at 0 -1.3 0)
			(unlocked yes)
			(layer "B.Fab")
			(effects
				(font
					(size 0.7 0.7)
					(thickness 0.15)
				)
				(justify left bottom mirror)
			)
		)
		(property "Footprint" "antmicro-footprints:SOD-923"
			(at 0 0 180)
			(layer "F.Fab")
			(hide yes)
			(effects
				(font
					(size 1.27 1.27)
					(thickness 0.15)
				)
			)
		)
		(property "Datasheet" "https://www.onsemi.com/pdf/datasheet/esd9x3.3st5g-d.pdf"
			(at 0 0 180)
			(layer "F.Fab")
			(hide yes)
			(effects
				(font
					(size 1.27 1.27)
					(thickness 0.15)
				)
			)
		)
		(property "Author" "Antmicro"
			(at 127.16 168.28 0)
			(layer "B.Fab")
			(hide yes)
			(effects
				(font
					(size 1 1)
					(thickness 0.15)
				)
				(justify mirror)
			)
		)
		(property "License" "Apache-2.0"
			(at 127.16 168.28 0)
			(layer "B.Fab")
			(hide yes)
			(effects
				(font
					(size 1 1)
					(thickness 0.15)
				)
				(justify mirror)
			)
		)
		(property "MPN" "ESD9X5.0ST5G"
			(at 127.16 168.28 0)
			(layer "B.Fab")
			(hide yes)
			(effects
				(font
					(size 1 1)
					(thickness 0.15)
				)
				(justify mirror)
			)
		)
		(property "Manufacturer" "ON Semiconductor"
			(at 127.16 168.28 0)
			(layer "B.Fab")
			(hide yes)
			(effects
				(font
					(size 1 1)
					(thickness 0.15)
				)
				(justify mirror)
			)
		)
		(sheetname "Supply")
		(sheetfile "supply.kicad_sch")
		(attr smd)
		(fp_line
			(start 0.5 0.4)
			(end -0.5 0.4)
			(stroke
				(width 0.15)
				(type solid)
			)
			(layer "B.SilkS")
		)
		(fp_line
			(start 0.5 0.3)
			(end 0.5 0.4)
			(stroke
				(width 0.15)
				(type solid)
			)
			(layer "B.SilkS")
		)
		(fp_line
			(start 0.5 -0.3)
			(end 0.5 -0.4)
			(stroke
				(width 0.15)
				(type solid)
			)
			(layer "B.SilkS")
		)
		(fp_line
			(start 0.5 -0.4)
			(end -0.5 -0.4)
			(stroke
				(width 0.15)
				(type solid)
			)
			(layer "B.SilkS")
		)
		(fp_line
			(start -0.16 -0.4)
			(end -0.16 0.4)
			(stroke
				(width 0.15)
				(type solid)
			)
			(layer "B.SilkS")
		)
		(fp_line
			(start -0.5 0.4)
			(end -0.5 0.3)
			(stroke
				(width 0.15)
				(type solid)
			)
			(layer "B.SilkS")
		)
		(fp_line
			(start -0.5 -0.3)
			(end -0.5 -0.4)
			(stroke
				(width 0.15)
				(type solid)
			)
			(layer "B.SilkS")
		)
		(fp_rect
			(start -0.68 0.41)
			(end 0.68 -0.41)
			(stroke
				(width 0.05)
				(type solid)
			)
			(fill none)
			(layer "B.CrtYd")
		)
		(fp_line
			(start -0.202 -0.298)
			(end -0.202 0.3)
			(stroke
				(width 0.15)
				(type solid)
			)
			(layer "B.Fab")
		)
		(fp_rect
			(start -0.402 0.3)
			(end 0.4 -0.298)
			(stroke
				(width 0.15)
				(type solid)
			)
			(fill none)
			(layer "B.Fab")
		)
		(fp_text user "License: Apache-2.0"
			(at -0.68 -4.5 0)
			(layer "B.Fab")
			(hide yes)
			(effects
				(font
					(size 0.7 0.7)
					(thickness 0.15)
				)
				(justify left bottom mirror)
			)
		)
		(fp_text user "Author: Antmicro"
			(at -0.68 -5.7 0)
			(layer "B.Fab")
			(hide yes)
			(effects
				(font
					(size 0.7 0.7)
					(thickness 0.15)
				)
				(justify left bottom mirror)
			)
		)
		(fp_text user "${REFERENCE}"
			(at -0.68 -3.3 0)
			(unlocked yes)
			(layer "B.Fab")
			(hide yes)
			(effects
				(font
					(size 0.7 0.7)
					(thickness 0.15)
				)
				(justify left bottom mirror)
			)
		)
		(pad "1" smd roundrect
			(at -0.438 0 180)
			(size 0.4 0.325)
			(layers "B.Cu" "B.Paste" "B.Mask")
			(roundrect_rratio 0.25)
			(net 112 "+1V8")
			(pinfunction "C")
			(pintype "passive")
		)
		(pad "2" smd roundrect
			(at 0.436 0 180)
			(size 0.4 0.325)
			(layers "B.Cu" "B.Paste" "B.Mask")
			(roundrect_rratio 0.25)
			(net 1 "GND")
			(pinfunction "A")
			(pintype "passive")
		)
	)
	(footprint "antmicro-footprints:C_0402_1005Metric"
		(layer "B.Cu")
		(at 66.46 81.31 180)
		(descr "Capacitor SMD 0402")
		(tags "capacitor SMD 0402")
		(property "Reference" "C40"
			(at -1.09 -1.34 0)
			(layer "B.SilkS")
			(effects
				(font
					(size 0.7 0.7)
					(thickness 0.15)
				)
				(justify left bottom mirror)
			)
		)
		(property "Value" "C_100n_0402"
			(at 0 -1.4 0)
			(layer "B.Fab")
			(effects
				(font
					(size 0.7 0.7)
					(thickness 0.15)
				)
				(justify left bottom mirror)
			)
		)
		(property "Footprint" "antmicro-footprints:C_0402_1005Metric"
			(at 0 0 180)
			(layer "F.Fab")
			(hide yes)
			(effects
				(font
					(size 1.27 1.27)
					(thickness 0.15)
				)
			)
		)
		(property "Datasheet" "https://www.murata.com/products/productdetail?partno=GRM155R61H104KE14%23"
			(at 0 0 180)
			(layer "F.Fab")
			(hide yes)
			(effects
				(font
					(size 1.27 1.27)
					(thickness 0.15)
				)
			)
		)
		(property "Author" "Antmicro"
			(at 132.92 162.62 0)
			(layer "B.Fab")
			(hide yes)
			(effects
				(font
					(size 1 1)
					(thickness 0.15)
				)
				(justify mirror)
			)
		)
		(property "Dielectric" "X5R"
			(at 132.92 162.62 0)
			(layer "B.Fab")
			(hide yes)
			(effects
				(font
					(size 1 1)
					(thickness 0.15)
				)
				(justify mirror)
			)
		)
		(property "License" "Apache-2.0"
			(at 132.92 162.62 0)
			(layer "B.Fab")
			(hide yes)
			(effects
				(font
					(size 1 1)
					(thickness 0.15)
				)
				(justify mirror)
			)
		)
		(property "MPN" "GRM155R61H104KE14D"
			(at 132.92 162.62 0)
			(layer "B.Fab")
			(hide yes)
			(effects
				(font
					(size 1 1)
					(thickness 0.15)
				)
				(justify mirror)
			)
		)
		(property "Manufacturer" "Murata"
			(at 132.92 162.62 0)
			(layer "B.Fab")
			(hide yes)
			(effects
				(font
					(size 1 1)
					(thickness 0.15)
				)
				(justify mirror)
			)
		)
		(property "Val" "100n"
			(at 132.92 162.62 0)
			(layer "B.Fab")
			(hide yes)
			(effects
				(font
					(size 1 1)
					(thickness 0.15)
				)
				(justify mirror)
			)
		)
		(property "Voltage" "50V"
			(at 132.92 162.62 0)
			(layer "B.Fab")
			(hide yes)
			(effects
				(font
					(size 1 1)
					(thickness 0.15)
				)
				(justify mirror)
			)
		)
		(sheetname "SoM")
		(sheetfile "som.kicad_sch")
		(attr smd)
		(fp_rect
			(start -0.925 0.47)
			(end 0.925 -0.47)
			(stroke
				(width 0.05)
				(type default)
			)
			(fill none)
			(layer "B.CrtYd")
		)
		(fp_line
			(start 0.504 0.25)
			(end -0.494 0.25)
			(stroke
				(width 0.15)
				(type solid)
			)
			(layer "B.Fab")
		)
		(fp_line
			(start 0.504 -0.248)
			(end 0.504 0.25)
			(stroke
				(width 0.15)
				(type solid)
			)
			(layer "B.Fab")
		)
		(fp_line
			(start -0.494 0.25)
			(end -0.494 -0.248)
			(stroke
				(width 0.15)
				(type solid)
			)
			(layer "B.Fab")
		)
		(fp_line
			(start -0.494 -0.248)
			(end 0.504 -0.248)
			(stroke
				(width 0.15)
				(type solid)
			)
			(layer "B.Fab")
		)
		(fp_text user "License: Apache-2.0"
			(at -0.932 -5.17 0)
			(layer "B.Fab")
			(hide yes)
			(effects
				(font
					(size 0.7 0.7)
					(thickness 0.15)
				)
				(justify left bottom mirror)
			)
		)
		(fp_text user "Author: Antmicro"
			(at -0.932 -4.17 0)
			(layer "B.Fab")
			(hide yes)
			(effects
				(font
					(size 0.7 0.7)
					(thickness 0.15)
				)
				(justify left bottom mirror)
			)
		)
		(fp_text user "${REFERENCE}"
			(at -0.932 -3.168 0)
			(layer "B.Fab")
			(hide yes)
			(effects
				(font
					(size 0.7 0.7)
					(thickness 0.15)
				)
				(justify left bottom mirror)
			)
		)
		(pad "1" smd roundrect
			(at -0.48 0 180)
			(size 0.59 0.64)
			(layers "B.Cu" "B.Paste" "B.Mask")
			(roundrect_rratio 0.25)
			(net 1 "GND")
			(pintype "passive")
		)
		(pad "2" smd roundrect
			(at 0.48 0 180)
			(size 0.59 0.64)
			(layers "B.Cu" "B.Paste" "B.Mask")
			(roundrect_rratio 0.25)
			(net 112 "+1V8")
			(pintype "passive")
		)
	)
	(footprint "antmicro-footprints:R_0402_1005Metric"
		(layer "B.Cu")
		(at 76 103.4 90)
		(descr "Resistor SMD 0402")
		(tags "resistor SMD 0402")
		(property "Reference" "R87"
			(at 5.16 1.67 -90)
			(layer "B.SilkS")
			(effects
				(font
					(size 0.7 0.7)
					(thickness 0.15)
				)
				(justify left bottom mirror)
			)
		)
		(property "Value" "R_1k_0402"
			(at 0 -1.4 -90)
			(layer "B.Fab")
			(effects
				(font
					(size 0.7 0.7)
					(thickness 0.15)
				)
				(justify left bottom mirror)
			)
		)
		(property "Footprint" "antmicro-footprints:R_0402_1005Metric"
			(at 0 0 90)
			(layer "F.Fab")
			(hide yes)
			(effects
				(font
					(size 1.27 1.27)
					(thickness 0.15)
				)
			)
		)
		(property "Datasheet" "https://www.bourns.com/docs/product-datasheets/cr.pdf"
			(at 0 0 90)
			(layer "F.Fab")
			(hide yes)
			(effects
				(font
					(size 1.27 1.27)
					(thickness 0.15)
				)
			)
		)
		(property "Author" "Antmicro"
			(at 179.4 27.4 0)
			(layer "B.Fab")
			(hide yes)
			(effects
				(font
					(size 1 1)
					(thickness 0.15)
				)
				(justify mirror)
			)
		)
		(property "License" "Apache-2.0"
			(at 179.4 27.4 0)
			(layer "B.Fab")
			(hide yes)
			(effects
				(font
					(size 1 1)
					(thickness 0.15)
				)
				(justify mirror)
			)
		)
		(property "MPN" "CR0402-FX-1001GLF"
			(at 179.4 27.4 0)
			(layer "B.Fab")
			(hide yes)
			(effects
				(font
					(size 1 1)
					(thickness 0.15)
				)
				(justify mirror)
			)
		)
		(property "Manufacturer" "Bourns"
			(at 179.4 27.4 0)
			(layer "B.Fab")
			(hide yes)
			(effects
				(font
					(size 1 1)
					(thickness 0.15)
				)
				(justify mirror)
			)
		)
		(property "Tolerance" "1%"
			(at 179.4 27.4 0)
			(layer "B.Fab")
			(hide yes)
			(effects
				(font
					(size 1 1)
					(thickness 0.15)
				)
				(justify mirror)
			)
		)
		(property "Val" "1k"
			(at 179.4 27.4 0)
			(layer "B.Fab")
			(hide yes)
			(effects
				(font
					(size 1 1)
					(thickness 0.15)
				)
				(justify mirror)
			)
		)
		(sheetname "USB Debug, DP")
		(sheetfile "usb.kicad_sch")
		(attr smd exclude_from_pos_files exclude_from_bom dnp)
		(fp_rect
			(start -0.925 0.47)
			(end 0.925 -0.47)
			(stroke
				(width 0.05)
				(type default)
			)
			(fill none)
			(layer "B.CrtYd")
		)
		(fp_rect
			(start -0.5 0.25)
			(end 0.5 -0.25)
			(stroke
				(width 0.15)
				(type solid)
			)
			(fill none)
			(layer "B.Fab")
		)
		(fp_text user "${REFERENCE}"
			(at -0.95 -3.168 -90)
			(layer "B.Fab")
			(hide yes)
			(effects
				(font
					(size 0.7 0.7)
					(thickness 0.15)
				)
				(justify left bottom mirror)
			)
		)
		(fp_text user "Author: Antmicro"
			(at -0.95 -4.169 -90)
			(layer "B.Fab")
			(hide yes)
			(effects
				(font
					(size 0.7 0.7)
					(thickness 0.15)
				)
				(justify left bottom mirror)
			)
		)
		(fp_text user "License: Apache-2.0"
			(at -0.95 -5.169 -90)
			(layer "B.Fab")
			(hide yes)
			(effects
				(font
					(size 0.7 0.7)
					(thickness 0.15)
				)
				(justify left bottom mirror)
			)
		)
		(pad "1" smd roundrect
			(at -0.48 0 90)
			(size 0.59 0.64)
			(layers "B.Cu" "B.Paste" "B.Mask")
			(roundrect_rratio 0.25)
			(net 305 "/USB Debug, DP/USBC0_SSEQ0")
			(pintype "passive")
		)
		(pad "2" smd roundrect
			(at 0.48 0 90)
			(size 0.59 0.64)
			(layers "B.Cu" "B.Paste" "B.Mask")
			(roundrect_rratio 0.25)
			(net 87 "+3V3")
			(pintype "passive")
		)
	)
	(footprint "antmicro-footprints:C_0402_1005Metric"
		(layer "B.Cu")
		(at 73.5 108.2)
		(descr "Capacitor SMD 0402")
		(tags "capacitor SMD 0402")
		(property "Reference" "C148"
			(at -0.17 2.25 180)
			(layer "B.SilkS")
			(effects
				(font
					(size 0.7 0.7)
					(thickness 0.15)
				)
				(justify left bottom mirror)
			)
		)
		(property "Value" "C_4u7_25V_0402"
			(at 0 -1.4 180)
			(layer "B.Fab")
			(effects
				(font
					(size 0.7 0.7)
					(thickness 0.15)
				)
				(justify left bottom mirror)
			)
		)
		(property "Footprint" "antmicro-footprints:C_0402_1005Metric"
			(at 0 0 0)
			(layer "F.Fab")
			(hide yes)
			(effects
				(font
					(size 1.27 1.27)
					(thickness 0.15)
				)
			)
		)
		(property "Datasheet" "https://www.murata.com/products/productdetail?partno=GRM155C61E475ME15%23"
			(at 0 0 0)
			(layer "F.Fab")
			(hide yes)
			(effects
				(font
					(size 1.27 1.27)
					(thickness 0.15)
				)
			)
		)
		(property "Author" "Antmicro"
			(at 0 0 0)
			(layer "B.Fab")
			(hide yes)
			(effects
				(font
					(size 1 1)
					(thickness 0.15)
				)
				(justify mirror)
			)
		)
		(property "Dielectric" "X5S"
			(at 0 0 0)
			(layer "B.Fab")
			(hide yes)
			(effects
				(font
					(size 1 1)
					(thickness 0.15)
				)
				(justify mirror)
			)
		)
		(property "License" "Apache-2.0"
			(at 0 0 0)
			(layer "B.Fab")
			(hide yes)
			(effects
				(font
					(size 1 1)
					(thickness 0.15)
				)
				(justify mirror)
			)
		)
		(property "MPN" "GRM155C61E475ME15J"
			(at 0 0 0)
			(layer "B.Fab")
			(hide yes)
			(effects
				(font
					(size 1 1)
					(thickness 0.15)
				)
				(justify mirror)
			)
		)
		(property "Manufacturer" "Murata"
			(at 0 0 0)
			(layer "B.Fab")
			(hide yes)
			(effects
				(font
					(size 1 1)
					(thickness 0.15)
				)
				(justify mirror)
			)
		)
		(property "Val" "4u7"
			(at 0 0 0)
			(layer "B.Fab")
			(hide yes)
			(effects
				(font
					(size 1 1)
					(thickness 0.15)
				)
				(justify mirror)
			)
		)
		(property "Voltage" "25V"
			(at 0 0 0)
			(layer "B.Fab")
			(hide yes)
			(effects
				(font
					(size 1 1)
					(thickness 0.15)
				)
				(justify mirror)
			)
		)
		(sheetname "USB Debug, DP")
		(sheetfile "usb.kicad_sch")
		(attr smd)
		(fp_rect
			(start -0.925 0.47)
			(end 0.925 -0.47)
			(stroke
				(width 0.05)
				(type default)
			)
			(fill none)
			(layer "B.CrtYd")
		)
		(fp_line
			(start -0.494 -0.248)
			(end 0.504 -0.248)
			(stroke
				(width 0.15)
				(type solid)
			)
			(layer "B.Fab")
		)
		(fp_line
			(start -0.494 0.25)
			(end -0.494 -0.248)
			(stroke
				(width 0.15)
				(type solid)
			)
			(layer "B.Fab")
		)
		(fp_line
			(start 0.504 -0.248)
			(end 0.504 0.25)
			(stroke
				(width 0.15)
				(type solid)
			)
			(layer "B.Fab")
		)
		(fp_line
			(start 0.504 0.25)
			(end -0.494 0.25)
			(stroke
				(width 0.15)
				(type solid)
			)
			(layer "B.Fab")
		)
		(fp_text user "License: Apache-2.0"
			(at -0.932 -5.17 180)
			(layer "B.Fab")
			(hide yes)
			(effects
				(font
					(size 0.7 0.7)
					(thickness 0.15)
				)
				(justify left bottom mirror)
			)
		)
		(fp_text user "${REFERENCE}"
			(at -0.932 -3.168 180)
			(layer "B.Fab")
			(hide yes)
			(effects
				(font
					(size 0.7 0.7)
					(thickness 0.15)
				)
				(justify left bottom mirror)
			)
		)
		(fp_text user "Author: Antmicro"
			(at -0.932 -4.17 180)
			(layer "B.Fab")
			(hide yes)
			(effects
				(font
					(size 0.7 0.7)
					(thickness 0.15)
				)
				(justify left bottom mirror)
			)
		)
		(pad "1" smd roundrect
			(at -0.48 0)
			(size 0.59 0.64)
			(layers "B.Cu" "B.Paste" "B.Mask")
			(roundrect_rratio 0.25)
			(net 481 "USBPD2_HV")
			(pintype "passive")
		)
		(pad "2" smd roundrect
			(at 0.48 0)
			(size 0.59 0.64)
			(layers "B.Cu" "B.Paste" "B.Mask")
			(roundrect_rratio 0.25)
			(net 1 "GND")
			(pintype "passive")
		)
	)
	(footprint "antmicro-footprints:R_0402_1005Metric"
		(layer "B.Cu")
		(at 72.3 105.2)
		(descr "Resistor SMD 0402")
		(tags "resistor SMD 0402")
		(property "Reference" "R82"
			(at -0.25 2.2 180)
			(layer "B.SilkS")
			(effects
				(font
					(size 0.7 0.7)
					(thickness 0.15)
				)
				(justify left bottom mirror)
			)
		)
		(property "Value" "R_0R_0402"
			(at 0 -1.4 180)
			(layer "B.Fab")
			(effects
				(font
					(size 0.7 0.7)
					(thickness 0.15)
				)
				(justify left bottom mirror)
			)
		)
		(property "Footprint" "antmicro-footprints:R_0402_1005Metric"
			(at 0 0 0)
			(layer "F.Fab")
			(hide yes)
			(effects
				(font
					(size 1.27 1.27)
					(thickness 0.15)
				)
			)
		)
		(property "Datasheet" "https://industrial.panasonic.com/cdbs/www-data/pdf/RDA0000/AOA0000C301.pdf"
			(at 0 0 0)
			(layer "F.Fab")
			(hide yes)
			(effects
				(font
					(size 1.27 1.27)
					(thickness 0.15)
				)
			)
		)
		(property "Author" "Antmicro"
			(at 0 0 0)
			(layer "B.Fab")
			(hide yes)
			(effects
				(font
					(size 1 1)
					(thickness 0.15)
				)
				(justify mirror)
			)
		)
		(property "Current" "1A"
			(at 0 0 0)
			(layer "B.Fab")
			(hide yes)
			(effects
				(font
					(size 1 1)
					(thickness 0.15)
				)
				(justify mirror)
			)
		)
		(property "License" "Apache-2.0"
			(at 0 0 0)
			(layer "B.Fab")
			(hide yes)
			(effects
				(font
					(size 1 1)
					(thickness 0.15)
				)
				(justify mirror)
			)
		)
		(property "MPN" "ERJ2GE0R00X"
			(at 0 0 0)
			(layer "B.Fab")
			(hide yes)
			(effects
				(font
					(size 1 1)
					(thickness 0.15)
				)
				(justify mirror)
			)
		)
		(property "Manufacturer" "Panasonic"
			(at 0 0 0)
			(layer "B.Fab")
			(hide yes)
			(effects
				(font
					(size 1 1)
					(thickness 0.15)
				)
				(justify mirror)
			)
		)
		(property "Tolerance" ""
			(at 0 0 0)
			(layer "B.Fab")
			(hide yes)
			(effects
				(font
					(size 1 1)
					(thickness 0.15)
				)
				(justify mirror)
			)
		)
		(property "Val" "0R"
			(at 0 0 0)
			(layer "B.Fab")
			(hide yes)
			(effects
				(font
					(size 1 1)
					(thickness 0.15)
				)
				(justify mirror)
			)
		)
		(sheetname "USB Debug, DP")
		(sheetfile "usb.kicad_sch")
		(attr smd exclude_from_pos_files exclude_from_bom dnp)
		(fp_rect
			(start -0.925 0.47)
			(end 0.925 -0.47)
			(stroke
				(width 0.05)
				(type default)
			)
			(fill none)
			(layer "B.CrtYd")
		)
		(fp_rect
			(start -0.5 0.25)
			(end 0.5 -0.25)
			(stroke
				(width 0.15)
				(type solid)
			)
			(fill none)
			(layer "B.Fab")
		)
		(fp_text user "${REFERENCE}"
			(at -0.95 -3.168 180)
			(layer "B.Fab")
			(hide yes)
			(effects
				(font
					(size 0.7 0.7)
					(thickness 0.15)
				)
				(justify left bottom mirror)
			)
		)
		(fp_text user "License: Apache-2.0"
			(at -0.95 -5.169 180)
			(layer "B.Fab")
			(hide yes)
			(effects
				(font
					(size 0.7 0.7)
					(thickness 0.15)
				)
				(justify left bottom mirror)
			)
		)
		(fp_text user "Author: Antmicro"
			(at -0.95 -4.169 180)
			(layer "B.Fab")
			(hide yes)
			(effects
				(font
					(size 0.7 0.7)
					(thickness 0.15)
				)
				(justify left bottom mirror)
			)
		)
		(pad "1" smd roundrect
			(at -0.48 0)
			(size 0.59 0.64)
			(layers "B.Cu" "B.Paste" "B.Mask")
			(roundrect_rratio 0.25)
			(net 293 "/USB Debug, DP/USBC0_FLIP")
			(pintype "passive")
		)
		(pad "2" smd roundrect
			(at 0.48 0)
			(size 0.59 0.64)
			(layers "B.Cu" "B.Paste" "B.Mask")
			(roundrect_rratio 0.25)
			(net 252 "SYS_SCL")
			(pintype "passive")
		)
	)
	(footprint "antmicro-footprints:R_0402_1005Metric"
		(layer "B.Cu")
		(at 112.4 106.1)
		(descr "Resistor SMD 0402")
		(tags "resistor SMD 0402")
		(property "Reference" "R113"
			(at 3.71 0.36 180)
			(layer "B.SilkS")
			(effects
				(font
					(size 0.7 0.7)
					(thickness 0.15)
				)
				(justify left bottom mirror)
			)
		)
		(property "Value" "R_0R_0402"
			(at 0 -1.4 180)
			(layer "B.Fab")
			(effects
				(font
					(size 0.7 0.7)
					(thickness 0.15)
				)
				(justify left bottom mirror)
			)
		)
		(property "Footprint" "antmicro-footprints:R_0402_1005Metric"
			(at 0 0 0)
			(layer "F.Fab")
			(hide yes)
			(effects
				(font
					(size 1.27 1.27)
					(thickness 0.15)
				)
			)
		)
		(property "Datasheet" "https://industrial.panasonic.com/cdbs/www-data/pdf/RDA0000/AOA0000C301.pdf"
			(at 0 0 0)
			(layer "F.Fab")
			(hide yes)
			(effects
				(font
					(size 1.27 1.27)
					(thickness 0.15)
				)
			)
		)
		(property "Author" "Antmicro"
			(at 0 0 0)
			(layer "B.Fab")
			(hide yes)
			(effects
				(font
					(size 1 1)
					(thickness 0.15)
				)
				(justify mirror)
			)
		)
		(property "Current" "1A"
			(at 0 0 0)
			(layer "B.Fab")
			(hide yes)
			(effects
				(font
					(size 1 1)
					(thickness 0.15)
				)
				(justify mirror)
			)
		)
		(property "License" "Apache-2.0"
			(at 0 0 0)
			(layer "B.Fab")
			(hide yes)
			(effects
				(font
					(size 1 1)
					(thickness 0.15)
				)
				(justify mirror)
			)
		)
		(property "MPN" "ERJ2GE0R00X"
			(at 0 0 0)
			(layer "B.Fab")
			(hide yes)
			(effects
				(font
					(size 1 1)
					(thickness 0.15)
				)
				(justify mirror)
			)
		)
		(property "Manufacturer" "Panasonic"
			(at 0 0 0)
			(layer "B.Fab")
			(hide yes)
			(effects
				(font
					(size 1 1)
					(thickness 0.15)
				)
				(justify mirror)
			)
		)
		(property "Tolerance" ""
			(at 0 0 0)
			(layer "B.Fab")
			(hide yes)
			(effects
				(font
					(size 1 1)
					(thickness 0.15)
				)
				(justify mirror)
			)
		)
		(property "Val" "0R"
			(at 0 0 0)
			(layer "B.Fab")
			(hide yes)
			(effects
				(font
					(size 1 1)
					(thickness 0.15)
				)
				(justify mirror)
			)
		)
		(sheetname "USB3")
		(sheetfile "usb3.kicad_sch")
		(attr smd exclude_from_pos_files exclude_from_bom dnp)
		(fp_rect
			(start -0.925 0.47)
			(end 0.925 -0.47)
			(stroke
				(width 0.05)
				(type default)
			)
			(fill none)
			(layer "B.CrtYd")
		)
		(fp_rect
			(start -0.5 0.25)
			(end 0.5 -0.25)
			(stroke
				(width 0.15)
				(type solid)
			)
			(fill none)
			(layer "B.Fab")
		)
		(fp_text user "${REFERENCE}"
			(at -0.95 -3.168 180)
			(layer "B.Fab")
			(hide yes)
			(effects
				(font
					(size 0.7 0.7)
					(thickness 0.15)
				)
				(justify left bottom mirror)
			)
		)
		(fp_text user "License: Apache-2.0"
			(at -0.95 -5.169 180)
			(layer "B.Fab")
			(hide yes)
			(effects
				(font
					(size 0.7 0.7)
					(thickness 0.15)
				)
				(justify left bottom mirror)
			)
		)
		(fp_text user "Author: Antmicro"
			(at -0.95 -4.169 180)
			(layer "B.Fab")
			(hide yes)
			(effects
				(font
					(size 0.7 0.7)
					(thickness 0.15)
				)
				(justify left bottom mirror)
			)
		)
		(pad "1" smd roundrect
			(at -0.48 0)
			(size 0.59 0.64)
			(layers "B.Cu" "B.Paste" "B.Mask")
			(roundrect_rratio 0.25)
			(net 314 "/USB3/USBC1_ADDR")
			(pintype "passive")
		)
		(pad "2" smd roundrect
			(at 0.48 0)
			(size 0.59 0.64)
			(layers "B.Cu" "B.Paste" "B.Mask")
			(roundrect_rratio 0.25)
			(net 99 "+5V")
			(pintype "passive")
		)
	)
	(footprint "antmicro-footprints:R_0402_1005Metric"
		(layer "B.Cu")
		(at 55.125 88.425)
		(descr "Resistor SMD 0402")
		(tags "resistor SMD 0402")
		(property "Reference" "R153"
			(at -1.245 2.555 0)
			(layer "B.SilkS")
			(effects
				(font
					(size 0.7 0.7)
					(thickness 0.15)
				)
				(justify right top mirror)
			)
		)
		(property "Value" "R_10k_0402"
			(at 0 -1.4 0)
			(layer "B.Fab")
			(effects
				(font
					(size 0.7 0.7)
					(thickness 0.15)
				)
				(justify right top mirror)
			)
		)
		(property "Footprint" "antmicro-footprints:R_0402_1005Metric"
			(at 0 0 0)
			(layer "F.Fab")
			(hide yes)
			(effects
				(font
					(size 1.27 1.27)
					(thickness 0.15)
				)
			)
		)
		(property "Datasheet" "https://www.bourns.com/docs/product-datasheets/cr.pdf"
			(at 0 0 0)
			(layer "F.Fab")
			(hide yes)
			(effects
				(font
					(size 1.27 1.27)
					(thickness 0.15)
				)
			)
		)
		(property "Author" "Antmicro"
			(at -33.575 143.225 90)
			(layer "B.Fab")
			(hide yes)
			(effects
				(font
					(size 1 1)
					(thickness 0.15)
				)
				(justify mirror)
			)
		)
		(property "License" "Apache-2.0"
			(at -33.575 143.225 90)
			(layer "B.Fab")
			(hide yes)
			(effects
				(font
					(size 1 1)
					(thickness 0.15)
				)
				(justify mirror)
			)
		)
		(property "MPN" "CR0402-FX-1002GLF"
			(at -33.575 143.225 90)
			(layer "B.Fab")
			(hide yes)
			(effects
				(font
					(size 1 1)
					(thickness 0.15)
				)
				(justify mirror)
			)
		)
		(property "Manufacturer" "Bourns"
			(at -33.575 143.225 90)
			(layer "B.Fab")
			(hide yes)
			(effects
				(font
					(size 1 1)
					(thickness 0.15)
				)
				(justify mirror)
			)
		)
		(property "Tolerance" "1%"
			(at -33.575 143.225 90)
			(layer "B.Fab")
			(hide yes)
			(effects
				(font
					(size 1 1)
					(thickness 0.15)
				)
				(justify mirror)
			)
		)
		(property "Val" "10k"
			(at -33.575 143.225 90)
			(layer "B.Fab")
			(hide yes)
			(effects
				(font
					(size 1 1)
					(thickness 0.15)
				)
				(justify mirror)
			)
		)
		(sheetname "Ethernet")
		(sheetfile "ethernet.kicad_sch")
		(attr smd exclude_from_pos_files exclude_from_bom dnp)
		(fp_rect
			(start -0.925 0.47)
			(end 0.925 -0.47)
			(stroke
				(width 0.05)
				(type default)
			)
			(fill none)
			(layer "B.CrtYd")
		)
		(fp_rect
			(start -0.5 0.25)
			(end 0.5 -0.25)
			(stroke
				(width 0.15)
				(type solid)
			)
			(fill none)
			(layer "B.Fab")
		)
		(fp_text user "${REFERENCE}"
			(at -0.95 -3.168 0)
			(layer "B.Fab")
			(hide yes)
			(effects
				(font
					(size 0.7 0.7)
					(thickness 0.15)
				)
				(justify right top mirror)
			)
		)
		(fp_text user "Author: Antmicro"
			(at -0.95 -4.169 0)
			(layer "B.Fab")
			(hide yes)
			(effects
				(font
					(size 0.7 0.7)
					(thickness 0.15)
				)
				(justify right top mirror)
			)
		)
		(fp_text user "License: Apache-2.0"
			(at -0.95 -5.169 0)
			(layer "B.Fab")
			(hide yes)
			(effects
				(font
					(size 0.7 0.7)
					(thickness 0.15)
				)
				(justify right top mirror)
			)
		)
		(pad "1" smd roundrect
			(at -0.48 0)
			(size 0.59 0.64)
			(layers "B.Cu" "B.Paste" "B.Mask")
			(roundrect_rratio 0.25)
			(net 574 "/Ethernet/~{BT}")
			(pintype "passive")
		)
		(pad "2" smd roundrect
			(at 0.48 0)
			(size 0.59 0.64)
			(layers "B.Cu" "B.Paste" "B.Mask")
			(roundrect_rratio 0.25)
			(net 105 "/Ethernet/VDD")
			(pintype "passive")
		)
	)
	(footprint "antmicro-footprints:R_0402_1005Metric"
		(layer "B.Cu")
		(at 67.7 72.9)
		(descr "Resistor SMD 0402")
		(tags "resistor SMD 0402")
		(property "Reference" "R259"
			(at 1.49 -0.58 180)
			(layer "B.SilkS")
			(effects
				(font
					(size 0.7 0.7)
					(thickness 0.15)
				)
				(justify left bottom mirror)
			)
		)
		(property "Value" "R_10k_0402"
			(at 0 -1.4 180)
			(layer "B.Fab")
			(effects
				(font
					(size 0.7 0.7)
					(thickness 0.15)
				)
				(justify left bottom mirror)
			)
		)
		(property "Footprint" "antmicro-footprints:R_0402_1005Metric"
			(at 0 0 0)
			(layer "F.Fab")
			(hide yes)
			(effects
				(font
					(size 1.27 1.27)
					(thickness 0.15)
				)
			)
		)
		(property "Datasheet" "https://www.bourns.com/docs/product-datasheets/cr.pdf"
			(at 0 0 0)
			(layer "F.Fab")
			(hide yes)
			(effects
				(font
					(size 1.27 1.27)
					(thickness 0.15)
				)
			)
		)
		(property "Author" "Antmicro"
			(at 0 0 0)
			(layer "B.Fab")
			(hide yes)
			(effects
				(font
					(size 1 1)
					(thickness 0.15)
				)
				(justify mirror)
			)
		)
		(property "License" "Apache-2.0"
			(at 0 0 0)
			(layer "B.Fab")
			(hide yes)
			(effects
				(font
					(size 1 1)
					(thickness 0.15)
				)
				(justify mirror)
			)
		)
		(property "MPN" "CR0402-FX-1002GLF"
			(at 0 0 0)
			(layer "B.Fab")
			(hide yes)
			(effects
				(font
					(size 1 1)
					(thickness 0.15)
				)
				(justify mirror)
			)
		)
		(property "Manufacturer" "Bourns"
			(at 0 0 0)
			(layer "B.Fab")
			(hide yes)
			(effects
				(font
					(size 1 1)
					(thickness 0.15)
				)
				(justify mirror)
			)
		)
		(property "Tolerance" "1%"
			(at 0 0 0)
			(layer "B.Fab")
			(hide yes)
			(effects
				(font
					(size 1 1)
					(thickness 0.15)
				)
				(justify mirror)
			)
		)
		(property "Val" "10k"
			(at 0 0 0)
			(layer "B.Fab")
			(hide yes)
			(effects
				(font
					(size 1 1)
					(thickness 0.15)
				)
				(justify mirror)
			)
		)
		(sheetname "Supply")
		(sheetfile "supply.kicad_sch")
		(attr smd)
		(fp_rect
			(start -0.925 0.47)
			(end 0.925 -0.47)
			(stroke
				(width 0.05)
				(type default)
			)
			(fill none)
			(layer "B.CrtYd")
		)
		(fp_rect
			(start -0.5 0.25)
			(end 0.5 -0.25)
			(stroke
				(width 0.15)
				(type solid)
			)
			(fill none)
			(layer "B.Fab")
		)
		(fp_text user "Author: Antmicro"
			(at -0.95 -4.169 180)
			(layer "B.Fab")
			(hide yes)
			(effects
				(font
					(size 0.7 0.7)
					(thickness 0.15)
				)
				(justify left bottom mirror)
			)
		)
		(fp_text user "License: Apache-2.0"
			(at -0.95 -5.169 180)
			(layer "B.Fab")
			(hide yes)
			(effects
				(font
					(size 0.7 0.7)
					(thickness 0.15)
				)
				(justify left bottom mirror)
			)
		)
		(fp_text user "${REFERENCE}"
			(at -0.95 -3.168 180)
			(layer "B.Fab")
			(hide yes)
			(effects
				(font
					(size 0.7 0.7)
					(thickness 0.15)
				)
				(justify left bottom mirror)
			)
		)
		(pad "1" smd roundrect
			(at -0.48 0)
			(size 0.59 0.64)
			(layers "B.Cu" "B.Paste" "B.Mask")
			(roundrect_rratio 0.25)
			(net 629 "Net-(D37-A)")
			(pintype "passive")
		)
		(pad "2" smd roundrect
			(at 0.48 0)
			(size 0.59 0.64)
			(layers "B.Cu" "B.Paste" "B.Mask")
			(roundrect_rratio 0.25)
			(net 117 "3V3_STDB")
			(pintype "passive")
		)
	)
	(footprint "antmicro-footprints:C_0402_1005Metric"
		(layer "B.Cu")
		(at 65.3 75.5)
		(descr "Capacitor SMD 0402")
		(tags "capacitor SMD 0402")
		(property "Reference" "C119"
			(at 16.86 3.45 180)
			(layer "B.SilkS")
			(effects
				(font
					(size 0.7 0.7)
					(thickness 0.15)
				)
				(justify left bottom mirror)
			)
		)
		(property "Value" "C_100n_0402"
			(at 0 -1.4 180)
			(layer "B.Fab")
			(effects
				(font
					(size 0.7 0.7)
					(thickness 0.15)
				)
				(justify left bottom mirror)
			)
		)
		(property "Footprint" "antmicro-footprints:C_0402_1005Metric"
			(at 0 0 0)
			(layer "F.Fab")
			(hide yes)
			(effects
				(font
					(size 1.27 1.27)
					(thickness 0.15)
				)
			)
		)
		(property "Datasheet" "https://www.murata.com/products/productdetail?partno=GRM155R61H104KE14%23"
			(at 0 0 0)
			(layer "F.Fab")
			(hide yes)
			(effects
				(font
					(size 1.27 1.27)
					(thickness 0.15)
				)
			)
		)
		(property "Author" "Antmicro"
			(at 0 0 0)
			(layer "B.Fab")
			(hide yes)
			(effects
				(font
					(size 1 1)
					(thickness 0.15)
				)
				(justify mirror)
			)
		)
		(property "Dielectric" "X5R"
			(at 0 0 0)
			(layer "B.Fab")
			(hide yes)
			(effects
				(font
					(size 1 1)
					(thickness 0.15)
				)
				(justify mirror)
			)
		)
		(property "License" "Apache-2.0"
			(at 0 0 0)
			(layer "B.Fab")
			(hide yes)
			(effects
				(font
					(size 1 1)
					(thickness 0.15)
				)
				(justify mirror)
			)
		)
		(property "MPN" "GRM155R61H104KE14D"
			(at 0 0 0)
			(layer "B.Fab")
			(hide yes)
			(effects
				(font
					(size 1 1)
					(thickness 0.15)
				)
				(justify mirror)
			)
		)
		(property "Manufacturer" "Murata"
			(at 0 0 0)
			(layer "B.Fab")
			(hide yes)
			(effects
				(font
					(size 1 1)
					(thickness 0.15)
				)
				(justify mirror)
			)
		)
		(property "Val" "100n"
			(at 0 0 0)
			(layer "B.Fab")
			(hide yes)
			(effects
				(font
					(size 1 1)
					(thickness 0.15)
				)
				(justify mirror)
			)
		)
		(property "Voltage" "50V"
			(at 0 0 0)
			(layer "B.Fab")
			(hide yes)
			(effects
				(font
					(size 1 1)
					(thickness 0.15)
				)
				(justify mirror)
			)
		)
		(sheetname "Supply")
		(sheetfile "supply.kicad_sch")
		(attr smd)
		(fp_rect
			(start -0.925 0.47)
			(end 0.925 -0.47)
			(stroke
				(width 0.05)
				(type default)
			)
			(fill none)
			(layer "B.CrtYd")
		)
		(fp_line
			(start -0.494 -0.248)
			(end 0.504 -0.248)
			(stroke
				(width 0.15)
				(type solid)
			)
			(layer "B.Fab")
		)
		(fp_line
			(start -0.494 0.25)
			(end -0.494 -0.248)
			(stroke
				(width 0.15)
				(type solid)
			)
			(layer "B.Fab")
		)
		(fp_line
			(start 0.504 -0.248)
			(end 0.504 0.25)
			(stroke
				(width 0.15)
				(type solid)
			)
			(layer "B.Fab")
		)
		(fp_line
			(start 0.504 0.25)
			(end -0.494 0.25)
			(stroke
				(width 0.15)
				(type solid)
			)
			(layer "B.Fab")
		)
		(fp_text user "Author: Antmicro"
			(at -0.932 -4.17 180)
			(layer "B.Fab")
			(hide yes)
			(effects
				(font
					(size 0.7 0.7)
					(thickness 0.15)
				)
				(justify left bottom mirror)
			)
		)
		(fp_text user "${REFERENCE}"
			(at -0.932 -3.168 180)
			(layer "B.Fab")
			(hide yes)
			(effects
				(font
					(size 0.7 0.7)
					(thickness 0.15)
				)
				(justify left bottom mirror)
			)
		)
		(fp_text user "License: Apache-2.0"
			(at -0.932 -5.17 180)
			(layer "B.Fab")
			(hide yes)
			(effects
				(font
					(size 0.7 0.7)
					(thickness 0.15)
				)
				(justify left bottom mirror)
			)
		)
		(pad "1" smd roundrect
			(at -0.48 0)
			(size 0.59 0.64)
			(layers "B.Cu" "B.Paste" "B.Mask")
			(roundrect_rratio 0.25)
			(net 1 "GND")
			(pintype "passive")
		)
		(pad "2" smd roundrect
			(at 0.48 0)
			(size 0.59 0.64)
			(layers "B.Cu" "B.Paste" "B.Mask")
			(roundrect_rratio 0.25)
			(net 117 "3V3_STDB")
			(pintype "passive")
		)
	)
	(footprint "antmicro-footprints:Spacer_Drill3.7mm_H2.5mm_9774025151R"
		(layer "B.Cu")
		(at 40.75 86.75 180)
		(descr "Spacer M=3 h=2.5mm fi=5.1mm")
		(property "Reference" "SP8"
			(at -1.05 3.45 0)
			(layer "B.SilkS")
			(effects
				(font
					(size 0.7 0.7)
					(thickness 0.15)
				)
				(justify left bottom mirror)
			)
		)
		(property "Value" "Spacer_Drill3.7mm_H2.5mm_9774025151R"
			(at 0 -4 0)
			(layer "B.Fab")
			(effects
				(font
					(size 0.7 0.7)
					(thickness 0.15)
				)
				(justify left bottom mirror)
			)
		)
		(property "Footprint" "antmicro-footprints:Spacer_Drill3.7mm_H2.5mm_9774025151R"
			(at 0 0 180)
			(layer "F.Fab")
			(hide yes)
			(effects
				(font
					(size 1.27 1.27)
					(thickness 0.15)
				)
			)
		)
		(property "Datasheet" "https://www.we-online.com/components/products/datasheet/9774025151R.pdf"
			(at 0 0 180)
			(layer "F.Fab")
			(hide yes)
			(effects
				(font
					(size 1.27 1.27)
					(thickness 0.15)
				)
			)
		)
		(property "Author" "Antmicro"
			(at 81.5 173.5 0)
			(layer "B.Fab")
			(hide yes)
			(effects
				(font
					(size 1 1)
					(thickness 0.15)
				)
				(justify mirror)
			)
		)
		(property "License" "Apache-2.0"
			(at 81.5 173.5 0)
			(layer "B.Fab")
			(hide yes)
			(effects
				(font
					(size 1 1)
					(thickness 0.15)
				)
				(justify mirror)
			)
		)
		(property "MPN" "9774025151R"
			(at 81.5 173.5 0)
			(layer "B.Fab")
			(hide yes)
			(effects
				(font
					(size 1 1)
					(thickness 0.15)
				)
				(justify mirror)
			)
		)
		(property "Manufacturer" "Würth Elektronik"
			(at 81.5 173.5 0)
			(layer "B.Fab")
			(hide yes)
			(effects
				(font
					(size 1 1)
					(thickness 0.15)
				)
				(justify mirror)
			)
		)
		(sheetname "M.2")
		(sheetfile "m-2.kicad_sch")
		(solder_paste_ratio -1)
		(attr smd)
		(fp_circle
			(center 0 0)
			(end 3.05 0)
			(stroke
				(width 0.05)
				(type solid)
			)
			(fill none)
			(layer "B.CrtYd")
		)
		(fp_circle
			(center 0 0)
			(end 2.6 0)
			(stroke
				(width 0.15)
				(type solid)
			)
			(fill none)
			(layer "B.Fab")
		)
		(fp_text user "Author: Antmicro"
			(at -9.6 -7.7 0)
			(layer "B.Fab")
			(hide yes)
			(effects
				(font
					(size 0.7 0.7)
					(thickness 0.15)
				)
				(justify left bottom mirror)
			)
		)
		(fp_text user "${REFERENCE}"
			(at -9.6 -6.5 0)
			(layer "B.Fab")
			(hide yes)
			(effects
				(font
					(size 0.7 0.7)
					(thickness 0.15)
				)
				(justify left bottom mirror)
			)
		)
		(fp_text user "License: Apache-2.0"
			(at -9.6 -8.9 0)
			(layer "B.Fab")
			(hide yes)
			(effects
				(font
					(size 0.7 0.7)
					(thickness 0.15)
				)
				(justify left bottom mirror)
			)
		)
		(pad "" smd custom
			(at -1.7 -1.7 90)
			(size 0.62 0.62)
			(layers "B.Paste")
			(thermal_bridge_angle 90)
			(options
				(clearance outline)
				(anchor circle)
			)
			(primitives
				(gr_arc
					(start 1.266786 0.24747)
					(mid 0.285453 -0.29439)
					(end -0.250195 -1.279127)
					(width 0.2)
				)
				(gr_arc
					(start 1.259603 0.339191)
					(mid 0.218448 -0.232561)
					(end -0.34334 -1.279127)
					(width 0.2)
				)
				(gr_arc
					(start 1.255279 0.431435)
					(mid 0.152481 -0.169693)
					(end -0.436309 -1.279127)
					(width 0.2)
				)
				(gr_arc
					(start 1.253811 0.524161)
					(mid 0.087542 -0.105784)
					(end -0.529126 -1.279127)
					(width 0.2)
				)
				(gr_arc
					(start 1.275473 0.621136)
					(mid 0.0309 -0.033527)
					(end -0.621807 -1.279127)
					(width 0.2)
				)
				(gr_arc
					(start 1.263664 0.711602)
					(mid -0.037759 0.026651)
					(end -0.71437 -1.279127)
					(width 0.2)
				)
				(gr_arc
					(start 1.253435 0.802342)
					(mid -0.105837 0.087395)
					(end -0.806826 -1.279127)
					(width 0.2)
				)
				(gr_arc
					(start 1.267475 0.897258)
					(mid -0.165236 0.156885)
					(end -0.899187 -1.279127)
					(width 0.2)
				)
				(gr_arc
					(start 1.270645 0.990112)
					(mid -0.228522 0.222449)
					(end -0.991463 -1.279127)
					(width 0.2)
				)
				(gr_arc
					(start 1.266278 1.081674)
					(mid -0.294507 0.285313)
					(end -1.083663 -1.279127)
					(width 0.2)
				)
				(gr_line
					(start 1.279127 0.250195)
					(end 1.279127 1.083663)
					(width 0.2)
				)
				(gr_line
					(start -0.250195 -1.279127)
					(end -1.083663 -1.279127)
					(width 0.2)
				)
			)
		)
		(pad "" smd custom
			(at -1.7 1.7 180)
			(size 0.62 0.62)
			(layers "B.Paste")
			(thermal_bridge_angle 90)
			(options
				(clearance outline)
				(anchor circle)
			)
			(primitives
				(gr_arc
					(start 1.266786 0.24747)
					(mid 0.285453 -0.29439)
					(end -0.250195 -1.279127)
					(width 0.2)
				)
				(gr_arc
					(start 1.259603 0.339191)
					(mid 0.218448 -0.232561)
					(end -0.34334 -1.279127)
					(width 0.2)
				)
				(gr_arc
					(start 1.255279 0.431435)
					(mid 0.152481 -0.169693)
					(end -0.436309 -1.279127)
					(width 0.2)
				)
				(gr_arc
					(start 1.253811 0.524161)
					(mid 0.087542 -0.105784)
					(end -0.529126 -1.279127)
					(width 0.2)
				)
				(gr_arc
					(start 1.275473 0.621136)
					(mid 0.0309 -0.033527)
					(end -0.621807 -1.279127)
					(width 0.2)
				)
				(gr_arc
					(start 1.263664 0.711602)
					(mid -0.037759 0.026651)
					(end -0.71437 -1.279127)
					(width 0.2)
				)
				(gr_arc
					(start 1.253435 0.802342)
					(mid -0.105837 0.087395)
					(end -0.806826 -1.279127)
					(width 0.2)
				)
				(gr_arc
					(start 1.267475 0.897258)
					(mid -0.165236 0.156885)
					(end -0.899187 -1.279127)
					(width 0.2)
				)
				(gr_arc
					(start 1.270645 0.990112)
					(mid -0.228522 0.222449)
					(end -0.991463 -1.279127)
					(width 0.2)
				)
				(gr_arc
					(start 1.266278 1.081674)
					(mid -0.294507 0.285313)
					(end -1.083663 -1.279127)
					(width 0.2)
				)
				(gr_line
					(start 1.279127 0.250195)
					(end 1.279127 1.083663)
					(width 0.2)
				)
				(gr_line
					(start -0.250195 -1.279127)
					(end -1.083663 -1.279127)
					(width 0.2)
				)
			)
		)
		(pad "" smd custom
			(at 1.7 -1.7)
			(size 0.62 0.62)
			(layers "B.Paste")
			(thermal_bridge_angle 90)
			(options
				(clearance outline)
				(anchor circle)
			)
			(primitives
				(gr_arc
					(start 1.266786 0.24747)
					(mid 0.285453 -0.29439)
					(end -0.250195 -1.279127)
					(width 0.2)
				)
				(gr_arc
					(start 1.259603 0.339191)
					(mid 0.218448 -0.232561)
					(end -0.34334 -1.279127)
					(width 0.2)
				)
				(gr_arc
					(start 1.255279 0.431435)
					(mid 0.152481 -0.169693)
					(end -0.436309 -1.279127)
					(width 0.2)
				)
				(gr_arc
					(start 1.253811 0.524161)
					(mid 0.087542 -0.105784)
					(end -0.529126 -1.279127)
					(width 0.2)
				)
				(gr_arc
					(start 1.275473 0.621136)
					(mid 0.0309 -0.033527)
					(end -0.621807 -1.279127)
					(width 0.2)
				)
				(gr_arc
					(start 1.263664 0.711602)
					(mid -0.037759 0.026651)
					(end -0.71437 -1.279127)
					(width 0.2)
				)
				(gr_arc
					(start 1.253435 0.802342)
					(mid -0.105837 0.087395)
					(end -0.806826 -1.279127)
					(width 0.2)
				)
				(gr_arc
					(start 1.267475 0.897258)
					(mid -0.165236 0.156885)
					(end -0.899187 -1.279127)
					(width 0.2)
				)
				(gr_arc
					(start 1.270645 0.990112)
					(mid -0.228522 0.222449)
					(end -0.991463 -1.279127)
					(width 0.2)
				)
				(gr_arc
					(start 1.266278 1.081674)
					(mid -0.294507 0.285313)
					(end -1.083663 -1.279127)
					(width 0.2)
				)
				(gr_line
					(start 1.279127 0.250195)
					(end 1.279127 1.083663)
					(width 0.2)
				)
				(gr_line
					(start -0.250195 -1.279127)
					(end -1.083663 -1.279127)
					(width 0.2)
				)
			)
		)
		(pad "" smd custom
			(at 1.7 1.7 270)
			(size 0.62 0.62)
			(layers "B.Paste")
			(thermal_bridge_angle 90)
			(options
				(clearance outline)
				(anchor circle)
			)
			(primitives
				(gr_arc
					(start 1.266786 0.24747)
					(mid 0.285453 -0.29439)
					(end -0.250195 -1.279127)
					(width 0.2)
				)
				(gr_arc
					(start 1.259603 0.339191)
					(mid 0.218448 -0.232561)
					(end -0.34334 -1.279127)
					(width 0.2)
				)
				(gr_arc
					(start 1.255279 0.431435)
					(mid 0.152481 -0.169693)
					(end -0.436309 -1.279127)
					(width 0.2)
				)
				(gr_arc
					(start 1.253811 0.524161)
					(mid 0.087542 -0.105784)
					(end -0.529126 -1.279127)
					(width 0.2)
				)
				(gr_arc
					(start 1.275473 0.621136)
					(mid 0.0309 -0.033527)
					(end -0.621807 -1.279127)
					(width 0.2)
				)
				(gr_arc
					(start 1.263664 0.711602)
					(mid -0.037759 0.026651)
					(end -0.71437 -1.279127)
					(width 0.2)
				)
				(gr_arc
					(start 1.253435 0.802342)
					(mid -0.105837 0.087395)
					(end -0.806826 -1.279127)
					(width 0.2)
				)
				(gr_arc
					(start 1.267475 0.897258)
					(mid -0.165236 0.156885)
					(end -0.899187 -1.279127)
					(width 0.2)
				)
				(gr_arc
					(start 1.270645 0.990112)
					(mid -0.228522 0.222449)
					(end -0.991463 -1.279127)
					(width 0.2)
				)
				(gr_arc
					(start 1.266278 1.081674)
					(mid -0.294507 0.285313)
					(end -1.083663 -1.279127)
					(width 0.2)
				)
				(gr_line
					(start 1.279127 0.250195)
					(end 1.279127 1.083663)
					(width 0.2)
				)
				(gr_line
					(start -0.250195 -1.279127)
					(end -1.083663 -1.279127)
					(width 0.2)
				)
			)
		)
		(pad "1" thru_hole circle
			(at 0 0 180)
			(size 6 6)
			(drill 3.7)
			(layers "*.Cu" "*.Mask")
			(remove_unused_layers no)
			(net 1 "GND")
			(pintype "passive")
		)
	)
	(footprint "antmicro-footprints:R_0402_1005Metric"
		(layer "B.Cu")
		(at 107.15175 95.525 90)
		(descr "Resistor SMD 0402")
		(tags "resistor SMD 0402")
		(property "Reference" "R174"
			(at 1.375 -0.40175 -90)
			(layer "B.SilkS")
			(effects
				(font
					(size 0.7 0.7)
					(thickness 0.15)
				)
				(justify left bottom mirror)
			)
		)
		(property "Value" "R_0R_0402"
			(at 0 -1.4 -90)
			(layer "B.Fab")
			(effects
				(font
					(size 0.7 0.7)
					(thickness 0.15)
				)
				(justify left bottom mirror)
			)
		)
		(property "Footprint" "antmicro-footprints:R_0402_1005Metric"
			(at 0 0 90)
			(layer "F.Fab")
			(hide yes)
			(effects
				(font
					(size 1.27 1.27)
					(thickness 0.15)
				)
			)
		)
		(property "Datasheet" "https://industrial.panasonic.com/cdbs/www-data/pdf/RDA0000/AOA0000C301.pdf"
			(at 0 0 90)
			(layer "F.Fab")
			(hide yes)
			(effects
				(font
					(size 1.27 1.27)
					(thickness 0.15)
				)
			)
		)
		(property "Author" "Antmicro"
			(at 202.67675 -11.62675 0)
			(layer "B.Fab")
			(hide yes)
			(effects
				(font
					(size 1 1)
					(thickness 0.15)
				)
				(justify mirror)
			)
		)
		(property "Current" "1A"
			(at 202.67675 -11.62675 0)
			(layer "B.Fab")
			(hide yes)
			(effects
				(font
					(size 1 1)
					(thickness 0.15)
				)
				(justify mirror)
			)
		)
		(property "License" "Apache-2.0"
			(at 202.67675 -11.62675 0)
			(layer "B.Fab")
			(hide yes)
			(effects
				(font
					(size 1 1)
					(thickness 0.15)
				)
				(justify mirror)
			)
		)
		(property "MPN" "ERJ2GE0R00X"
			(at 202.67675 -11.62675 0)
			(layer "B.Fab")
			(hide yes)
			(effects
				(font
					(size 1 1)
					(thickness 0.15)
				)
				(justify mirror)
			)
		)
		(property "Manufacturer" "Panasonic"
			(at 202.67675 -11.62675 0)
			(layer "B.Fab")
			(hide yes)
			(effects
				(font
					(size 1 1)
					(thickness 0.15)
				)
				(justify mirror)
			)
		)
		(property "Tolerance" ""
			(at 202.67675 -11.62675 0)
			(layer "B.Fab")
			(hide yes)
			(effects
				(font
					(size 1 1)
					(thickness 0.15)
				)
				(justify mirror)
			)
		)
		(property "Val" "0R"
			(at 202.67675 -11.62675 0)
			(layer "B.Fab")
			(hide yes)
			(effects
				(font
					(size 1 1)
					(thickness 0.15)
				)
				(justify mirror)
			)
		)
		(sheetname "CSI")
		(sheetfile "csi.kicad_sch")
		(attr smd)
		(fp_rect
			(start -0.925 0.47)
			(end 0.925 -0.47)
			(stroke
				(width 0.05)
				(type default)
			)
			(fill none)
			(layer "B.CrtYd")
		)
		(fp_rect
			(start -0.5 0.25)
			(end 0.5 -0.25)
			(stroke
				(width 0.15)
				(type solid)
			)
			(fill none)
			(layer "B.Fab")
		)
		(fp_text user "${REFERENCE}"
			(at -0.95 -3.168 -90)
			(layer "B.Fab")
			(hide yes)
			(effects
				(font
					(size 0.7 0.7)
					(thickness 0.15)
				)
				(justify left bottom mirror)
			)
		)
		(fp_text user "License: Apache-2.0"
			(at -0.95 -5.169 -90)
			(layer "B.Fab")
			(hide yes)
			(effects
				(font
					(size 0.7 0.7)
					(thickness 0.15)
				)
				(justify left bottom mirror)
			)
		)
		(fp_text user "Author: Antmicro"
			(at -0.95 -4.169 -90)
			(layer "B.Fab")
			(hide yes)
			(effects
				(font
					(size 0.7 0.7)
					(thickness 0.15)
				)
				(justify left bottom mirror)
			)
		)
		(pad "1" smd roundrect
			(at -0.48 0 90)
			(size 0.59 0.64)
			(layers "B.Cu" "B.Paste" "B.Mask")
			(roundrect_rratio 0.25)
			(net 636 "/CSI/CSIB_I2C_VCC")
			(pintype "passive")
		)
		(pad "2" smd roundrect
			(at 0.48 0 90)
			(size 0.59 0.64)
			(layers "B.Cu" "B.Paste" "B.Mask")
			(roundrect_rratio 0.25)
			(net 87 "+3V3")
			(pintype "passive")
		)
	)
	(footprint "antmicro-footprints:C_0402_1005Metric"
		(layer "B.Cu")
		(at 71.3 75.7 90)
		(descr "Capacitor SMD 0402")
		(tags "capacitor SMD 0402")
		(property "Reference" "C124"
			(at -2.27 14.38 -90)
			(layer "B.SilkS")
			(effects
				(font
					(size 0.7 0.7)
					(thickness 0.15)
				)
				(justify left bottom mirror)
			)
		)
		(property "Value" "C_100n_0402"
			(at 0 -1.4 -90)
			(layer "B.Fab")
			(effects
				(font
					(size 0.7 0.7)
					(thickness 0.15)
				)
				(justify left bottom mirror)
			)
		)
		(property "Footprint" "antmicro-footprints:C_0402_1005Metric"
			(at 0 0 90)
			(layer "F.Fab")
			(hide yes)
			(effects
				(font
					(size 1.27 1.27)
					(thickness 0.15)
				)
			)
		)
		(property "Datasheet" "https://www.murata.com/products/productdetail?partno=GRM155R61H104KE14%23"
			(at 0 0 90)
			(layer "F.Fab")
			(hide yes)
			(effects
				(font
					(size 1.27 1.27)
					(thickness 0.15)
				)
			)
		)
		(property "Author" "Antmicro"
			(at 147 4.4 0)
			(layer "B.Fab")
			(hide yes)
			(effects
				(font
					(size 1 1)
					(thickness 0.15)
				)
				(justify mirror)
			)
		)
		(property "Dielectric" "X5R"
			(at 147 4.4 0)
			(layer "B.Fab")
			(hide yes)
			(effects
				(font
					(size 1 1)
					(thickness 0.15)
				)
				(justify mirror)
			)
		)
		(property "License" "Apache-2.0"
			(at 147 4.4 0)
			(layer "B.Fab")
			(hide yes)
			(effects
				(font
					(size 1 1)
					(thickness 0.15)
				)
				(justify mirror)
			)
		)
		(property "MPN" "GRM155R61H104KE14D"
			(at 147 4.4 0)
			(layer "B.Fab")
			(hide yes)
			(effects
				(font
					(size 1 1)
					(thickness 0.15)
				)
				(justify mirror)
			)
		)
		(property "Manufacturer" "Murata"
			(at 147 4.4 0)
			(layer "B.Fab")
			(hide yes)
			(effects
				(font
					(size 1 1)
					(thickness 0.15)
				)
				(justify mirror)
			)
		)
		(property "Val" "100n"
			(at 147 4.4 0)
			(layer "B.Fab")
			(hide yes)
			(effects
				(font
					(size 1 1)
					(thickness 0.15)
				)
				(justify mirror)
			)
		)
		(property "Voltage" "50V"
			(at 147 4.4 0)
			(layer "B.Fab")
			(hide yes)
			(effects
				(font
					(size 1 1)
					(thickness 0.15)
				)
				(justify mirror)
			)
		)
		(sheetname "Supply")
		(sheetfile "supply.kicad_sch")
		(attr smd)
		(fp_rect
			(start -0.925 0.47)
			(end 0.925 -0.47)
			(stroke
				(width 0.05)
				(type default)
			)
			(fill none)
			(layer "B.CrtYd")
		)
		(fp_line
			(start 0.504 -0.248)
			(end 0.504 0.25)
			(stroke
				(width 0.15)
				(type solid)
			)
			(layer "B.Fab")
		)
		(fp_line
			(start -0.494 -0.248)
			(end 0.504 -0.248)
			(stroke
				(width 0.15)
				(type solid)
			)
			(layer "B.Fab")
		)
		(fp_line
			(start 0.504 0.25)
			(end -0.494 0.25)
			(stroke
				(width 0.15)
				(type solid)
			)
			(layer "B.Fab")
		)
		(fp_line
			(start -0.494 0.25)
			(end -0.494 -0.248)
			(stroke
				(width 0.15)
				(type solid)
			)
			(layer "B.Fab")
		)
		(fp_text user "Author: Antmicro"
			(at -0.932 -4.17 -90)
			(layer "B.Fab")
			(hide yes)
			(effects
				(font
					(size 0.7 0.7)
					(thickness 0.15)
				)
				(justify left bottom mirror)
			)
		)
		(fp_text user "License: Apache-2.0"
			(at -0.932 -5.17 -90)
			(layer "B.Fab")
			(hide yes)
			(effects
				(font
					(size 0.7 0.7)
					(thickness 0.15)
				)
				(justify left bottom mirror)
			)
		)
		(fp_text user "${REFERENCE}"
			(at -0.932 -3.168 -90)
			(layer "B.Fab")
			(hide yes)
			(effects
				(font
					(size 0.7 0.7)
					(thickness 0.15)
				)
				(justify left bottom mirror)
			)
		)
		(pad "1" smd roundrect
			(at -0.48 0 90)
			(size 0.59 0.64)
			(layers "B.Cu" "B.Paste" "B.Mask")
			(roundrect_rratio 0.25)
			(net 1 "GND")
			(pintype "passive")
		)
		(pad "2" smd roundrect
			(at 0.48 0 90)
			(size 0.59 0.64)
			(layers "B.Cu" "B.Paste" "B.Mask")
			(roundrect_rratio 0.25)
			(net 179 "Net-(D61-A)")
			(pintype "passive")
		)
	)
	(footprint "antmicro-footprints:C_0402_1005Metric"
		(layer "B.Cu")
		(at 73.5 107.2)
		(descr "Capacitor SMD 0402")
		(tags "capacitor SMD 0402")
		(property "Reference" "C58"
			(at -0.15 2.28 180)
			(layer "B.SilkS")
			(effects
				(font
					(size 0.7 0.7)
					(thickness 0.15)
				)
				(justify left bottom mirror)
			)
		)
		(property "Value" "C_100n_0402"
			(at 0 -1.4 180)
			(layer "B.Fab")
			(effects
				(font
					(size 0.7 0.7)
					(thickness 0.15)
				)
				(justify left bottom mirror)
			)
		)
		(property "Footprint" "antmicro-footprints:C_0402_1005Metric"
			(at 0 0 0)
			(layer "F.Fab")
			(hide yes)
			(effects
				(font
					(size 1.27 1.27)
					(thickness 0.15)
				)
			)
		)
		(property "Datasheet" "https://www.murata.com/products/productdetail?partno=GRM155R61H104KE14%23"
			(at 0 0 0)
			(layer "F.Fab")
			(hide yes)
			(effects
				(font
					(size 1.27 1.27)
					(thickness 0.15)
				)
			)
		)
		(property "Author" "Antmicro"
			(at 0 0 0)
			(layer "B.Fab")
			(hide yes)
			(effects
				(font
					(size 1 1)
					(thickness 0.15)
				)
				(justify mirror)
			)
		)
		(property "Dielectric" "X5R"
			(at 0 0 0)
			(layer "B.Fab")
			(hide yes)
			(effects
				(font
					(size 1 1)
					(thickness 0.15)
				)
				(justify mirror)
			)
		)
		(property "License" "Apache-2.0"
			(at 0 0 0)
			(layer "B.Fab")
			(hide yes)
			(effects
				(font
					(size 1 1)
					(thickness 0.15)
				)
				(justify mirror)
			)
		)
		(property "MPN" "GRM155R61H104KE14D"
			(at 0 0 0)
			(layer "B.Fab")
			(hide yes)
			(effects
				(font
					(size 1 1)
					(thickness 0.15)
				)
				(justify mirror)
			)
		)
		(property "Manufacturer" "Murata"
			(at 0 0 0)
			(layer "B.Fab")
			(hide yes)
			(effects
				(font
					(size 1 1)
					(thickness 0.15)
				)
				(justify mirror)
			)
		)
		(property "Val" "100n"
			(at 0 0 0)
			(layer "B.Fab")
			(hide yes)
			(effects
				(font
					(size 1 1)
					(thickness 0.15)
				)
				(justify mirror)
			)
		)
		(property "Voltage" "50V"
			(at 0 0 0)
			(layer "B.Fab")
			(hide yes)
			(effects
				(font
					(size 1 1)
					(thickness 0.15)
				)
				(justify mirror)
			)
		)
		(sheetname "USB Debug, DP")
		(sheetfile "usb.kicad_sch")
		(attr smd)
		(fp_rect
			(start -0.925 0.47)
			(end 0.925 -0.47)
			(stroke
				(width 0.05)
				(type default)
			)
			(fill none)
			(layer "B.CrtYd")
		)
		(fp_line
			(start -0.494 -0.248)
			(end 0.504 -0.248)
			(stroke
				(width 0.15)
				(type solid)
			)
			(layer "B.Fab")
		)
		(fp_line
			(start -0.494 0.25)
			(end -0.494 -0.248)
			(stroke
				(width 0.15)
				(type solid)
			)
			(layer "B.Fab")
		)
		(fp_line
			(start 0.504 -0.248)
			(end 0.504 0.25)
			(stroke
				(width 0.15)
				(type solid)
			)
			(layer "B.Fab")
		)
		(fp_line
			(start 0.504 0.25)
			(end -0.494 0.25)
			(stroke
				(width 0.15)
				(type solid)
			)
			(layer "B.Fab")
		)
		(fp_text user "License: Apache-2.0"
			(at -0.932 -5.17 180)
			(layer "B.Fab")
			(hide yes)
			(effects
				(font
					(size 0.7 0.7)
					(thickness 0.15)
				)
				(justify left bottom mirror)
			)
		)
		(fp_text user "${REFERENCE}"
			(at -0.932 -3.168 180)
			(layer "B.Fab")
			(hide yes)
			(effects
				(font
					(size 0.7 0.7)
					(thickness 0.15)
				)
				(justify left bottom mirror)
			)
		)
		(fp_text user "Author: Antmicro"
			(at -0.932 -4.17 180)
			(layer "B.Fab")
			(hide yes)
			(effects
				(font
					(size 0.7 0.7)
					(thickness 0.15)
				)
				(justify left bottom mirror)
			)
		)
		(pad "1" smd roundrect
			(at -0.48 0)
			(size 0.59 0.64)
			(layers "B.Cu" "B.Paste" "B.Mask")
			(roundrect_rratio 0.25)
			(net 481 "USBPD2_HV")
			(pintype "passive")
		)
		(pad "2" smd roundrect
			(at 0.48 0)
			(size 0.59 0.64)
			(layers "B.Cu" "B.Paste" "B.Mask")
			(roundrect_rratio 0.25)
			(net 1 "GND")
			(pintype "passive")
		)
	)
	(footprint "antmicro-footprints:R_0402_1005Metric"
		(layer "B.Cu")
		(at 61.8 78.95)
		(descr "Resistor SMD 0402")
		(tags "resistor SMD 0402")
		(property "Reference" "R258"
			(at 1.9 1.25 180)
			(layer "B.SilkS")
			(effects
				(font
					(size 0.7 0.7)
					(thickness 0.15)
				)
				(justify left bottom mirror)
			)
		)
		(property "Value" "R_200k_0402"
			(at 0 -1.4 180)
			(layer "B.Fab")
			(effects
				(font
					(size 0.7 0.7)
					(thickness 0.15)
				)
				(justify left bottom mirror)
			)
		)
		(property "Footprint" "antmicro-footprints:R_0402_1005Metric"
			(at 0 0 0)
			(layer "F.Fab")
			(hide yes)
			(effects
				(font
					(size 1.27 1.27)
					(thickness 0.15)
				)
			)
		)
		(property "Datasheet" "https://www.bourns.com/docs/product-datasheets/cr.pdf"
			(at 0 0 0)
			(layer "F.Fab")
			(hide yes)
			(effects
				(font
					(size 1.27 1.27)
					(thickness 0.15)
				)
			)
		)
		(property "Author" "Antmicro"
			(at 0 0 0)
			(layer "B.Fab")
			(hide yes)
			(effects
				(font
					(size 1 1)
					(thickness 0.15)
				)
				(justify mirror)
			)
		)
		(property "License" "Apache-2.0"
			(at 0 0 0)
			(layer "B.Fab")
			(hide yes)
			(effects
				(font
					(size 1 1)
					(thickness 0.15)
				)
				(justify mirror)
			)
		)
		(property "MPN" "CR0402-FX-2003GLF"
			(at 0 0 0)
			(layer "B.Fab")
			(hide yes)
			(effects
				(font
					(size 1 1)
					(thickness 0.15)
				)
				(justify mirror)
			)
		)
		(property "Manufacturer" "Bourns"
			(at 0 0 0)
			(layer "B.Fab")
			(hide yes)
			(effects
				(font
					(size 1 1)
					(thickness 0.15)
				)
				(justify mirror)
			)
		)
		(property "Tolerance" "1%"
			(at 0 0 0)
			(layer "B.Fab")
			(hide yes)
			(effects
				(font
					(size 1 1)
					(thickness 0.15)
				)
				(justify mirror)
			)
		)
		(property "Val" "200k"
			(at 0 0 0)
			(layer "B.Fab")
			(hide yes)
			(effects
				(font
					(size 1 1)
					(thickness 0.15)
				)
				(justify mirror)
			)
		)
		(sheetname "Supply")
		(sheetfile "supply.kicad_sch")
		(attr smd)
		(fp_rect
			(start -0.925 0.47)
			(end 0.925 -0.47)
			(stroke
				(width 0.05)
				(type default)
			)
			(fill none)
			(layer "B.CrtYd")
		)
		(fp_rect
			(start -0.5 0.25)
			(end 0.5 -0.25)
			(stroke
				(width 0.15)
				(type solid)
			)
			(fill none)
			(layer "B.Fab")
		)
		(fp_text user "${REFERENCE}"
			(at -0.95 -3.168 180)
			(layer "B.Fab")
			(hide yes)
			(effects
				(font
					(size 0.7 0.7)
					(thickness 0.15)
				)
				(justify left bottom mirror)
			)
		)
		(fp_text user "Author: Antmicro"
			(at -0.95 -4.169 180)
			(layer "B.Fab")
			(hide yes)
			(effects
				(font
					(size 0.7 0.7)
					(thickness 0.15)
				)
				(justify left bottom mirror)
			)
		)
		(fp_text user "License: Apache-2.0"
			(at -0.95 -5.169 180)
			(layer "B.Fab")
			(hide yes)
			(effects
				(font
					(size 0.7 0.7)
					(thickness 0.15)
				)
				(justify left bottom mirror)
			)
		)
		(pad "1" smd roundrect
			(at -0.48 0)
			(size 0.59 0.64)
			(layers "B.Cu" "B.Paste" "B.Mask")
			(roundrect_rratio 0.25)
			(net 137 "Net-(D36-A)")
			(pintype "passive")
		)
		(pad "2" smd roundrect
			(at 0.48 0)
			(size 0.59 0.64)
			(layers "B.Cu" "B.Paste" "B.Mask")
			(roundrect_rratio 0.25)
			(net 688 "Net-(U38-CLK)")
			(pintype "passive")
		)
	)
	(footprint "antmicro-footprints:C_0805_2012Metric"
		(layer "B.Cu")
		(at 62.675 92.95)
		(descr "Capacitor SMD 0805")
		(tags "capacitor SMD 0805")
		(property "Reference" "C5"
			(at -0.715 1 0)
			(layer "B.SilkS")
			(effects
				(font
					(size 0.7 0.7)
					(thickness 0.15)
				)
				(justify right top mirror)
			)
		)
		(property "Value" "C_22u_25V_0805"
			(at -2.055717 -1.963152 0)
			(layer "B.Fab")
			(effects
				(font
					(size 0.7 0.7)
					(thickness 0.15)
				)
				(justify right top mirror)
			)
		)
		(property "Footprint" "antmicro-footprints:C_0805_2012Metric"
			(at 0 0 0)
			(layer "B.Fab")
			(hide yes)
			(effects
				(font
					(size 1.27 1.27)
					(thickness 0.15)
				)
				(justify mirror)
			)
		)
		(property "Datasheet" "https://product.samsungsem.com/mlcc/CL21A226MAYNNN.do"
			(at 0 0 0)
			(layer "B.Fab")
			(hide yes)
			(effects
				(font
					(size 1.27 1.27)
					(thickness 0.15)
				)
				(justify mirror)
			)
		)
		(property "Author" "Antmicro"
			(at 0 0 0)
			(layer "B.Fab")
			(hide yes)
			(effects
				(font
					(size 1 1)
					(thickness 0.15)
				)
				(justify mirror)
			)
		)
		(property "Dielectric" "X5R"
			(at 0 0 0)
			(layer "B.Fab")
			(hide yes)
			(effects
				(font
					(size 1 1)
					(thickness 0.15)
				)
				(justify mirror)
			)
		)
		(property "License" "Apache-2.0"
			(at 0 0 0)
			(layer "B.Fab")
			(hide yes)
			(effects
				(font
					(size 1 1)
					(thickness 0.15)
				)
				(justify mirror)
			)
		)
		(property "MPN" "CL21A226MAYNNNE"
			(at 0 0 0)
			(layer "B.Fab")
			(hide yes)
			(effects
				(font
					(size 1 1)
					(thickness 0.15)
				)
				(justify mirror)
			)
		)
		(property "Manufacturer" "Samsung Electro-Mechanics"
			(at 0 0 0)
			(layer "B.Fab")
			(hide yes)
			(effects
				(font
					(size 1 1)
					(thickness 0.15)
				)
				(justify mirror)
			)
		)
		(property "Public" "False"
			(at 0 0 0)
			(layer "B.Fab")
			(hide yes)
			(effects
				(font
					(size 1 1)
					(thickness 0.15)
				)
				(justify mirror)
			)
		)
		(property "Val" "22u"
			(at 0 0 0)
			(layer "B.Fab")
			(hide yes)
			(effects
				(font
					(size 1 1)
					(thickness 0.15)
				)
				(justify mirror)
			)
		)
		(property "Voltage" "25V"
			(at 0 0 0)
			(layer "B.Fab")
			(hide yes)
			(effects
				(font
					(size 1 1)
					(thickness 0.15)
				)
				(justify mirror)
			)
		)
		(sheetname "Supply")
		(sheetfile "supply.kicad_sch")
		(attr smd)
		(fp_line
			(start 0.3 -0.7)
			(end -0.3 -0.7)
			(stroke
				(width 0.15)
				(type solid)
			)
			(layer "B.SilkS")
		)
		(fp_line
			(start 0.3 0.7)
			(end -0.3 0.7)
			(stroke
				(width 0.15)
				(type solid)
			)
			(layer "B.SilkS")
		)
		(fp_rect
			(start 1.95 0.9)
			(end -1.95 -0.9)
			(stroke
				(width 0.05)
				(type default)
			)
			(fill none)
			(layer "B.CrtYd")
		)
		(fp_rect
			(start -0.95 0.675)
			(end 0.95 -0.675)
			(stroke
				(width 0.15)
				(type solid)
			)
			(fill none)
			(layer "B.Fab")
		)
		(fp_text user "License: Apache-2.0"
			(at -1.9 -4.947 0)
			(layer "B.Fab")
			(hide yes)
			(effects
				(font
					(size 0.7 0.7)
					(thickness 0.15)
				)
				(justify right top mirror)
			)
		)
		(fp_text user "Author: Antmicro"
			(at -1.9 -5.947 0)
			(layer "B.Fab")
			(hide yes)
			(effects
				(font
					(size 0.7 0.7)
					(thickness 0.15)
				)
				(justify right top mirror)
			)
		)
		(fp_text user "${REFERENCE}"
			(at -1.9 -3.947 0)
			(layer "B.Fab")
			(hide yes)
			(effects
				(font
					(size 0.7 0.7)
					(thickness 0.15)
				)
				(justify right top mirror)
			)
		)
		(pad "1" smd roundrect
			(at -1.1 0)
			(size 1.2 1.3)
			(layers "B.Cu" "B.Paste" "B.Mask")
			(roundrect_rratio 0.25)
			(net 1 "GND")
			(pintype "passive")
		)
		(pad "2" smd roundrect
			(at 1.1 0)
			(size 1.2 1.3)
			(layers "B.Cu" "B.Paste" "B.Mask")
			(roundrect_rratio 0.25)
			(net 115 "VCC")
			(pintype "passive")
		)
	)
	(footprint "antmicro-footprints:R_0402_1005Metric"
		(layer "B.Cu")
		(at 57.55 113.45 180)
		(descr "Resistor SMD 0402")
		(tags "resistor SMD 0402")
		(property "Reference" "R59"
			(at -3.08 -0.31 0)
			(layer "B.SilkS")
			(effects
				(font
					(size 0.7 0.7)
					(thickness 0.15)
				)
				(justify left bottom mirror)
			)
		)
		(property "Value" "R_0R_0402"
			(at 0 -1.4 0)
			(layer "B.Fab")
			(effects
				(font
					(size 0.7 0.7)
					(thickness 0.15)
				)
				(justify left bottom mirror)
			)
		)
		(property "Footprint" "antmicro-footprints:R_0402_1005Metric"
			(at 0 0 180)
			(layer "F.Fab")
			(hide yes)
			(effects
				(font
					(size 1.27 1.27)
					(thickness 0.15)
				)
			)
		)
		(property "Datasheet" "https://industrial.panasonic.com/cdbs/www-data/pdf/RDA0000/AOA0000C301.pdf"
			(at 0 0 180)
			(layer "F.Fab")
			(hide yes)
			(effects
				(font
					(size 1.27 1.27)
					(thickness 0.15)
				)
			)
		)
		(property "Author" "Antmicro"
			(at 115.1 226.9 0)
			(layer "B.Fab")
			(hide yes)
			(effects
				(font
					(size 1 1)
					(thickness 0.15)
				)
				(justify mirror)
			)
		)
		(property "Current" "1A"
			(at 115.1 226.9 0)
			(layer "B.Fab")
			(hide yes)
			(effects
				(font
					(size 1 1)
					(thickness 0.15)
				)
				(justify mirror)
			)
		)
		(property "License" "Apache-2.0"
			(at 115.1 226.9 0)
			(layer "B.Fab")
			(hide yes)
			(effects
				(font
					(size 1 1)
					(thickness 0.15)
				)
				(justify mirror)
			)
		)
		(property "MPN" "ERJ2GE0R00X"
			(at 115.1 226.9 0)
			(layer "B.Fab")
			(hide yes)
			(effects
				(font
					(size 1 1)
					(thickness 0.15)
				)
				(justify mirror)
			)
		)
		(property "Manufacturer" "Panasonic"
			(at 115.1 226.9 0)
			(layer "B.Fab")
			(hide yes)
			(effects
				(font
					(size 1 1)
					(thickness 0.15)
				)
				(justify mirror)
			)
		)
		(property "Tolerance" ""
			(at 115.1 226.9 0)
			(layer "B.Fab")
			(hide yes)
			(effects
				(font
					(size 1 1)
					(thickness 0.15)
				)
				(justify mirror)
			)
		)
		(property "Val" "0R"
			(at 115.1 226.9 0)
			(layer "B.Fab")
			(hide yes)
			(effects
				(font
					(size 1 1)
					(thickness 0.15)
				)
				(justify mirror)
			)
		)
		(sheetname "USB Debug, DP")
		(sheetfile "usb.kicad_sch")
		(attr smd exclude_from_pos_files exclude_from_bom dnp)
		(fp_rect
			(start -0.925 0.47)
			(end 0.925 -0.47)
			(stroke
				(width 0.05)
				(type default)
			)
			(fill none)
			(layer "B.CrtYd")
		)
		(fp_rect
			(start -0.5 0.25)
			(end 0.5 -0.25)
			(stroke
				(width 0.15)
				(type solid)
			)
			(fill none)
			(layer "B.Fab")
		)
		(fp_text user "${REFERENCE}"
			(at -0.95 -3.168 0)
			(layer "B.Fab")
			(hide yes)
			(effects
				(font
					(size 0.7 0.7)
					(thickness 0.15)
				)
				(justify left bottom mirror)
			)
		)
		(fp_text user "Author: Antmicro"
			(at -0.95 -4.169 0)
			(layer "B.Fab")
			(hide yes)
			(effects
				(font
					(size 0.7 0.7)
					(thickness 0.15)
				)
				(justify left bottom mirror)
			)
		)
		(fp_text user "License: Apache-2.0"
			(at -0.95 -5.169 0)
			(layer "B.Fab")
			(hide yes)
			(effects
				(font
					(size 0.7 0.7)
					(thickness 0.15)
				)
				(justify left bottom mirror)
			)
		)
		(pad "1" smd roundrect
			(at -0.48 0 180)
			(size 0.59 0.64)
			(layers "B.Cu" "B.Paste" "B.Mask")
			(roundrect_rratio 0.25)
			(net 465 "unconnected-(R59-Pad1)")
			(pintype "passive+no_connect")
		)
		(pad "2" smd roundrect
			(at 0.48 0 180)
			(size 0.59 0.64)
			(layers "B.Cu" "B.Paste" "B.Mask")
			(roundrect_rratio 0.25)
			(net 649 "Net-(U5-~{CTS})")
			(pintype "passive")
		)
	)
	(footprint "antmicro-footprints:R_0402_1005Metric"
		(layer "B.Cu")
		(at 86.6 108.2 180)
		(descr "Resistor SMD 0402")
		(tags "resistor SMD 0402")
		(property "Reference" "R218"
			(at 0.8 -0.475 0)
			(layer "B.SilkS")
			(effects
				(font
					(size 0.7 0.7)
					(thickness 0.15)
				)
				(justify left bottom mirror)
			)
		)
		(property "Value" "R_0R_0402"
			(at 0 -1.4 0)
			(layer "B.Fab")
			(effects
				(font
					(size 0.7 0.7)
					(thickness 0.15)
				)
				(justify left bottom mirror)
			)
		)
		(property "Footprint" "antmicro-footprints:R_0402_1005Metric"
			(at 0 0 180)
			(layer "F.Fab")
			(hide yes)
			(effects
				(font
					(size 1.27 1.27)
					(thickness 0.15)
				)
			)
		)
		(property "Datasheet" "https://industrial.panasonic.com/cdbs/www-data/pdf/RDA0000/AOA0000C301.pdf"
			(at 0 0 180)
			(layer "F.Fab")
			(hide yes)
			(effects
				(font
					(size 1.27 1.27)
					(thickness 0.15)
				)
			)
		)
		(property "Author" "Antmicro"
			(at 173.2 216.4 0)
			(layer "B.Fab")
			(hide yes)
			(effects
				(font
					(size 1 1)
					(thickness 0.15)
				)
				(justify mirror)
			)
		)
		(property "Current" "1A"
			(at 173.2 216.4 0)
			(layer "B.Fab")
			(hide yes)
			(effects
				(font
					(size 1 1)
					(thickness 0.15)
				)
				(justify mirror)
			)
		)
		(property "License" "Apache-2.0"
			(at 173.2 216.4 0)
			(layer "B.Fab")
			(hide yes)
			(effects
				(font
					(size 1 1)
					(thickness 0.15)
				)
				(justify mirror)
			)
		)
		(property "MPN" "ERJ2GE0R00X"
			(at 173.2 216.4 0)
			(layer "B.Fab")
			(hide yes)
			(effects
				(font
					(size 1 1)
					(thickness 0.15)
				)
				(justify mirror)
			)
		)
		(property "Manufacturer" "Panasonic"
			(at 173.2 216.4 0)
			(layer "B.Fab")
			(hide yes)
			(effects
				(font
					(size 1 1)
					(thickness 0.15)
				)
				(justify mirror)
			)
		)
		(property "Tolerance" ""
			(at 173.2 216.4 0)
			(layer "B.Fab")
			(hide yes)
			(effects
				(font
					(size 1 1)
					(thickness 0.15)
				)
				(justify mirror)
			)
		)
		(property "Val" "0R"
			(at 173.2 216.4 0)
			(layer "B.Fab")
			(hide yes)
			(effects
				(font
					(size 1 1)
					(thickness 0.15)
				)
				(justify mirror)
			)
		)
		(sheetname "Peripherals")
		(sheetfile "peripherals.kicad_sch")
		(attr smd)
		(fp_rect
			(start -0.925 0.47)
			(end 0.925 -0.47)
			(stroke
				(width 0.05)
				(type default)
			)
			(fill none)
			(layer "B.CrtYd")
		)
		(fp_rect
			(start -0.5 0.25)
			(end 0.5 -0.25)
			(stroke
				(width 0.15)
				(type solid)
			)
			(fill none)
			(layer "B.Fab")
		)
		(fp_text user "License: Apache-2.0"
			(at -0.95 -5.169 0)
			(layer "B.Fab")
			(hide yes)
			(effects
				(font
					(size 0.7 0.7)
					(thickness 0.15)
				)
				(justify left bottom mirror)
			)
		)
		(fp_text user "${REFERENCE}"
			(at -0.95 -3.168 0)
			(layer "B.Fab")
			(hide yes)
			(effects
				(font
					(size 0.7 0.7)
					(thickness 0.15)
				)
				(justify left bottom mirror)
			)
		)
		(fp_text user "Author: Antmicro"
			(at -0.95 -4.169 0)
			(layer "B.Fab")
			(hide yes)
			(effects
				(font
					(size 0.7 0.7)
					(thickness 0.15)
				)
				(justify left bottom mirror)
			)
		)
		(pad "1" smd roundrect
			(at -0.48 0 180)
			(size 0.59 0.64)
			(layers "B.Cu" "B.Paste" "B.Mask")
			(roundrect_rratio 0.25)
			(net 1 "GND")
			(pintype "passive")
		)
		(pad "2" smd roundrect
			(at 0.48 0 180)
			(size 0.59 0.64)
			(layers "B.Cu" "B.Paste" "B.Mask")
			(roundrect_rratio 0.25)
			(net 352 "/Peripherals/GPIOEX_ADDR")
			(pintype "passive")
		)
	)
	(footprint "antmicro-footprints:R_0402_1005Metric"
		(layer "B.Cu")
		(at 111.6 90.02 90)
		(descr "Resistor SMD 0402")
		(tags "resistor SMD 0402")
		(property "Reference" "R16"
			(at 1.02 1.41 -90)
			(layer "B.SilkS")
			(effects
				(font
					(size 0.7 0.7)
					(thickness 0.15)
				)
				(justify left bottom mirror)
			)
		)
		(property "Value" "R_0R_0402"
			(at 0 -1.4 -90)
			(layer "B.Fab")
			(effects
				(font
					(size 0.7 0.7)
					(thickness 0.15)
				)
				(justify left bottom mirror)
			)
		)
		(property "Footprint" "antmicro-footprints:R_0402_1005Metric"
			(at 0 0 90)
			(layer "F.Fab")
			(hide yes)
			(effects
				(font
					(size 1.27 1.27)
					(thickness 0.15)
				)
			)
		)
		(property "Datasheet" "https://industrial.panasonic.com/cdbs/www-data/pdf/RDA0000/AOA0000C301.pdf"
			(at 0 0 90)
			(layer "F.Fab")
			(hide yes)
			(effects
				(font
					(size 1.27 1.27)
					(thickness 0.15)
				)
			)
		)
		(property "Author" "Antmicro"
			(at 201.62 -21.58 0)
			(layer "B.Fab")
			(hide yes)
			(effects
				(font
					(size 1 1)
					(thickness 0.15)
				)
				(justify mirror)
			)
		)
		(property "Current" "1A"
			(at 201.62 -21.58 0)
			(layer "B.Fab")
			(hide yes)
			(effects
				(font
					(size 1 1)
					(thickness 0.15)
				)
				(justify mirror)
			)
		)
		(property "License" "Apache-2.0"
			(at 201.62 -21.58 0)
			(layer "B.Fab")
			(hide yes)
			(effects
				(font
					(size 1 1)
					(thickness 0.15)
				)
				(justify mirror)
			)
		)
		(property "MPN" "ERJ2GE0R00X"
			(at 201.62 -21.58 0)
			(layer "B.Fab")
			(hide yes)
			(effects
				(font
					(size 1 1)
					(thickness 0.15)
				)
				(justify mirror)
			)
		)
		(property "Manufacturer" "Panasonic"
			(at 201.62 -21.58 0)
			(layer "B.Fab")
			(hide yes)
			(effects
				(font
					(size 1 1)
					(thickness 0.15)
				)
				(justify mirror)
			)
		)
		(property "Tolerance" ""
			(at 201.62 -21.58 0)
			(layer "B.Fab")
			(hide yes)
			(effects
				(font
					(size 1 1)
					(thickness 0.15)
				)
				(justify mirror)
			)
		)
		(property "Val" "0R"
			(at 201.62 -21.58 0)
			(layer "B.Fab")
			(hide yes)
			(effects
				(font
					(size 1 1)
					(thickness 0.15)
				)
				(justify mirror)
			)
		)
		(sheetname "M.2")
		(sheetfile "m-2.kicad_sch")
		(attr smd)
		(fp_rect
			(start -0.925 0.47)
			(end 0.925 -0.47)
			(stroke
				(width 0.05)
				(type default)
			)
			(fill none)
			(layer "B.CrtYd")
		)
		(fp_rect
			(start -0.5 0.25)
			(end 0.5 -0.25)
			(stroke
				(width 0.15)
				(type solid)
			)
			(fill none)
			(layer "B.Fab")
		)
		(fp_text user "Author: Antmicro"
			(at -0.95 -4.169 -90)
			(layer "B.Fab")
			(hide yes)
			(effects
				(font
					(size 0.7 0.7)
					(thickness 0.15)
				)
				(justify left bottom mirror)
			)
		)
		(fp_text user "License: Apache-2.0"
			(at -0.95 -5.169 -90)
			(layer "B.Fab")
			(hide yes)
			(effects
				(font
					(size 0.7 0.7)
					(thickness 0.15)
				)
				(justify left bottom mirror)
			)
		)
		(fp_text user "${REFERENCE}"
			(at -0.95 -3.168 -90)
			(layer "B.Fab")
			(hide yes)
			(effects
				(font
					(size 0.7 0.7)
					(thickness 0.15)
				)
				(justify left bottom mirror)
			)
		)
		(pad "1" smd roundrect
			(at -0.48 0 90)
			(size 0.59 0.64)
			(layers "B.Cu" "B.Paste" "B.Mask")
			(roundrect_rratio 0.25)
			(net 561 "/M.2/PCIE_WAKE_SEL0")
			(pintype "passive")
		)
		(pad "2" smd roundrect
			(at 0.48 0 90)
			(size 0.59 0.64)
			(layers "B.Cu" "B.Paste" "B.Mask")
			(roundrect_rratio 0.25)
			(net 249 "/M.2/~{M2_M_PEWAKE0}")
			(pintype "passive")
		)
	)
	(footprint "antmicro-footprints:R_0402_1005Metric"
		(layer "B.Cu")
		(at 46.9 86.6375 180)
		(descr "Resistor SMD 0402")
		(tags "resistor SMD 0402")
		(property "Reference" "R129"
			(at -0.325 3.4375 0)
			(layer "B.SilkS")
			(effects
				(font
					(size 0.7 0.7)
					(thickness 0.15)
				)
				(justify left bottom mirror)
			)
		)
		(property "Value" "R_0R_0402"
			(at 0 -1.4 0)
			(layer "B.Fab")
			(effects
				(font
					(size 0.7 0.7)
					(thickness 0.15)
				)
				(justify left bottom mirror)
			)
		)
		(property "Footprint" "antmicro-footprints:R_0402_1005Metric"
			(at 0 0 180)
			(layer "F.Fab")
			(hide yes)
			(effects
				(font
					(size 1.27 1.27)
					(thickness 0.15)
				)
			)
		)
		(property "Datasheet" "https://industrial.panasonic.com/cdbs/www-data/pdf/RDA0000/AOA0000C301.pdf"
			(at 0 0 180)
			(layer "F.Fab")
			(hide yes)
			(effects
				(font
					(size 1.27 1.27)
					(thickness 0.15)
				)
			)
		)
		(property "Author" "Antmicro"
			(at 93.8 173.275 0)
			(layer "B.Fab")
			(hide yes)
			(effects
				(font
					(size 1 1)
					(thickness 0.15)
				)
				(justify mirror)
			)
		)
		(property "Current" "1A"
			(at 93.8 173.275 0)
			(layer "B.Fab")
			(hide yes)
			(effects
				(font
					(size 1 1)
					(thickness 0.15)
				)
				(justify mirror)
			)
		)
		(property "License" "Apache-2.0"
			(at 93.8 173.275 0)
			(layer "B.Fab")
			(hide yes)
			(effects
				(font
					(size 1 1)
					(thickness 0.15)
				)
				(justify mirror)
			)
		)
		(property "MPN" "ERJ2GE0R00X"
			(at 93.8 173.275 0)
			(layer "B.Fab")
			(hide yes)
			(effects
				(font
					(size 1 1)
					(thickness 0.15)
				)
				(justify mirror)
			)
		)
		(property "Manufacturer" "Panasonic"
			(at 93.8 173.275 0)
			(layer "B.Fab")
			(hide yes)
			(effects
				(font
					(size 1 1)
					(thickness 0.15)
				)
				(justify mirror)
			)
		)
		(property "Tolerance" ""
			(at 93.8 173.275 0)
			(layer "B.Fab")
			(hide yes)
			(effects
				(font
					(size 1 1)
					(thickness 0.15)
				)
				(justify mirror)
			)
		)
		(property "Val" "0R"
			(at 93.8 173.275 0)
			(layer "B.Fab")
			(hide yes)
			(effects
				(font
					(size 1 1)
					(thickness 0.15)
				)
				(justify mirror)
			)
		)
		(sheetname "Ethernet")
		(sheetfile "ethernet.kicad_sch")
		(attr smd)
		(fp_rect
			(start -0.925 0.47)
			(end 0.925 -0.47)
			(stroke
				(width 0.05)
				(type default)
			)
			(fill none)
			(layer "B.CrtYd")
		)
		(fp_rect
			(start -0.5 0.25)
			(end 0.5 -0.25)
			(stroke
				(width 0.15)
				(type solid)
			)
			(fill none)
			(layer "B.Fab")
		)
		(fp_text user "${REFERENCE}"
			(at -0.95 -3.168 0)
			(layer "B.Fab")
			(hide yes)
			(effects
				(font
					(size 0.7 0.7)
					(thickness 0.15)
				)
				(justify left bottom mirror)
			)
		)
		(fp_text user "License: Apache-2.0"
			(at -0.95 -5.169 0)
			(layer "B.Fab")
			(hide yes)
			(effects
				(font
					(size 0.7 0.7)
					(thickness 0.15)
				)
				(justify left bottom mirror)
			)
		)
		(fp_text user "Author: Antmicro"
			(at -0.95 -4.169 0)
			(layer "B.Fab")
			(hide yes)
			(effects
				(font
					(size 0.7 0.7)
					(thickness 0.15)
				)
				(justify left bottom mirror)
			)
		)
		(pad "1" smd roundrect
			(at -0.48 0 180)
			(size 0.59 0.64)
			(layers "B.Cu" "B.Paste" "B.Mask")
			(roundrect_rratio 0.25)
			(net 567 "/Ethernet/MPS_DUTY")
			(pintype "passive")
		)
		(pad "2" smd roundrect
			(at 0.48 0 180)
			(size 0.59 0.64)
			(layers "B.Cu" "B.Paste" "B.Mask")
			(roundrect_rratio 0.25)
			(net 499 "/Ethernet/VSS")
			(pintype "passive")
		)
	)
	(footprint "antmicro-footprints:R_0402_1005Metric"
		(layer "B.Cu")
		(at 73.975 110.625 90)
		(descr "Resistor SMD 0402")
		(tags "resistor SMD 0402")
		(property "Reference" "R75"
			(at 0.125 -0.35 -90)
			(layer "B.SilkS")
			(effects
				(font
					(size 0.7 0.7)
					(thickness 0.15)
				)
				(justify left bottom mirror)
			)
		)
		(property "Value" "R_0R_0402"
			(at 0 -1.4 -90)
			(layer "B.Fab")
			(effects
				(font
					(size 0.7 0.7)
					(thickness 0.15)
				)
				(justify left bottom mirror)
			)
		)
		(property "Footprint" "antmicro-footprints:R_0402_1005Metric"
			(at 0 0 90)
			(layer "F.Fab")
			(hide yes)
			(effects
				(font
					(size 1.27 1.27)
					(thickness 0.15)
				)
			)
		)
		(property "Datasheet" "https://industrial.panasonic.com/cdbs/www-data/pdf/RDA0000/AOA0000C301.pdf"
			(at 0 0 90)
			(layer "F.Fab")
			(hide yes)
			(effects
				(font
					(size 1.27 1.27)
					(thickness 0.15)
				)
			)
		)
		(property "Author" "Antmicro"
			(at 184.6 36.65 0)
			(layer "B.Fab")
			(hide yes)
			(effects
				(font
					(size 1 1)
					(thickness 0.15)
				)
				(justify mirror)
			)
		)
		(property "Current" "1A"
			(at 184.6 36.65 0)
			(layer "B.Fab")
			(hide yes)
			(effects
				(font
					(size 1 1)
					(thickness 0.15)
				)
				(justify mirror)
			)
		)
		(property "License" "Apache-2.0"
			(at 184.6 36.65 0)
			(layer "B.Fab")
			(hide yes)
			(effects
				(font
					(size 1 1)
					(thickness 0.15)
				)
				(justify mirror)
			)
		)
		(property "MPN" "ERJ2GE0R00X"
			(at 184.6 36.65 0)
			(layer "B.Fab")
			(hide yes)
			(effects
				(font
					(size 1 1)
					(thickness 0.15)
				)
				(justify mirror)
			)
		)
		(property "Manufacturer" "Panasonic"
			(at 184.6 36.65 0)
			(layer "B.Fab")
			(hide yes)
			(effects
				(font
					(size 1 1)
					(thickness 0.15)
				)
				(justify mirror)
			)
		)
		(property "Tolerance" ""
			(at 184.6 36.65 0)
			(layer "B.Fab")
			(hide yes)
			(effects
				(font
					(size 1 1)
					(thickness 0.15)
				)
				(justify mirror)
			)
		)
		(property "Val" "0R"
			(at 184.6 36.65 0)
			(layer "B.Fab")
			(hide yes)
			(effects
				(font
					(size 1 1)
					(thickness 0.15)
				)
				(justify mirror)
			)
		)
		(sheetname "USB Debug, DP")
		(sheetfile "usb.kicad_sch")
		(attr smd)
		(fp_rect
			(start -0.925 0.47)
			(end 0.925 -0.47)
			(stroke
				(width 0.05)
				(type default)
			)
			(fill none)
			(layer "B.CrtYd")
		)
		(fp_rect
			(start -0.5 0.25)
			(end 0.5 -0.25)
			(stroke
				(width 0.15)
				(type solid)
			)
			(fill none)
			(layer "B.Fab")
		)
		(fp_text user "${REFERENCE}"
			(at -0.95 -3.168 -90)
			(layer "B.Fab")
			(hide yes)
			(effects
				(font
					(size 0.7 0.7)
					(thickness 0.15)
				)
				(justify left bottom mirror)
			)
		)
		(fp_text user "License: Apache-2.0"
			(at -0.95 -5.169 -90)
			(layer "B.Fab")
			(hide yes)
			(effects
				(font
					(size 0.7 0.7)
					(thickness 0.15)
				)
				(justify left bottom mirror)
			)
		)
		(fp_text user "Author: Antmicro"
			(at -0.95 -4.169 -90)
			(layer "B.Fab")
			(hide yes)
			(effects
				(font
					(size 0.7 0.7)
					(thickness 0.15)
				)
				(justify left bottom mirror)
			)
		)
		(pad "1" smd roundrect
			(at -0.48 0 90)
			(size 0.59 0.64)
			(layers "B.Cu" "B.Paste" "B.Mask")
			(roundrect_rratio 0.25)
			(net 677 "USBC_HPD")
			(pintype "passive")
		)
		(pad "2" smd roundrect
			(at 0.48 0 90)
			(size 0.59 0.64)
			(layers "B.Cu" "B.Paste" "B.Mask")
			(roundrect_rratio 0.25)
			(net 502 "/USB Debug, DP/HPDIN")
			(pintype "passive")
		)
	)
	(footprint "antmicro-footprints:R_0402_1005Metric"
		(layer "B.Cu")
		(at 142 114 180)
		(descr "Resistor SMD 0402")
		(tags "resistor SMD 0402")
		(property "Reference" "R132"
			(at -1 -1.3 0)
			(layer "B.SilkS")
			(effects
				(font
					(size 0.7 0.7)
					(thickness 0.15)
				)
				(justify left bottom mirror)
			)
		)
		(property "Value" "R_200R_0402"
			(at 0 -1.4 0)
			(layer "B.Fab")
			(effects
				(font
					(size 0.7 0.7)
					(thickness 0.15)
				)
				(justify left bottom mirror)
			)
		)
		(property "Footprint" "antmicro-footprints:R_0402_1005Metric"
			(at 0 0 180)
			(layer "F.Fab")
			(hide yes)
			(effects
				(font
					(size 1.27 1.27)
					(thickness 0.15)
				)
			)
		)
		(property "Datasheet" "https://www.bourns.com/docs/product-datasheets/cr.pdf"
			(at 0 0 180)
			(layer "F.Fab")
			(hide yes)
			(effects
				(font
					(size 1.27 1.27)
					(thickness 0.15)
				)
			)
		)
		(property "Author" "Antmicro"
			(at 284 228 0)
			(layer "B.Fab")
			(hide yes)
			(effects
				(font
					(size 1 1)
					(thickness 0.15)
				)
				(justify mirror)
			)
		)
		(property "License" "Apache-2.0"
			(at 284 228 0)
			(layer "B.Fab")
			(hide yes)
			(effects
				(font
					(size 1 1)
					(thickness 0.15)
				)
				(justify mirror)
			)
		)
		(property "MPN" "CR0402-FX-2000GLF"
			(at 284 228 0)
			(layer "B.Fab")
			(hide yes)
			(effects
				(font
					(size 1 1)
					(thickness 0.15)
				)
				(justify mirror)
			)
		)
		(property "Manufacturer" "Bourns"
			(at 284 228 0)
			(layer "B.Fab")
			(hide yes)
			(effects
				(font
					(size 1 1)
					(thickness 0.15)
				)
				(justify mirror)
			)
		)
		(property "Tolerance" "1%"
			(at 284 228 0)
			(layer "B.Fab")
			(hide yes)
			(effects
				(font
					(size 1 1)
					(thickness 0.15)
				)
				(justify mirror)
			)
		)
		(property "Val" "200R"
			(at 284 228 0)
			(layer "B.Fab")
			(hide yes)
			(effects
				(font
					(size 1 1)
					(thickness 0.15)
				)
				(justify mirror)
			)
		)
		(sheetname "CSI")
		(sheetfile "csi.kicad_sch")
		(attr smd)
		(fp_rect
			(start -0.925 0.47)
			(end 0.925 -0.47)
			(stroke
				(width 0.05)
				(type default)
			)
			(fill none)
			(layer "B.CrtYd")
		)
		(fp_rect
			(start -0.5 0.25)
			(end 0.5 -0.25)
			(stroke
				(width 0.15)
				(type solid)
			)
			(fill none)
			(layer "B.Fab")
		)
		(fp_text user "License: Apache-2.0"
			(at -0.95 -5.169 0)
			(layer "B.Fab")
			(hide yes)
			(effects
				(font
					(size 0.7 0.7)
					(thickness 0.15)
				)
				(justify left bottom mirror)
			)
		)
		(fp_text user "Author: Antmicro"
			(at -0.95 -4.169 0)
			(layer "B.Fab")
			(hide yes)
			(effects
				(font
					(size 0.7 0.7)
					(thickness 0.15)
				)
				(justify left bottom mirror)
			)
		)
		(fp_text user "${REFERENCE}"
			(at -0.95 -3.168 0)
			(layer "B.Fab")
			(hide yes)
			(effects
				(font
					(size 0.7 0.7)
					(thickness 0.15)
				)
				(justify left bottom mirror)
			)
		)
		(pad "1" smd roundrect
			(at -0.48 0 180)
			(size 0.59 0.64)
			(layers "B.Cu" "B.Paste" "B.Mask")
			(roundrect_rratio 0.25)
			(net 155 "Net-(D18-A)")
			(pintype "passive")
		)
		(pad "2" smd roundrect
			(at 0.48 0 180)
			(size 0.59 0.64)
			(layers "B.Cu" "B.Paste" "B.Mask")
			(roundrect_rratio 0.25)
			(net 108 "/CSI/CSIA_3V3")
			(pintype "passive")
		)
	)
	(footprint "antmicro-footprints:C_0402_1005Metric"
		(layer "B.Cu")
		(at 59.9 78.95)
		(descr "Capacitor SMD 0402")
		(tags "capacitor SMD 0402")
		(property "Reference" "C116"
			(at 23.11 9.2 180)
			(layer "B.SilkS")
			(effects
				(font
					(size 0.7 0.7)
					(thickness 0.15)
				)
				(justify left bottom mirror)
			)
		)
		(property "Value" "C_10u_0402"
			(at 0 -1.4 180)
			(layer "B.Fab")
			(effects
				(font
					(size 0.7 0.7)
					(thickness 0.15)
				)
				(justify left bottom mirror)
			)
		)
		(property "Footprint" "antmicro-footprints:C_0402_1005Metric"
			(at 0 0 0)
			(layer "F.Fab")
			(hide yes)
			(effects
				(font
					(size 1.27 1.27)
					(thickness 0.15)
				)
			)
		)
		(property "Datasheet" "https://www.yageo.com/en/Chart/Download/pdf/CC0402MRX5R5BB106"
			(at 0 0 0)
			(layer "F.Fab")
			(hide yes)
			(effects
				(font
					(size 1.27 1.27)
					(thickness 0.15)
				)
			)
		)
		(property "Author" "Antmicro"
			(at 0 0 0)
			(layer "B.Fab")
			(hide yes)
			(effects
				(font
					(size 1 1)
					(thickness 0.15)
				)
				(justify mirror)
			)
		)
		(property "Dielectric" ""
			(at 0 0 0)
			(layer "B.Fab")
			(hide yes)
			(effects
				(font
					(size 1 1)
					(thickness 0.15)
				)
				(justify mirror)
			)
		)
		(property "License" "Apache-2.0"
			(at 0 0 0)
			(layer "B.Fab")
			(hide yes)
			(effects
				(font
					(size 1 1)
					(thickness 0.15)
				)
				(justify mirror)
			)
		)
		(property "MPN" "CC0402MRX5R5BB106"
			(at 0 0 0)
			(layer "B.Fab")
			(hide yes)
			(effects
				(font
					(size 1 1)
					(thickness 0.15)
				)
				(justify mirror)
			)
		)
		(property "Manufacturer" "YAGEO"
			(at 0 0 0)
			(layer "B.Fab")
			(hide yes)
			(effects
				(font
					(size 1 1)
					(thickness 0.15)
				)
				(justify mirror)
			)
		)
		(property "Val" "10u"
			(at 0 0 0)
			(layer "B.Fab")
			(hide yes)
			(effects
				(font
					(size 1 1)
					(thickness 0.15)
				)
				(justify mirror)
			)
		)
		(property "Voltage" ""
			(at 0 0 0)
			(layer "B.Fab")
			(hide yes)
			(effects
				(font
					(size 1 1)
					(thickness 0.15)
				)
				(justify mirror)
			)
		)
		(sheetname "Supply")
		(sheetfile "supply.kicad_sch")
		(attr smd)
		(fp_rect
			(start -0.925 0.47)
			(end 0.925 -0.47)
			(stroke
				(width 0.05)
				(type default)
			)
			(fill none)
			(layer "B.CrtYd")
		)
		(fp_line
			(start -0.494 -0.248)
			(end 0.504 -0.248)
			(stroke
				(width 0.15)
				(type solid)
			)
			(layer "B.Fab")
		)
		(fp_line
			(start -0.494 0.25)
			(end -0.494 -0.248)
			(stroke
				(width 0.15)
				(type solid)
			)
			(layer "B.Fab")
		)
		(fp_line
			(start 0.504 -0.248)
			(end 0.504 0.25)
			(stroke
				(width 0.15)
				(type solid)
			)
			(layer "B.Fab")
		)
		(fp_line
			(start 0.504 0.25)
			(end -0.494 0.25)
			(stroke
				(width 0.15)
				(type solid)
			)
			(layer "B.Fab")
		)
		(fp_text user "License: Apache-2.0"
			(at -0.932 -5.17 180)
			(layer "B.Fab")
			(hide yes)
			(effects
				(font
					(size 0.7 0.7)
					(thickness 0.15)
				)
				(justify left bottom mirror)
			)
		)
		(fp_text user "Author: Antmicro"
			(at -0.932 -4.17 180)
			(layer "B.Fab")
			(hide yes)
			(effects
				(font
					(size 0.7 0.7)
					(thickness 0.15)
				)
				(justify left bottom mirror)
			)
		)
		(fp_text user "${REFERENCE}"
			(at -0.932 -3.168 180)
			(layer "B.Fab")
			(hide yes)
			(effects
				(font
					(size 0.7 0.7)
					(thickness 0.15)
				)
				(justify left bottom mirror)
			)
		)
		(pad "1" smd roundrect
			(at -0.48 0)
			(size 0.59 0.64)
			(layers "B.Cu" "B.Paste" "B.Mask")
			(roundrect_rratio 0.25)
			(net 1 "GND")
			(pintype "passive")
		)
		(pad "2" smd roundrect
			(at 0.48 0)
			(size 0.59 0.64)
			(layers "B.Cu" "B.Paste" "B.Mask")
			(roundrect_rratio 0.25)
			(net 137 "Net-(D36-A)")
			(pintype "passive")
		)
	)
	(footprint "antmicro-footprints:TP_SMD_0.75mm"
		(layer "B.Cu")
		(at 60 103.4 -135)
		(property "Reference" "TP25"
			(at 0 0.6 45)
			(layer "B.SilkS")
			(hide yes)
			(effects
				(font
					(size 0.7 0.7)
					(thickness 0.15)
				)
				(justify left bottom mirror)
			)
		)
		(property "Value" "TP_0.75mm_SMD"
			(at 0 -1.2 45)
			(layer "B.Fab")
			(effects
				(font
					(size 0.7 0.7)
					(thickness 0.15)
				)
				(justify left bottom mirror)
			)
		)
		(property "Footprint" "antmicro-footprints:TP_SMD_0.75mm"
			(at 0 0 -135)
			(layer "F.Fab")
			(hide yes)
			(effects
				(font
					(size 1.27 1.27)
					(thickness 0.15)
				)
			)
		)
		(property "Author" "Antmicro"
			(at 29.311566 218.941248 0)
			(layer "B.Fab")
			(hide yes)
			(effects
				(font
					(size 1 1)
					(thickness 0.15)
				)
				(justify mirror)
			)
		)
		(property "License" "Apache-2.0"
			(at 29.311566 218.941248 0)
			(layer "B.Fab")
			(hide yes)
			(effects
				(font
					(size 1 1)
					(thickness 0.15)
				)
				(justify mirror)
			)
		)
		(property "MPN" ""
			(at 29.311566 218.941248 0)
			(layer "B.Fab")
			(hide yes)
			(effects
				(font
					(size 1 1)
					(thickness 0.15)
				)
				(justify mirror)
			)
		)
		(property "Manufacturer" ""
			(at 29.311566 218.941248 0)
			(layer "B.Fab")
			(hide yes)
			(effects
				(font
					(size 1 1)
					(thickness 0.15)
				)
				(justify mirror)
			)
		)
		(sheetname "USB Debug, DP")
		(sheetfile "usb.kicad_sch")
		(attr exclude_from_pos_files exclude_from_bom)
		(fp_circle
			(center 0 0)
			(end 0.475 0)
			(stroke
				(width 0.05)
				(type default)
			)
			(fill none)
			(layer "B.CrtYd")
		)
		(fp_text user "License: Apache-2.0"
			(at -0.4 -5.101 45)
			(layer "B.Fab")
			(hide yes)
			(effects
				(font
					(size 0.7 0.7)
					(thickness 0.15)
				)
				(justify left bottom mirror)
			)
		)
		(fp_text user "${REFERENCE}"
			(at -0.4 -2.7 45)
			(layer "B.Fab")
			(hide yes)
			(effects
				(font
					(size 0.7 0.7)
					(thickness 0.15)
				)
				(justify left bottom mirror)
			)
		)
		(fp_text user "Author: Antmicro"
			(at -0.4 -3.901 45)
			(layer "B.Fab")
			(hide yes)
			(effects
				(font
					(size 0.7 0.7)
					(thickness 0.15)
				)
				(justify left bottom mirror)
			)
		)
		(pad "1" smd circle
			(at 0 0 225)
			(size 0.75 0.75)
			(layers "B.Cu" "B.Mask")
			(net 299 "/USB Debug, DP/PDC_I2C3_SDA")
			(pinfunction "1")
			(pintype "passive")
		)
	)
	(footprint "antmicro-footprints:C_0402_1005Metric"
		(layer "B.Cu")
		(at 140.01 126.6 180)
		(descr "Capacitor SMD 0402")
		(tags "capacitor SMD 0402")
		(property "Reference" "C130"
			(at -1.33 -1.33 0)
			(layer "B.SilkS")
			(effects
				(font
					(size 0.7 0.7)
					(thickness 0.15)
				)
				(justify left bottom mirror)
			)
		)
		(property "Value" "C_100n_0402"
			(at 0 -1.4 0)
			(layer "B.Fab")
			(effects
				(font
					(size 0.7 0.7)
					(thickness 0.15)
				)
				(justify left bottom mirror)
			)
		)
		(property "Footprint" "antmicro-footprints:C_0402_1005Metric"
			(at 0 0 180)
			(layer "F.Fab")
			(hide yes)
			(effects
				(font
					(size 1.27 1.27)
					(thickness 0.15)
				)
			)
		)
		(property "Datasheet" "https://www.murata.com/products/productdetail?partno=GRM155R61H104KE14%23"
			(at 0 0 180)
			(layer "F.Fab")
			(hide yes)
			(effects
				(font
					(size 1.27 1.27)
					(thickness 0.15)
				)
			)
		)
		(property "Author" "Antmicro"
			(at 280.02 253.2 0)
			(layer "B.Fab")
			(hide yes)
			(effects
				(font
					(size 1 1)
					(thickness 0.15)
				)
				(justify mirror)
			)
		)
		(property "Dielectric" "X5R"
			(at 280.02 253.2 0)
			(layer "B.Fab")
			(hide yes)
			(effects
				(font
					(size 1 1)
					(thickness 0.15)
				)
				(justify mirror)
			)
		)
		(property "License" "Apache-2.0"
			(at 280.02 253.2 0)
			(layer "B.Fab")
			(hide yes)
			(effects
				(font
					(size 1 1)
					(thickness 0.15)
				)
				(justify mirror)
			)
		)
		(property "MPN" "GRM155R61H104KE14D"
			(at 280.02 253.2 0)
			(layer "B.Fab")
			(hide yes)
			(effects
				(font
					(size 1 1)
					(thickness 0.15)
				)
				(justify mirror)
			)
		)
		(property "Manufacturer" "Murata"
			(at 280.02 253.2 0)
			(layer "B.Fab")
			(hide yes)
			(effects
				(font
					(size 1 1)
					(thickness 0.15)
				)
				(justify mirror)
			)
		)
		(property "Val" "100n"
			(at 280.02 253.2 0)
			(layer "B.Fab")
			(hide yes)
			(effects
				(font
					(size 1 1)
					(thickness 0.15)
				)
				(justify mirror)
			)
		)
		(property "Voltage" "50V"
			(at 280.02 253.2 0)
			(layer "B.Fab")
			(hide yes)
			(effects
				(font
					(size 1 1)
					(thickness 0.15)
				)
				(justify mirror)
			)
		)
		(sheetname "Peripherals")
		(sheetfile "peripherals.kicad_sch")
		(attr smd)
		(fp_rect
			(start -0.925 0.47)
			(end 0.925 -0.47)
			(stroke
				(width 0.05)
				(type default)
			)
			(fill none)
			(layer "B.CrtYd")
		)
		(fp_line
			(start 0.504 0.25)
			(end -0.494 0.25)
			(stroke
				(width 0.15)
				(type solid)
			)
			(layer "B.Fab")
		)
		(fp_line
			(start 0.504 -0.248)
			(end 0.504 0.25)
			(stroke
				(width 0.15)
				(type solid)
			)
			(layer "B.Fab")
		)
		(fp_line
			(start -0.494 0.25)
			(end -0.494 -0.248)
			(stroke
				(width 0.15)
				(type solid)
			)
			(layer "B.Fab")
		)
		(fp_line
			(start -0.494 -0.248)
			(end 0.504 -0.248)
			(stroke
				(width 0.15)
				(type solid)
			)
			(layer "B.Fab")
		)
		(fp_text user "License: Apache-2.0"
			(at -0.932 -5.17 0)
			(layer "B.Fab")
			(hide yes)
			(effects
				(font
					(size 0.7 0.7)
					(thickness 0.15)
				)
				(justify left bottom mirror)
			)
		)
		(fp_text user "${REFERENCE}"
			(at -0.932 -3.168 0)
			(layer "B.Fab")
			(hide yes)
			(effects
				(font
					(size 0.7 0.7)
					(thickness 0.15)
				)
				(justify left bottom mirror)
			)
		)
		(fp_text user "Author: Antmicro"
			(at -0.932 -4.17 0)
			(layer "B.Fab")
			(hide yes)
			(effects
				(font
					(size 0.7 0.7)
					(thickness 0.15)
				)
				(justify left bottom mirror)
			)
		)
		(pad "1" smd roundrect
			(at -0.48 0 180)
			(size 0.59 0.64)
			(layers "B.Cu" "B.Paste" "B.Mask")
			(roundrect_rratio 0.25)
			(net 87 "+3V3")
			(pintype "passive")
		)
		(pad "2" smd roundrect
			(at 0.48 0 180)
			(size 0.59 0.64)
			(layers "B.Cu" "B.Paste" "B.Mask")
			(roundrect_rratio 0.25)
			(net 1 "GND")
			(pintype "passive")
		)
	)
	(footprint "antmicro-footprints:TP_SMD_0.75mm"
		(layer "B.Cu")
		(at 68.165 120.07 180)
		(property "Reference" "TP14"
			(at -1.65 -2.2 0)
			(layer "B.SilkS")
			(hide yes)
			(effects
				(font
					(size 0.7 0.7)
					(thickness 0.15)
				)
				(justify left bottom mirror)
			)
		)
		(property "Value" "TP_0.75mm_SMD"
			(at 0 -1.2 0)
			(layer "B.Fab")
			(effects
				(font
					(size 0.7 0.7)
					(thickness 0.15)
				)
				(justify left bottom mirror)
			)
		)
		(property "Footprint" "antmicro-footprints:TP_SMD_0.75mm"
			(at 0 0 180)
			(layer "F.Fab")
			(hide yes)
			(effects
				(font
					(size 1.27 1.27)
					(thickness 0.15)
				)
			)
		)
		(property "Author" "Antmicro"
			(at 136.33 240.14 0)
			(layer "B.Fab")
			(hide yes)
			(effects
				(font
					(size 1 1)
					(thickness 0.15)
				)
				(justify mirror)
			)
		)
		(property "License" "Apache-2.0"
			(at 136.33 240.14 0)
			(layer "B.Fab")
			(hide yes)
			(effects
				(font
					(size 1 1)
					(thickness 0.15)
				)
				(justify mirror)
			)
		)
		(property "MPN" ""
			(at 136.33 240.14 0)
			(layer "B.Fab")
			(hide yes)
			(effects
				(font
					(size 1 1)
					(thickness 0.15)
				)
				(justify mirror)
			)
		)
		(property "Manufacturer" ""
			(at 136.33 240.14 0)
			(layer "B.Fab")
			(hide yes)
			(effects
				(font
					(size 1 1)
					(thickness 0.15)
				)
				(justify mirror)
			)
		)
		(sheetname "Supply")
		(sheetfile "supply.kicad_sch")
		(attr exclude_from_pos_files exclude_from_bom)
		(fp_circle
			(center 0 0)
			(end 0.475 0)
			(stroke
				(width 0.05)
				(type default)
			)
			(fill none)
			(layer "B.CrtYd")
		)
		(fp_text user "${REFERENCE}"
			(at -0.4 -2.7 0)
			(layer "B.Fab")
			(hide yes)
			(effects
				(font
					(size 0.7 0.7)
					(thickness 0.15)
				)
				(justify left bottom mirror)
			)
		)
		(fp_text user "License: Apache-2.0"
			(at -0.4 -5.101 0)
			(layer "B.Fab")
			(hide yes)
			(effects
				(font
					(size 0.7 0.7)
					(thickness 0.15)
				)
				(justify left bottom mirror)
			)
		)
		(fp_text user "Author: Antmicro"
			(at -0.4 -3.901 0)
			(layer "B.Fab")
			(hide yes)
			(effects
				(font
					(size 0.7 0.7)
					(thickness 0.15)
				)
				(justify left bottom mirror)
			)
		)
		(pad "1" smd circle
			(at 0 0 180)
			(size 0.75 0.75)
			(layers "B.Cu" "B.Mask")
			(net 115 "VCC")
			(pinfunction "1")
			(pintype "passive")
		)
	)
	(footprint "antmicro-footprints:XDFN-2_1x0.60mm"
		(layer "B.Cu")
		(at 128.95 94.5 180)
		(property "Reference" "D23"
			(at 1.1 0.55 0)
			(layer "B.SilkS")
			(effects
				(font
					(size 0.7 0.7)
					(thickness 0.15)
				)
				(justify right bottom mirror)
			)
		)
		(property "Value" "TPD1E0B04_XDFN-2"
			(at 0 -1.5 0)
			(layer "B.Fab")
			(effects
				(font
					(size 0.7 0.7)
					(thickness 0.15)
				)
				(justify left bottom mirror)
			)
		)
		(property "Footprint" "antmicro-footprints:XDFN-2_1x0.60mm"
			(at 0 0 180)
			(layer "F.Fab")
			(hide yes)
			(effects
				(font
					(size 1.27 1.27)
					(thickness 0.15)
				)
			)
		)
		(property "Datasheet" "https://www.ti.com/general/docs/suppproductinfo.tsp?distId=26&gotoUrl=https://www.ti.com/lit/gpn/tpd1e0b04"
			(at 0 0 180)
			(layer "F.Fab")
			(hide yes)
			(effects
				(font
					(size 1.27 1.27)
					(thickness 0.15)
				)
			)
		)
		(property "MPN" "TPD1E0B04DPYR"
			(at 257.9 189 0)
			(layer "B.Fab")
			(hide yes)
			(effects
				(font
					(size 1 1)
					(thickness 0.15)
				)
				(justify mirror)
			)
		)
		(property "Manufacturer" "Texas Instruments"
			(at 257.9 189 0)
			(layer "B.Fab")
			(hide yes)
			(effects
				(font
					(size 1 1)
					(thickness 0.15)
				)
				(justify mirror)
			)
		)
		(property "Author" "Antmicro"
			(at 257.9 189 0)
			(layer "B.Fab")
			(hide yes)
			(effects
				(font
					(size 1 1)
					(thickness 0.15)
				)
				(justify mirror)
			)
		)
		(property "License" "Apache-2.0"
			(at 257.9 189 0)
			(layer "B.Fab")
			(hide yes)
			(effects
				(font
					(size 1 1)
					(thickness 0.15)
				)
				(justify mirror)
			)
		)
		(sheetname "Peripherals")
		(sheetfile "peripherals.kicad_sch")
		(attr smd)
		(fp_rect
			(start -0.725 0.475)
			(end 0.725 -0.475)
			(stroke
				(width 0.05)
				(type solid)
			)
			(fill none)
			(layer "B.CrtYd")
		)
		(fp_rect
			(start -0.55 0.35)
			(end 0.55 -0.35)
			(stroke
				(width 0.15)
				(type solid)
			)
			(fill none)
			(layer "B.Fab")
		)
		(fp_text user "Author: Antmicro"
			(at -0.8 -4.4 0)
			(layer "B.Fab")
			(hide yes)
			(effects
				(font
					(size 0.7 0.7)
					(thickness 0.15)
				)
				(justify left bottom mirror)
			)
		)
		(fp_text user "License: Apache-2.0"
			(at -0.8 -5.6 0)
			(layer "B.Fab")
			(hide yes)
			(effects
				(font
					(size 0.7 0.7)
					(thickness 0.15)
				)
				(justify left bottom mirror)
			)
		)
		(fp_text user "${REFERENCE}"
			(at -0.8 -3.2 0)
			(layer "B.Fab")
			(hide yes)
			(effects
				(font
					(size 0.7 0.7)
					(thickness 0.15)
				)
				(justify left bottom mirror)
			)
		)
		(pad "1" smd roundrect
			(at -0.351 0 180)
			(size 0.3 0.5)
			(layers "B.Cu" "B.Paste" "B.Mask")
			(roundrect_rratio 0.25)
			(net 436 "USB1_D_P")
			(pinfunction "C")
			(pintype "passive")
		)
		(pad "2" smd roundrect
			(at 0.349 0 180)
			(size 0.3 0.5)
			(layers "B.Cu" "B.Paste" "B.Mask")
			(roundrect_rratio 0.25)
			(net 1 "GND")
			(pinfunction "A")
			(pintype "passive")
		)
	)
	(footprint "antmicro-footprints:C_0402_1005Metric"
		(layer "B.Cu")
		(at 87 110.3 90)
		(descr "Capacitor SMD 0402")
		(tags "capacitor SMD 0402")
		(property "Reference" "C104"
			(at 1.45 -0.45 -90)
			(layer "B.SilkS")
			(effects
				(font
					(size 0.7 0.7)
					(thickness 0.15)
				)
				(justify left bottom mirror)
			)
		)
		(property "Value" "C_100n_0402"
			(at 0 -1.4 -90)
			(layer "B.Fab")
			(effects
				(font
					(size 0.7 0.7)
					(thickness 0.15)
				)
				(justify left bottom mirror)
			)
		)
		(property "Footprint" "antmicro-footprints:C_0402_1005Metric"
			(at 0 0 90)
			(layer "F.Fab")
			(hide yes)
			(effects
				(font
					(size 1.27 1.27)
					(thickness 0.15)
				)
			)
		)
		(property "Datasheet" "https://www.murata.com/products/productdetail?partno=GRM155R61H104KE14%23"
			(at 0 0 90)
			(layer "F.Fab")
			(hide yes)
			(effects
				(font
					(size 1.27 1.27)
					(thickness 0.15)
				)
			)
		)
		(property "Author" "Antmicro"
			(at 197.3 23.3 0)
			(layer "B.Fab")
			(hide yes)
			(effects
				(font
					(size 1 1)
					(thickness 0.15)
				)
				(justify mirror)
			)
		)
		(property "Dielectric" "X5R"
			(at 197.3 23.3 0)
			(layer "B.Fab")
			(hide yes)
			(effects
				(font
					(size 1 1)
					(thickness 0.15)
				)
				(justify mirror)
			)
		)
		(property "License" "Apache-2.0"
			(at 197.3 23.3 0)
			(layer "B.Fab")
			(hide yes)
			(effects
				(font
					(size 1 1)
					(thickness 0.15)
				)
				(justify mirror)
			)
		)
		(property "MPN" "GRM155R61H104KE14D"
			(at 197.3 23.3 0)
			(layer "B.Fab")
			(hide yes)
			(effects
				(font
					(size 1 1)
					(thickness 0.15)
				)
				(justify mirror)
			)
		)
		(property "Manufacturer" "Murata"
			(at 197.3 23.3 0)
			(layer "B.Fab")
			(hide yes)
			(effects
				(font
					(size 1 1)
					(thickness 0.15)
				)
				(justify mirror)
			)
		)
		(property "Val" "100n"
			(at 197.3 23.3 0)
			(layer "B.Fab")
			(hide yes)
			(effects
				(font
					(size 1 1)
					(thickness 0.15)
				)
				(justify mirror)
			)
		)
		(property "Voltage" "50V"
			(at 197.3 23.3 0)
			(layer "B.Fab")
			(hide yes)
			(effects
				(font
					(size 1 1)
					(thickness 0.15)
				)
				(justify mirror)
			)
		)
		(sheetname "Peripherals")
		(sheetfile "peripherals.kicad_sch")
		(attr smd)
		(fp_rect
			(start -0.925 0.47)
			(end 0.925 -0.47)
			(stroke
				(width 0.05)
				(type default)
			)
			(fill none)
			(layer "B.CrtYd")
		)
		(fp_line
			(start 0.504 -0.248)
			(end 0.504 0.25)
			(stroke
				(width 0.15)
				(type solid)
			)
			(layer "B.Fab")
		)
		(fp_line
			(start -0.494 -0.248)
			(end 0.504 -0.248)
			(stroke
				(width 0.15)
				(type solid)
			)
			(layer "B.Fab")
		)
		(fp_line
			(start 0.504 0.25)
			(end -0.494 0.25)
			(stroke
				(width 0.15)
				(type solid)
			)
			(layer "B.Fab")
		)
		(fp_line
			(start -0.494 0.25)
			(end -0.494 -0.248)
			(stroke
				(width 0.15)
				(type solid)
			)
			(layer "B.Fab")
		)
		(fp_text user "License: Apache-2.0"
			(at -0.932 -5.17 -90)
			(layer "B.Fab")
			(hide yes)
			(effects
				(font
					(size 0.7 0.7)
					(thickness 0.15)
				)
				(justify left bottom mirror)
			)
		)
		(fp_text user "${REFERENCE}"
			(at -0.932 -3.168 -90)
			(layer "B.Fab")
			(hide yes)
			(effects
				(font
					(size 0.7 0.7)
					(thickness 0.15)
				)
				(justify left bottom mirror)
			)
		)
		(fp_text user "Author: Antmicro"
			(at -0.932 -4.17 -90)
			(layer "B.Fab")
			(hide yes)
			(effects
				(font
					(size 0.7 0.7)
					(thickness 0.15)
				)
				(justify left bottom mirror)
			)
		)
		(pad "1" smd roundrect
			(at -0.48 0 90)
			(size 0.59 0.64)
			(layers "B.Cu" "B.Paste" "B.Mask")
			(roundrect_rratio 0.25)
			(net 1 "GND")
			(pintype "passive")
		)
		(pad "2" smd roundrect
			(at 0.48 0 90)
			(size 0.59 0.64)
			(layers "B.Cu" "B.Paste" "B.Mask")
			(roundrect_rratio 0.25)
			(net 87 "+3V3")
			(pintype "passive")
		)
	)
	(footprint "antmicro-footprints:R_Array_4x0201_Panasonic_EXB18V"
		(layer "B.Cu")
		(at 83.21 122.11 180)
		(property "Reference" "R204"
			(at 1.96 0.71 0)
			(layer "B.SilkS")
			(effects
				(font
					(size 0.7 0.7)
					(thickness 0.15)
				)
				(justify right bottom mirror)
			)
		)
		(property "Value" "R_4x0R_0201_array"
			(at -1.1 -1.8 0)
			(layer "B.Fab")
			(effects
				(font
					(size 0.7 0.7)
					(thickness 0.15)
				)
				(justify left bottom mirror)
			)
		)
		(property "Footprint" "antmicro-footprints:R_Array_4x0201_Panasonic_EXB18V"
			(at 0 0 180)
			(layer "F.Fab")
			(hide yes)
			(effects
				(font
					(size 1.27 1.27)
					(thickness 0.15)
				)
			)
		)
		(property "Datasheet" "http://industrial.panasonic.com/cdbs/www-data/pdf/AOC0000/AOC0000C14.pdf"
			(at 0 0 180)
			(layer "F.Fab")
			(hide yes)
			(effects
				(font
					(size 1.27 1.27)
					(thickness 0.15)
				)
			)
		)
		(property "Author" "Antmicro"
			(at 166.42 244.22 0)
			(layer "B.Fab")
			(hide yes)
			(effects
				(font
					(size 1 1)
					(thickness 0.15)
				)
				(justify mirror)
			)
		)
		(property "License" "Apache-2.0"
			(at 166.42 244.22 0)
			(layer "B.Fab")
			(hide yes)
			(effects
				(font
					(size 1 1)
					(thickness 0.15)
				)
				(justify mirror)
			)
		)
		(property "MPN" "EXB-18VR000X"
			(at 166.42 244.22 0)
			(layer "B.Fab")
			(hide yes)
			(effects
				(font
					(size 1 1)
					(thickness 0.15)
				)
				(justify mirror)
			)
		)
		(property "Manufacturer" "Panasonic"
			(at 166.42 244.22 0)
			(layer "B.Fab")
			(hide yes)
			(effects
				(font
					(size 1 1)
					(thickness 0.15)
				)
				(justify mirror)
			)
		)
		(property "Val" "4x0R_0201"
			(at 166.42 244.22 0)
			(layer "B.Fab")
			(hide yes)
			(effects
				(font
					(size 1 1)
					(thickness 0.15)
				)
				(justify mirror)
			)
		)
		(sheetname "Peripherals")
		(sheetfile "peripherals.kicad_sch")
		(attr smd)
		(fp_line
			(start 0.8 -0.45)
			(end 0.8 0.45)
			(stroke
				(width 0.12)
				(type solid)
			)
			(layer "B.SilkS")
		)
		(fp_line
			(start -0.8 -0.45)
			(end -0.8 0.45)
			(stroke
				(width 0.12)
				(type solid)
			)
			(layer "B.SilkS")
		)
		(fp_rect
			(start -0.898 0.66)
			(end 0.898 -0.65)
			(stroke
				(width 0.05)
				(type solid)
			)
			(fill none)
			(layer "B.CrtYd")
		)
		(fp_text user "${REFERENCE}"
			(at -1.051 -3.2 0)
			(layer "B.Fab")
			(hide yes)
			(effects
				(font
					(size 0.7 0.7)
					(thickness 0.15)
				)
				(justify left bottom mirror)
			)
		)
		(fp_text user "Author: Antmicro"
			(at -1.051 -4.599 0)
			(layer "B.Fab")
			(hide yes)
			(effects
				(font
					(size 0.7 0.7)
					(thickness 0.15)
				)
				(justify left bottom mirror)
			)
		)
		(fp_text user "License: Apache-2.0"
			(at -1.051 -6 0)
			(layer "B.Fab")
			(hide yes)
			(effects
				(font
					(size 0.7 0.7)
					(thickness 0.15)
				)
				(justify left bottom mirror)
			)
		)
		(pad "1" smd roundrect
			(at -0.6 -0.298 180)
			(size 0.2 0.4)
			(layers "B.Cu" "B.Paste" "B.Mask")
			(roundrect_rratio 0.25)
			(net 772 "/Peripherals/~{CS}")
			(pinfunction "R1.1")
			(pintype "passive")
		)
		(pad "2" smd roundrect
			(at -0.202 -0.298 180)
			(size 0.2 0.4)
			(layers "B.Cu" "B.Paste" "B.Mask")
			(roundrect_rratio 0.25)
			(net 774 "/Peripherals/MOSI")
			(pinfunction "R2.1")
			(pintype "passive")
		)
		(pad "3" smd roundrect
			(at 0.2 -0.298 180)
			(size 0.2 0.4)
			(layers "B.Cu" "B.Paste" "B.Mask")
			(roundrect_rratio 0.25)
			(net 671 "/Peripherals/SCK")
			(pinfunction "R3.1")
			(pintype "passive")
		)
		(pad "4" smd roundrect
			(at 0.598 -0.298 180)
			(size 0.2 0.4)
			(layers "B.Cu" "B.Paste" "B.Mask")
			(roundrect_rratio 0.25)
			(net 773 "/Peripherals/MISO")
			(pinfunction "R4.1")
			(pintype "passive")
		)
		(pad "5" smd roundrect
			(at 0.598 0.3 180)
			(size 0.2 0.4)
			(layers "B.Cu" "B.Paste" "B.Mask")
			(roundrect_rratio 0.25)
			(net 255 "PDC_MISO")
			(pinfunction "R4.2")
			(pintype "passive")
		)
		(pad "6" smd roundrect
			(at 0.2 0.3 180)
			(size 0.2 0.4)
			(layers "B.Cu" "B.Paste" "B.Mask")
			(roundrect_rratio 0.25)
			(net 254 "PDC_SCLK")
			(pinfunction "R3.2")
			(pintype "passive")
		)
		(pad "7" smd roundrect
			(at -0.202 0.3 180)
			(size 0.2 0.4)
			(layers "B.Cu" "B.Paste" "B.Mask")
			(roundrect_rratio 0.25)
			(net 256 "PDC_MOSI")
			(pinfunction "R2.2")
			(pintype "passive")
		)
		(pad "8" smd roundrect
			(at -0.6 0.3 180)
			(size 0.2 0.4)
			(layers "B.Cu" "B.Paste" "B.Mask")
			(roundrect_rratio 0.25)
			(net 253 "~{PDC_CS}")
			(pinfunction "R1.2")
			(pintype "passive")
		)
	)
	(footprint "antmicro-footprints:Spacer_Drill3.7mm_H6.5mm_9774065151R"
		(locked yes)
		(layer "B.Cu")
		(at 37.25 76.25 180)
		(descr "Spacer M=3 h=6.5mm fi=5.1mm")
		(property "Reference" "H6"
			(at -3.65 -3.15 0)
			(layer "B.SilkS")
			(effects
				(font
					(size 0.7 0.7)
					(thickness 0.15)
				)
				(justify left bottom mirror)
			)
		)
		(property "Value" "Spacer_Drill3.7mm_H6.5mm_9774065151R"
			(at 0 -4 0)
			(layer "B.Fab")
			(effects
				(font
					(size 0.7 0.7)
					(thickness 0.15)
				)
				(justify left bottom mirror)
			)
		)
		(property "Footprint" "antmicro-footprints:Spacer_Drill3.7mm_H6.5mm_9774065151R"
			(at 0 0 180)
			(layer "F.Fab")
			(hide yes)
			(effects
				(font
					(size 1.27 1.27)
					(thickness 0.15)
				)
			)
		)
		(property "Datasheet" "https://www.we-online.com/components/products/datasheet/9774065151R.pdf"
			(at 0 0 180)
			(layer "F.Fab")
			(hide yes)
			(effects
				(font
					(size 1.27 1.27)
					(thickness 0.15)
				)
			)
		)
		(property "Author" "Antmicro"
			(at 74.5 152.5 0)
			(layer "B.Fab")
			(hide yes)
			(effects
				(font
					(size 1 1)
					(thickness 0.15)
				)
				(justify mirror)
			)
		)
		(property "License" "Apache-2.0"
			(at 74.5 152.5 0)
			(layer "B.Fab")
			(hide yes)
			(effects
				(font
					(size 1 1)
					(thickness 0.15)
				)
				(justify mirror)
			)
		)
		(property "MPN" "9774065151R"
			(at 74.5 152.5 0)
			(layer "B.Fab")
			(hide yes)
			(effects
				(font
					(size 1 1)
					(thickness 0.15)
				)
				(justify mirror)
			)
		)
		(property "Manufacturer" "Würth Elektronik"
			(at 74.5 152.5 0)
			(layer "B.Fab")
			(hide yes)
			(effects
				(font
					(size 1 1)
					(thickness 0.15)
				)
				(justify mirror)
			)
		)
		(sheetname "Root")
		(sheetfile "jetson-orin-baseboard.kicad_sch")
		(solder_paste_ratio -1)
		(attr smd)
		(fp_circle
			(center 0 0)
			(end 3.05 0)
			(stroke
				(width 0.05)
				(type solid)
			)
			(fill none)
			(layer "B.CrtYd")
		)
		(fp_circle
			(center 0 0)
			(end 2.6 0)
			(stroke
				(width 0.15)
				(type solid)
			)
			(fill none)
			(layer "B.Fab")
		)
		(fp_text user "Author: Antmicro"
			(at -9.6 -7.7 0)
			(layer "B.Fab")
			(hide yes)
			(effects
				(font
					(size 0.7 0.7)
					(thickness 0.15)
				)
				(justify left bottom mirror)
			)
		)
		(fp_text user "License: Apache-2.0"
			(at -9.6 -8.9 0)
			(layer "B.Fab")
			(hide yes)
			(effects
				(font
					(size 0.7 0.7)
					(thickness 0.15)
				)
				(justify left bottom mirror)
			)
		)
		(fp_text user "${REFERENCE}"
			(at -9.6 -6.5 0)
			(layer "B.Fab")
			(hide yes)
			(effects
				(font
					(size 0.7 0.7)
					(thickness 0.15)
				)
				(justify left bottom mirror)
			)
		)
		(pad "" smd custom
			(at -1.7 -1.7 90)
			(size 0.62 0.62)
			(layers "B.Paste")
			(thermal_bridge_angle 90)
			(options
				(clearance outline)
				(anchor circle)
			)
			(primitives
				(gr_arc
					(start 1.266786 0.24747)
					(mid 0.285453 -0.29439)
					(end -0.250195 -1.279127)
					(width 0.2)
				)
				(gr_arc
					(start 1.259603 0.339191)
					(mid 0.218448 -0.232561)
					(end -0.34334 -1.279127)
					(width 0.2)
				)
				(gr_arc
					(start 1.255279 0.431435)
					(mid 0.152481 -0.169693)
					(end -0.436309 -1.279127)
					(width 0.2)
				)
				(gr_arc
					(start 1.253811 0.524161)
					(mid 0.087542 -0.105784)
					(end -0.529126 -1.279127)
					(width 0.2)
				)
				(gr_arc
					(start 1.275473 0.621136)
					(mid 0.0309 -0.033527)
					(end -0.621807 -1.279127)
					(width 0.2)
				)
				(gr_arc
					(start 1.263664 0.711602)
					(mid -0.037759 0.026651)
					(end -0.71437 -1.279127)
					(width 0.2)
				)
				(gr_arc
					(start 1.253435 0.802342)
					(mid -0.105837 0.087395)
					(end -0.806826 -1.279127)
					(width 0.2)
				)
				(gr_arc
					(start 1.267475 0.897258)
					(mid -0.165236 0.156885)
					(end -0.899187 -1.279127)
					(width 0.2)
				)
				(gr_arc
					(start 1.270645 0.990112)
					(mid -0.228522 0.222449)
					(end -0.991463 -1.279127)
					(width 0.2)
				)
				(gr_arc
					(start 1.266278 1.081674)
					(mid -0.294507 0.285313)
					(end -1.083663 -1.279127)
					(width 0.2)
				)
				(gr_line
					(start 1.279127 0.250195)
					(end 1.279127 1.083663)
					(width 0.2)
				)
				(gr_line
					(start -0.250195 -1.279127)
					(end -1.083663 -1.279127)
					(width 0.2)
				)
			)
		)
		(pad "" smd custom
			(at -1.7 1.7 180)
			(size 0.62 0.62)
			(layers "B.Paste")
			(thermal_bridge_angle 90)
			(options
				(clearance outline)
				(anchor circle)
			)
			(primitives
				(gr_arc
					(start 1.266786 0.24747)
					(mid 0.285453 -0.29439)
					(end -0.250195 -1.279127)
					(width 0.2)
				)
				(gr_arc
					(start 1.259603 0.339191)
					(mid 0.218448 -0.232561)
					(end -0.34334 -1.279127)
					(width 0.2)
				)
				(gr_arc
					(start 1.255279 0.431435)
					(mid 0.152481 -0.169693)
					(end -0.436309 -1.279127)
					(width 0.2)
				)
				(gr_arc
					(start 1.253811 0.524161)
					(mid 0.087542 -0.105784)
					(end -0.529126 -1.279127)
					(width 0.2)
				)
				(gr_arc
					(start 1.275473 0.621136)
					(mid 0.0309 -0.033527)
					(end -0.621807 -1.279127)
					(width 0.2)
				)
				(gr_arc
					(start 1.263664 0.711602)
					(mid -0.037759 0.026651)
					(end -0.71437 -1.279127)
					(width 0.2)
				)
				(gr_arc
					(start 1.253435 0.802342)
					(mid -0.105837 0.087395)
					(end -0.806826 -1.279127)
					(width 0.2)
				)
				(gr_arc
					(start 1.267475 0.897258)
					(mid -0.165236 0.156885)
					(end -0.899187 -1.279127)
					(width 0.2)
				)
				(gr_arc
					(start 1.270645 0.990112)
					(mid -0.228522 0.222449)
					(end -0.991463 -1.279127)
					(width 0.2)
				)
				(gr_arc
					(start 1.266278 1.081674)
					(mid -0.294507 0.285313)
					(end -1.083663 -1.279127)
					(width 0.2)
				)
				(gr_line
					(start 1.279127 0.250195)
					(end 1.279127 1.083663)
					(width 0.2)
				)
				(gr_line
					(start -0.250195 -1.279127)
					(end -1.083663 -1.279127)
					(width 0.2)
				)
			)
		)
		(pad "" smd custom
			(at 1.7 -1.7)
			(size 0.62 0.62)
			(layers "B.Paste")
			(thermal_bridge_angle 90)
			(options
				(clearance outline)
				(anchor circle)
			)
			(primitives
				(gr_arc
					(start 1.266786 0.24747)
					(mid 0.285453 -0.29439)
					(end -0.250195 -1.279127)
					(width 0.2)
				)
				(gr_arc
					(start 1.259603 0.339191)
					(mid 0.218448 -0.232561)
					(end -0.34334 -1.279127)
					(width 0.2)
				)
				(gr_arc
					(start 1.255279 0.431435)
					(mid 0.152481 -0.169693)
					(end -0.436309 -1.279127)
					(width 0.2)
				)
				(gr_arc
					(start 1.253811 0.524161)
					(mid 0.087542 -0.105784)
					(end -0.529126 -1.279127)
					(width 0.2)
				)
				(gr_arc
					(start 1.275473 0.621136)
					(mid 0.0309 -0.033527)
					(end -0.621807 -1.279127)
					(width 0.2)
				)
				(gr_arc
					(start 1.263664 0.711602)
					(mid -0.037759 0.026651)
					(end -0.71437 -1.279127)
					(width 0.2)
				)
				(gr_arc
					(start 1.253435 0.802342)
					(mid -0.105837 0.087395)
					(end -0.806826 -1.279127)
					(width 0.2)
				)
				(gr_arc
					(start 1.267475 0.897258)
					(mid -0.165236 0.156885)
					(end -0.899187 -1.279127)
					(width 0.2)
				)
				(gr_arc
					(start 1.270645 0.990112)
					(mid -0.228522 0.222449)
					(end -0.991463 -1.279127)
					(width 0.2)
				)
				(gr_arc
					(start 1.266278 1.081674)
					(mid -0.294507 0.285313)
					(end -1.083663 -1.279127)
					(width 0.2)
				)
				(gr_line
					(start 1.279127 0.250195)
					(end 1.279127 1.083663)
					(width 0.2)
				)
				(gr_line
					(start -0.250195 -1.279127)
					(end -1.083663 -1.279127)
					(width 0.2)
				)
			)
		)
		(pad "" smd custom
			(at 1.7 1.7 270)
			(size 0.62 0.62)
			(layers "B.Paste")
			(thermal_bridge_angle 90)
			(options
				(clearance outline)
				(anchor circle)
			)
			(primitives
				(gr_arc
					(start 1.266786 0.24747)
					(mid 0.285453 -0.29439)
					(end -0.250195 -1.279127)
					(width 0.2)
				)
				(gr_arc
					(start 1.259603 0.339191)
					(mid 0.218448 -0.232561)
					(end -0.34334 -1.279127)
					(width 0.2)
				)
				(gr_arc
					(start 1.255279 0.431435)
					(mid 0.152481 -0.169693)
					(end -0.436309 -1.279127)
					(width 0.2)
				)
				(gr_arc
					(start 1.253811 0.524161)
					(mid 0.087542 -0.105784)
					(end -0.529126 -1.279127)
					(width 0.2)
				)
				(gr_arc
					(start 1.275473 0.621136)
					(mid 0.0309 -0.033527)
					(end -0.621807 -1.279127)
					(width 0.2)
				)
				(gr_arc
					(start 1.263664 0.711602)
					(mid -0.037759 0.026651)
					(end -0.71437 -1.279127)
					(width 0.2)
				)
				(gr_arc
					(start 1.253435 0.802342)
					(mid -0.105837 0.087395)
					(end -0.806826 -1.279127)
					(width 0.2)
				)
				(gr_arc
					(start 1.267475 0.897258)
					(mid -0.165236 0.156885)
					(end -0.899187 -1.279127)
					(width 0.2)
				)
				(gr_arc
					(start 1.270645 0.990112)
					(mid -0.228522 0.222449)
					(end -0.991463 -1.279127)
					(width 0.2)
				)
				(gr_arc
					(start 1.266278 1.081674)
					(mid -0.294507 0.285313)
					(end -1.083663 -1.279127)
					(width 0.2)
				)
				(gr_line
					(start 1.279127 0.250195)
					(end 1.279127 1.083663)
					(width 0.2)
				)
				(gr_line
					(start -0.250195 -1.279127)
					(end -1.083663 -1.279127)
					(width 0.2)
				)
			)
		)
		(pad "1" thru_hole circle
			(at 0 0 180)
			(size 6 6)
			(drill 3.7)
			(layers "*.Cu" "*.Mask")
			(remove_unused_layers no)
			(net 1 "GND")
			(pintype "passive")
		)
	)
	(footprint "antmicro-footprints:C_0402_1005Metric"
		(layer "B.Cu")
		(at 138 107.75 90)
		(descr "Capacitor SMD 0402")
		(tags "capacitor SMD 0402")
		(property "Reference" "C95"
			(at 1.1 1.3 -90)
			(layer "B.SilkS")
			(effects
				(font
					(size 0.7 0.7)
					(thickness 0.15)
				)
				(justify left bottom mirror)
			)
		)
		(property "Value" "C_1u_0402"
			(at 0 -1.4 -90)
			(layer "B.Fab")
			(effects
				(font
					(size 0.7 0.7)
					(thickness 0.15)
				)
				(justify left bottom mirror)
			)
		)
		(property "Footprint" "antmicro-footprints:C_0402_1005Metric"
			(at 0 0 90)
			(layer "F.Fab")
			(hide yes)
			(effects
				(font
					(size 1.27 1.27)
					(thickness 0.15)
				)
			)
		)
		(property "Datasheet" "https://product.tdk.com/en/search/capacitor/ceramic/mlcc/info?part_no=C1005X6S1A105K050BC"
			(at 0 0 90)
			(layer "F.Fab")
			(hide yes)
			(effects
				(font
					(size 1.27 1.27)
					(thickness 0.15)
				)
			)
		)
		(property "Author" "Antmicro"
			(at 245.75 -30.25 0)
			(layer "B.Fab")
			(hide yes)
			(effects
				(font
					(size 1 1)
					(thickness 0.15)
				)
				(justify mirror)
			)
		)
		(property "Dielectric" ""
			(at 245.75 -30.25 0)
			(layer "B.Fab")
			(hide yes)
			(effects
				(font
					(size 1 1)
					(thickness 0.15)
				)
				(justify mirror)
			)
		)
		(property "License" "Apache-2.0"
			(at 245.75 -30.25 0)
			(layer "B.Fab")
			(hide yes)
			(effects
				(font
					(size 1 1)
					(thickness 0.15)
				)
				(justify mirror)
			)
		)
		(property "MPN" "C1005X6S1A105K050BC"
			(at 245.75 -30.25 0)
			(layer "B.Fab")
			(hide yes)
			(effects
				(font
					(size 1 1)
					(thickness 0.15)
				)
				(justify mirror)
			)
		)
		(property "Manufacturer" "TDK"
			(at 245.75 -30.25 0)
			(layer "B.Fab")
			(hide yes)
			(effects
				(font
					(size 1 1)
					(thickness 0.15)
				)
				(justify mirror)
			)
		)
		(property "Val" "1u"
			(at 245.75 -30.25 0)
			(layer "B.Fab")
			(hide yes)
			(effects
				(font
					(size 1 1)
					(thickness 0.15)
				)
				(justify mirror)
			)
		)
		(property "Voltage" ""
			(at 245.75 -30.25 0)
			(layer "B.Fab")
			(hide yes)
			(effects
				(font
					(size 1 1)
					(thickness 0.15)
				)
				(justify mirror)
			)
		)
		(sheetname "CSI")
		(sheetfile "csi.kicad_sch")
		(attr smd)
		(fp_rect
			(start -0.925 0.47)
			(end 0.925 -0.47)
			(stroke
				(width 0.05)
				(type default)
			)
			(fill none)
			(layer "B.CrtYd")
		)
		(fp_line
			(start 0.504 -0.248)
			(end 0.504 0.25)
			(stroke
				(width 0.15)
				(type solid)
			)
			(layer "B.Fab")
		)
		(fp_line
			(start -0.494 -0.248)
			(end 0.504 -0.248)
			(stroke
				(width 0.15)
				(type solid)
			)
			(layer "B.Fab")
		)
		(fp_line
			(start 0.504 0.25)
			(end -0.494 0.25)
			(stroke
				(width 0.15)
				(type solid)
			)
			(layer "B.Fab")
		)
		(fp_line
			(start -0.494 0.25)
			(end -0.494 -0.248)
			(stroke
				(width 0.15)
				(type solid)
			)
			(layer "B.Fab")
		)
		(fp_text user "License: Apache-2.0"
			(at -0.932 -5.17 -90)
			(layer "B.Fab")
			(hide yes)
			(effects
				(font
					(size 0.7 0.7)
					(thickness 0.15)
				)
				(justify left bottom mirror)
			)
		)
		(fp_text user "${REFERENCE}"
			(at -0.932 -3.168 -90)
			(layer "B.Fab")
			(hide yes)
			(effects
				(font
					(size 0.7 0.7)
					(thickness 0.15)
				)
				(justify left bottom mirror)
			)
		)
		(fp_text user "Author: Antmicro"
			(at -0.932 -4.17 -90)
			(layer "B.Fab")
			(hide yes)
			(effects
				(font
					(size 0.7 0.7)
					(thickness 0.15)
				)
				(justify left bottom mirror)
			)
		)
		(pad "1" smd roundrect
			(at -0.48 0 90)
			(size 0.59 0.64)
			(layers "B.Cu" "B.Paste" "B.Mask")
			(roundrect_rratio 0.25)
			(net 1 "GND")
			(pintype "passive")
		)
		(pad "2" smd roundrect
			(at 0.48 0 90)
			(size 0.59 0.64)
			(layers "B.Cu" "B.Paste" "B.Mask")
			(roundrect_rratio 0.25)
			(net 109 "/CSI/CSIA_5V")
			(pintype "passive")
		)
	)
	(footprint "antmicro-footprints:TP_SMD_0.75mm"
		(layer "B.Cu")
		(at 101.14999 103.5508 180)
		(property "Reference" "TP40"
			(at 0 0.6 0)
			(layer "B.SilkS")
			(hide yes)
			(effects
				(font
					(size 0.7 0.7)
					(thickness 0.15)
				)
				(justify left bottom mirror)
			)
		)
		(property "Value" "TP_0.75mm_SMD"
			(at 0 -1.2 0)
			(layer "B.Fab")
			(effects
				(font
					(size 0.7 0.7)
					(thickness 0.15)
				)
				(justify left bottom mirror)
			)
		)
		(property "Footprint" "antmicro-footprints:TP_SMD_0.75mm"
			(at 0 0 180)
			(layer "F.Fab")
			(hide yes)
			(effects
				(font
					(size 1.27 1.27)
					(thickness 0.15)
				)
			)
		)
		(property "Author" "Antmicro"
			(at 202.29998 207.1016 0)
			(layer "B.Fab")
			(hide yes)
			(effects
				(font
					(size 1 1)
					(thickness 0.15)
				)
				(justify mirror)
			)
		)
		(property "License" "Apache-2.0"
			(at 202.29998 207.1016 0)
			(layer "B.Fab")
			(hide yes)
			(effects
				(font
					(size 1 1)
					(thickness 0.15)
				)
				(justify mirror)
			)
		)
		(property "MPN" ""
			(at 202.29998 207.1016 0)
			(layer "B.Fab")
			(hide yes)
			(effects
				(font
					(size 1 1)
					(thickness 0.15)
				)
				(justify mirror)
			)
		)
		(property "Manufacturer" ""
			(at 202.29998 207.1016 0)
			(layer "B.Fab")
			(hide yes)
			(effects
				(font
					(size 1 1)
					(thickness 0.15)
				)
				(justify mirror)
			)
		)
		(sheetname "CSI")
		(sheetfile "csi.kicad_sch")
		(attr exclude_from_pos_files exclude_from_bom)
		(fp_circle
			(center 0 0)
			(end 0.475 0)
			(stroke
				(width 0.05)
				(type default)
			)
			(fill none)
			(layer "B.CrtYd")
		)
		(fp_text user "License: Apache-2.0"
			(at -0.4 -5.101 0)
			(layer "B.Fab")
			(hide yes)
			(effects
				(font
					(size 0.7 0.7)
					(thickness 0.15)
				)
				(justify left bottom mirror)
			)
		)
		(fp_text user "Author: Antmicro"
			(at -0.4 -3.901 0)
			(layer "B.Fab")
			(hide yes)
			(effects
				(font
					(size 0.7 0.7)
					(thickness 0.15)
				)
				(justify left bottom mirror)
			)
		)
		(fp_text user "${REFERENCE}"
			(at -0.4 -2.7 0)
			(layer "B.Fab")
			(hide yes)
			(effects
				(font
					(size 0.7 0.7)
					(thickness 0.15)
				)
				(justify left bottom mirror)
			)
		)
		(pad "1" smd circle
			(at 0 0 180)
			(size 0.75 0.75)
			(layers "B.Cu" "B.Mask")
			(net 539 "/CSI/MUX_I2C_6_SDA")
			(pinfunction "1")
			(pintype "passive")
		)
	)
	(footprint "antmicro-footprints:R_0402_1005Metric"
		(layer "B.Cu")
		(at 57.55 109.45 180)
		(descr "Resistor SMD 0402")
		(tags "resistor SMD 0402")
		(property "Reference" "R56"
			(at -2.97 -0.41 0)
			(layer "B.SilkS")
			(effects
				(font
					(size 0.7 0.7)
					(thickness 0.15)
				)
				(justify left bottom mirror)
			)
		)
		(property "Value" "R_0R_0402"
			(at 0 -1.4 0)
			(layer "B.Fab")
			(effects
				(font
					(size 0.7 0.7)
					(thickness 0.15)
				)
				(justify left bottom mirror)
			)
		)
		(property "Footprint" "antmicro-footprints:R_0402_1005Metric"
			(at 0 0 180)
			(layer "F.Fab")
			(hide yes)
			(effects
				(font
					(size 1.27 1.27)
					(thickness 0.15)
				)
			)
		)
		(property "Datasheet" "https://industrial.panasonic.com/cdbs/www-data/pdf/RDA0000/AOA0000C301.pdf"
			(at 0 0 180)
			(layer "F.Fab")
			(hide yes)
			(effects
				(font
					(size 1.27 1.27)
					(thickness 0.15)
				)
			)
		)
		(property "Author" "Antmicro"
			(at 115.1 218.9 0)
			(layer "B.Fab")
			(hide yes)
			(effects
				(font
					(size 1 1)
					(thickness 0.15)
				)
				(justify mirror)
			)
		)
		(property "Current" "1A"
			(at 115.1 218.9 0)
			(layer "B.Fab")
			(hide yes)
			(effects
				(font
					(size 1 1)
					(thickness 0.15)
				)
				(justify mirror)
			)
		)
		(property "License" "Apache-2.0"
			(at 115.1 218.9 0)
			(layer "B.Fab")
			(hide yes)
			(effects
				(font
					(size 1 1)
					(thickness 0.15)
				)
				(justify mirror)
			)
		)
		(property "MPN" "ERJ2GE0R00X"
			(at 115.1 218.9 0)
			(layer "B.Fab")
			(hide yes)
			(effects
				(font
					(size 1 1)
					(thickness 0.15)
				)
				(justify mirror)
			)
		)
		(property "Manufacturer" "Panasonic"
			(at 115.1 218.9 0)
			(layer "B.Fab")
			(hide yes)
			(effects
				(font
					(size 1 1)
					(thickness 0.15)
				)
				(justify mirror)
			)
		)
		(property "Tolerance" ""
			(at 115.1 218.9 0)
			(layer "B.Fab")
			(hide yes)
			(effects
				(font
					(size 1 1)
					(thickness 0.15)
				)
				(justify mirror)
			)
		)
		(property "Val" "0R"
			(at 115.1 218.9 0)
			(layer "B.Fab")
			(hide yes)
			(effects
				(font
					(size 1 1)
					(thickness 0.15)
				)
				(justify mirror)
			)
		)
		(sheetname "USB Debug, DP")
		(sheetfile "usb.kicad_sch")
		(attr smd)
		(fp_rect
			(start -0.925 0.47)
			(end 0.925 -0.47)
			(stroke
				(width 0.05)
				(type default)
			)
			(fill none)
			(layer "B.CrtYd")
		)
		(fp_rect
			(start -0.5 0.25)
			(end 0.5 -0.25)
			(stroke
				(width 0.15)
				(type solid)
			)
			(fill none)
			(layer "B.Fab")
		)
		(fp_text user "Author: Antmicro"
			(at -0.95 -4.169 0)
			(layer "B.Fab")
			(hide yes)
			(effects
				(font
					(size 0.7 0.7)
					(thickness 0.15)
				)
				(justify left bottom mirror)
			)
		)
		(fp_text user "${REFERENCE}"
			(at -0.95 -3.168 0)
			(layer "B.Fab")
			(hide yes)
			(effects
				(font
					(size 0.7 0.7)
					(thickness 0.15)
				)
				(justify left bottom mirror)
			)
		)
		(fp_text user "License: Apache-2.0"
			(at -0.95 -5.169 0)
			(layer "B.Fab")
			(hide yes)
			(effects
				(font
					(size 0.7 0.7)
					(thickness 0.15)
				)
				(justify left bottom mirror)
			)
		)
		(pad "1" smd roundrect
			(at -0.48 0 180)
			(size 0.59 0.64)
			(layers "B.Cu" "B.Paste" "B.Mask")
			(roundrect_rratio 0.25)
			(net 477 "DEBUG_RXD")
			(pintype "passive")
		)
		(pad "2" smd roundrect
			(at 0.48 0 180)
			(size 0.59 0.64)
			(layers "B.Cu" "B.Paste" "B.Mask")
			(roundrect_rratio 0.25)
			(net 646 "Net-(U5-TXD)")
			(pintype "passive")
		)
	)
	(footprint "antmicro-footprints:C_0402_1005Metric"
		(layer "B.Cu")
		(at 138.91 100.11 180)
		(descr "Capacitor SMD 0402")
		(tags "capacitor SMD 0402")
		(property "Reference" "C96"
			(at -1.04 -1.29 0)
			(layer "B.SilkS")
			(effects
				(font
					(size 0.7 0.7)
					(thickness 0.15)
				)
				(justify left bottom mirror)
			)
		)
		(property "Value" "C_100n_0402"
			(at 0 -1.4 0)
			(layer "B.Fab")
			(effects
				(font
					(size 0.7 0.7)
					(thickness 0.15)
				)
				(justify left bottom mirror)
			)
		)
		(property "Footprint" "antmicro-footprints:C_0402_1005Metric"
			(at 0 0 180)
			(layer "F.Fab")
			(hide yes)
			(effects
				(font
					(size 1.27 1.27)
					(thickness 0.15)
				)
			)
		)
		(property "Datasheet" "https://www.murata.com/products/productdetail?partno=GRM155R61H104KE14%23"
			(at 0 0 180)
			(layer "F.Fab")
			(hide yes)
			(effects
				(font
					(size 1.27 1.27)
					(thickness 0.15)
				)
			)
		)
		(property "Author" "Antmicro"
			(at 277.82 200.22 0)
			(layer "B.Fab")
			(hide yes)
			(effects
				(font
					(size 1 1)
					(thickness 0.15)
				)
				(justify mirror)
			)
		)
		(property "Dielectric" "X5R"
			(at 277.82 200.22 0)
			(layer "B.Fab")
			(hide yes)
			(effects
				(font
					(size 1 1)
					(thickness 0.15)
				)
				(justify mirror)
			)
		)
		(property "License" "Apache-2.0"
			(at 277.82 200.22 0)
			(layer "B.Fab")
			(hide yes)
			(effects
				(font
					(size 1 1)
					(thickness 0.15)
				)
				(justify mirror)
			)
		)
		(property "MPN" "GRM155R61H104KE14D"
			(at 277.82 200.22 0)
			(layer "B.Fab")
			(hide yes)
			(effects
				(font
					(size 1 1)
					(thickness 0.15)
				)
				(justify mirror)
			)
		)
		(property "Manufacturer" "Murata"
			(at 277.82 200.22 0)
			(layer "B.Fab")
			(hide yes)
			(effects
				(font
					(size 1 1)
					(thickness 0.15)
				)
				(justify mirror)
			)
		)
		(property "Val" "100n"
			(at 277.82 200.22 0)
			(layer "B.Fab")
			(hide yes)
			(effects
				(font
					(size 1 1)
					(thickness 0.15)
				)
				(justify mirror)
			)
		)
		(property "Voltage" "50V"
			(at 277.82 200.22 0)
			(layer "B.Fab")
			(hide yes)
			(effects
				(font
					(size 1 1)
					(thickness 0.15)
				)
				(justify mirror)
			)
		)
		(sheetname "CSI")
		(sheetfile "csi.kicad_sch")
		(attr smd)
		(fp_rect
			(start -0.925 0.47)
			(end 0.925 -0.47)
			(stroke
				(width 0.05)
				(type default)
			)
			(fill none)
			(layer "B.CrtYd")
		)
		(fp_line
			(start 0.504 0.25)
			(end -0.494 0.25)
			(stroke
				(width 0.15)
				(type solid)
			)
			(layer "B.Fab")
		)
		(fp_line
			(start 0.504 -0.248)
			(end 0.504 0.25)
			(stroke
				(width 0.15)
				(type solid)
			)
			(layer "B.Fab")
		)
		(fp_line
			(start -0.494 0.25)
			(end -0.494 -0.248)
			(stroke
				(width 0.15)
				(type solid)
			)
			(layer "B.Fab")
		)
		(fp_line
			(start -0.494 -0.248)
			(end 0.504 -0.248)
			(stroke
				(width 0.15)
				(type solid)
			)
			(layer "B.Fab")
		)
		(fp_text user "Author: Antmicro"
			(at -0.932 -4.17 0)
			(layer "B.Fab")
			(hide yes)
			(effects
				(font
					(size 0.7 0.7)
					(thickness 0.15)
				)
				(justify left bottom mirror)
			)
		)
		(fp_text user "${REFERENCE}"
			(at -0.932 -3.168 0)
			(layer "B.Fab")
			(hide yes)
			(effects
				(font
					(size 0.7 0.7)
					(thickness 0.15)
				)
				(justify left bottom mirror)
			)
		)
		(fp_text user "License: Apache-2.0"
			(at -0.932 -5.17 0)
			(layer "B.Fab")
			(hide yes)
			(effects
				(font
					(size 0.7 0.7)
					(thickness 0.15)
				)
				(justify left bottom mirror)
			)
		)
		(pad "1" smd roundrect
			(at -0.48 0 180)
			(size 0.59 0.64)
			(layers "B.Cu" "B.Paste" "B.Mask")
			(roundrect_rratio 0.25)
			(net 1 "GND")
			(pintype "passive")
		)
		(pad "2" smd roundrect
			(at 0.48 0 180)
			(size 0.59 0.64)
			(layers "B.Cu" "B.Paste" "B.Mask")
			(roundrect_rratio 0.25)
			(net 112 "+1V8")
			(pintype "passive")
		)
	)
	(footprint "antmicro-footprints:C_0402_1005Metric"
		(layer "B.Cu")
		(at 67.2 108.2 -90)
		(descr "Capacitor SMD 0402")
		(tags "capacitor SMD 0402")
		(property "Reference" "C26"
			(at -0.96 0.44 90)
			(layer "B.SilkS")
			(effects
				(font
					(size 0.7 0.7)
					(thickness 0.15)
				)
				(justify left bottom mirror)
			)
		)
		(property "Value" "C_100n_0402"
			(at 0 -1.4 90)
			(layer "B.Fab")
			(effects
				(font
					(size 0.7 0.7)
					(thickness 0.15)
				)
				(justify left bottom mirror)
			)
		)
		(property "Footprint" "antmicro-footprints:C_0402_1005Metric"
			(at 0 0 -90)
			(layer "F.Fab")
			(hide yes)
			(effects
				(font
					(size 1.27 1.27)
					(thickness 0.15)
				)
			)
		)
		(property "Datasheet" "https://www.murata.com/products/productdetail?partno=GRM155R61H104KE14%23"
			(at 0 0 -90)
			(layer "F.Fab")
			(hide yes)
			(effects
				(font
					(size 1.27 1.27)
					(thickness 0.15)
				)
			)
		)
		(property "Author" "Antmicro"
			(at -41 175.4 0)
			(layer "B.Fab")
			(hide yes)
			(effects
				(font
					(size 1 1)
					(thickness 0.15)
				)
				(justify mirror)
			)
		)
		(property "Dielectric" "X5R"
			(at -41 175.4 0)
			(layer "B.Fab")
			(hide yes)
			(effects
				(font
					(size 1 1)
					(thickness 0.15)
				)
				(justify mirror)
			)
		)
		(property "License" "Apache-2.0"
			(at -41 175.4 0)
			(layer "B.Fab")
			(hide yes)
			(effects
				(font
					(size 1 1)
					(thickness 0.15)
				)
				(justify mirror)
			)
		)
		(property "MPN" "GRM155R61H104KE14D"
			(at -41 175.4 0)
			(layer "B.Fab")
			(hide yes)
			(effects
				(font
					(size 1 1)
					(thickness 0.15)
				)
				(justify mirror)
			)
		)
		(property "Manufacturer" "Murata"
			(at -41 175.4 0)
			(layer "B.Fab")
			(hide yes)
			(effects
				(font
					(size 1 1)
					(thickness 0.15)
				)
				(justify mirror)
			)
		)
		(property "Val" "100n"
			(at -41 175.4 0)
			(layer "B.Fab")
			(hide yes)
			(effects
				(font
					(size 1 1)
					(thickness 0.15)
				)
				(justify mirror)
			)
		)
		(property "Voltage" "50V"
			(at -41 175.4 0)
			(layer "B.Fab")
			(hide yes)
			(effects
				(font
					(size 1 1)
					(thickness 0.15)
				)
				(justify mirror)
			)
		)
		(sheetname "USB Debug, DP")
		(sheetfile "usb.kicad_sch")
		(attr smd)
		(fp_rect
			(start -0.925 0.47)
			(end 0.925 -0.47)
			(stroke
				(width 0.05)
				(type default)
			)
			(fill none)
			(layer "B.CrtYd")
		)
		(fp_line
			(start -0.494 0.25)
			(end -0.494 -0.248)
			(stroke
				(width 0.15)
				(type solid)
			)
			(layer "B.Fab")
		)
		(fp_line
			(start 0.504 0.25)
			(end -0.494 0.25)
			(stroke
				(width 0.15)
				(type solid)
			)
			(layer "B.Fab")
		)
		(fp_line
			(start -0.494 -0.248)
			(end 0.504 -0.248)
			(stroke
				(width 0.15)
				(type solid)
			)
			(layer "B.Fab")
		)
		(fp_line
			(start 0.504 -0.248)
			(end 0.504 0.25)
			(stroke
				(width 0.15)
				(type solid)
			)
			(layer "B.Fab")
		)
		(fp_text user "License: Apache-2.0"
			(at -0.932 -5.17 90)
			(layer "B.Fab")
			(hide yes)
			(effects
				(font
					(size 0.7 0.7)
					(thickness 0.15)
				)
				(justify left bottom mirror)
			)
		)
		(fp_text user "${REFERENCE}"
			(at -0.932 -3.168 90)
			(layer "B.Fab")
			(hide yes)
			(effects
				(font
					(size 0.7 0.7)
					(thickness 0.15)
				)
				(justify left bottom mirror)
			)
		)
		(fp_text user "Author: Antmicro"
			(at -0.932 -4.17 90)
			(layer "B.Fab")
			(hide yes)
			(effects
				(font
					(size 0.7 0.7)
					(thickness 0.15)
				)
				(justify left bottom mirror)
			)
		)
		(pad "1" smd roundrect
			(at -0.48 0 270)
			(size 0.59 0.64)
			(layers "B.Cu" "B.Paste" "B.Mask")
			(roundrect_rratio 0.25)
			(net 87 "+3V3")
			(pintype "passive")
		)
		(pad "2" smd roundrect
			(at 0.48 0 270)
			(size 0.59 0.64)
			(layers "B.Cu" "B.Paste" "B.Mask")
			(roundrect_rratio 0.25)
			(net 1 "GND")
			(pintype "passive")
		)
	)
	(footprint "antmicro-footprints:R_0402_1005Metric"
		(layer "B.Cu")
		(at 46.3 80.1 90)
		(descr "Resistor SMD 0402")
		(tags "resistor SMD 0402")
		(property "Reference" "R164"
			(at 3.5 -0.5 -90)
			(layer "B.SilkS")
			(effects
				(font
					(size 0.7 0.7)
					(thickness 0.15)
				)
				(justify left bottom mirror)
			)
		)
		(property "Value" "R_4k7_0402"
			(at 0 -1.4 -90)
			(layer "B.Fab")
			(effects
				(font
					(size 0.7 0.7)
					(thickness 0.15)
				)
				(justify left bottom mirror)
			)
		)
		(property "Footprint" "antmicro-footprints:R_0402_1005Metric"
			(at 0 0 90)
			(layer "F.Fab")
			(hide yes)
			(effects
				(font
					(size 1.27 1.27)
					(thickness 0.15)
				)
			)
		)
		(property "Datasheet" "https://www.bourns.com/docs/product-datasheets/cr.pdf"
			(at 0 0 90)
			(layer "F.Fab")
			(hide yes)
			(effects
				(font
					(size 1.27 1.27)
					(thickness 0.15)
				)
			)
		)
		(property "Author" "Antmicro"
			(at 127.55 32.65 0)
			(layer "B.Fab")
			(hide yes)
			(effects
				(font
					(size 1 1)
					(thickness 0.15)
				)
				(justify mirror)
			)
		)
		(property "License" "Apache-2.0"
			(at 127.55 32.65 0)
			(layer "B.Fab")
			(hide yes)
			(effects
				(font
					(size 1 1)
					(thickness 0.15)
				)
				(justify mirror)
			)
		)
		(property "MPN" "CR0402-FX-4701GLF"
			(at 127.55 32.65 0)
			(layer "B.Fab")
			(hide yes)
			(effects
				(font
					(size 1 1)
					(thickness 0.15)
				)
				(justify mirror)
			)
		)
		(property "Manufacturer" "Bourns"
			(at 127.55 32.65 0)
			(layer "B.Fab")
			(hide yes)
			(effects
				(font
					(size 1 1)
					(thickness 0.15)
				)
				(justify mirror)
			)
		)
		(property "Tolerance" "1%"
			(at 127.55 32.65 0)
			(layer "B.Fab")
			(hide yes)
			(effects
				(font
					(size 1 1)
					(thickness 0.15)
				)
				(justify mirror)
			)
		)
		(property "Val" "4k7"
			(at 127.55 32.65 0)
			(layer "B.Fab")
			(hide yes)
			(effects
				(font
					(size 1 1)
					(thickness 0.15)
				)
				(justify mirror)
			)
		)
		(sheetname "Supply")
		(sheetfile "supply.kicad_sch")
		(attr smd)
		(fp_rect
			(start -0.925 0.47)
			(end 0.925 -0.47)
			(stroke
				(width 0.05)
				(type default)
			)
			(fill none)
			(layer "B.CrtYd")
		)
		(fp_rect
			(start -0.5 0.25)
			(end 0.5 -0.25)
			(stroke
				(width 0.15)
				(type solid)
			)
			(fill none)
			(layer "B.Fab")
		)
		(fp_text user "Author: Antmicro"
			(at -0.95 -4.169 -90)
			(layer "B.Fab")
			(hide yes)
			(effects
				(font
					(size 0.7 0.7)
					(thickness 0.15)
				)
				(justify left bottom mirror)
			)
		)
		(fp_text user "${REFERENCE}"
			(at -0.95 -3.168 -90)
			(layer "B.Fab")
			(hide yes)
			(effects
				(font
					(size 0.7 0.7)
					(thickness 0.15)
				)
				(justify left bottom mirror)
			)
		)
		(fp_text user "License: Apache-2.0"
			(at -0.95 -5.169 -90)
			(layer "B.Fab")
			(hide yes)
			(effects
				(font
					(size 0.7 0.7)
					(thickness 0.15)
				)
				(justify left bottom mirror)
			)
		)
		(pad "1" smd roundrect
			(at -0.48 0 90)
			(size 0.59 0.64)
			(layers "B.Cu" "B.Paste" "B.Mask")
			(roundrect_rratio 0.25)
			(net 135 "Net-(Q18-G)")
			(pintype "passive")
		)
		(pad "2" smd roundrect
			(at 0.48 0 90)
			(size 0.59 0.64)
			(layers "B.Cu" "B.Paste" "B.Mask")
			(roundrect_rratio 0.25)
			(net 328 "/Supply/VCC_IN")
			(pintype "passive")
		)
	)
	(footprint "antmicro-footprints:C_0402_1005Metric"
		(layer "B.Cu")
		(at 90.025 83.5)
		(descr "Capacitor SMD 0402")
		(tags "capacitor SMD 0402")
		(property "Reference" "C138"
			(at -0.875 0.47 180)
			(layer "B.SilkS")
			(effects
				(font
					(size 0.7 0.7)
					(thickness 0.15)
				)
				(justify left bottom mirror)
			)
		)
		(property "Value" "C_100n_0402"
			(at 0 -1.4 180)
			(layer "B.Fab")
			(effects
				(font
					(size 0.7 0.7)
					(thickness 0.15)
				)
				(justify left bottom mirror)
			)
		)
		(property "Footprint" "antmicro-footprints:C_0402_1005Metric"
			(at 0 0 0)
			(layer "F.Fab")
			(hide yes)
			(effects
				(font
					(size 1.27 1.27)
					(thickness 0.15)
				)
			)
		)
		(property "Datasheet" "https://www.murata.com/products/productdetail?partno=GRM155R61H104KE14%23"
			(at 0 0 0)
			(layer "F.Fab")
			(hide yes)
			(effects
				(font
					(size 1.27 1.27)
					(thickness 0.15)
				)
			)
		)
		(property "Author" "Antmicro"
			(at 0 0 0)
			(layer "B.Fab")
			(hide yes)
			(effects
				(font
					(size 1 1)
					(thickness 0.15)
				)
				(justify mirror)
			)
		)
		(property "Dielectric" "X5R"
			(at 0 0 0)
			(layer "B.Fab")
			(hide yes)
			(effects
				(font
					(size 1 1)
					(thickness 0.15)
				)
				(justify mirror)
			)
		)
		(property "License" "Apache-2.0"
			(at 0 0 0)
			(layer "B.Fab")
			(hide yes)
			(effects
				(font
					(size 1 1)
					(thickness 0.15)
				)
				(justify mirror)
			)
		)
		(property "MPN" "GRM155R61H104KE14D"
			(at 0 0 0)
			(layer "B.Fab")
			(hide yes)
			(effects
				(font
					(size 1 1)
					(thickness 0.15)
				)
				(justify mirror)
			)
		)
		(property "Manufacturer" "Murata"
			(at 0 0 0)
			(layer "B.Fab")
			(hide yes)
			(effects
				(font
					(size 1 1)
					(thickness 0.15)
				)
				(justify mirror)
			)
		)
		(property "Val" "100n"
			(at 0 0 0)
			(layer "B.Fab")
			(hide yes)
			(effects
				(font
					(size 1 1)
					(thickness 0.15)
				)
				(justify mirror)
			)
		)
		(property "Voltage" "50V"
			(at 0 0 0)
			(layer "B.Fab")
			(hide yes)
			(effects
				(font
					(size 1 1)
					(thickness 0.15)
				)
				(justify mirror)
			)
		)
		(sheetname "HDMI")
		(sheetfile "hdmi.kicad_sch")
		(attr smd)
		(fp_rect
			(start -0.925 0.47)
			(end 0.925 -0.47)
			(stroke
				(width 0.05)
				(type default)
			)
			(fill none)
			(layer "B.CrtYd")
		)
		(fp_line
			(start -0.494 -0.248)
			(end 0.504 -0.248)
			(stroke
				(width 0.15)
				(type solid)
			)
			(layer "B.Fab")
		)
		(fp_line
			(start -0.494 0.25)
			(end -0.494 -0.248)
			(stroke
				(width 0.15)
				(type solid)
			)
			(layer "B.Fab")
		)
		(fp_line
			(start 0.504 -0.248)
			(end 0.504 0.25)
			(stroke
				(width 0.15)
				(type solid)
			)
			(layer "B.Fab")
		)
		(fp_line
			(start 0.504 0.25)
			(end -0.494 0.25)
			(stroke
				(width 0.15)
				(type solid)
			)
			(layer "B.Fab")
		)
		(fp_text user "${REFERENCE}"
			(at -0.932 -3.168 180)
			(layer "B.Fab")
			(hide yes)
			(effects
				(font
					(size 0.7 0.7)
					(thickness 0.15)
				)
				(justify left bottom mirror)
			)
		)
		(fp_text user "License: Apache-2.0"
			(at -0.932 -5.17 180)
			(layer "B.Fab")
			(hide yes)
			(effects
				(font
					(size 0.7 0.7)
					(thickness 0.15)
				)
				(justify left bottom mirror)
			)
		)
		(fp_text user "Author: Antmicro"
			(at -0.932 -4.17 180)
			(layer "B.Fab")
			(hide yes)
			(effects
				(font
					(size 0.7 0.7)
					(thickness 0.15)
				)
				(justify left bottom mirror)
			)
		)
		(pad "1" smd roundrect
			(at -0.48 0)
			(size 0.59 0.64)
			(layers "B.Cu" "B.Paste" "B.Mask")
			(roundrect_rratio 0.25)
			(net 35 "DP1_AUX_N")
			(pintype "passive")
		)
		(pad "2" smd roundrect
			(at 0.48 0)
			(size 0.59 0.64)
			(layers "B.Cu" "B.Paste" "B.Mask")
			(roundrect_rratio 0.25)
			(net 668 "/HDMI/DP_MUX_AUX_B-")
			(pintype "passive")
		)
	)
	(footprint "antmicro-footprints:C_2220_5650Metric"
		(layer "B.Cu")
		(at 41.74 103.23 180)
		(descr "Capacitor SMD 2220")
		(tags "capacitor SMD 2220")
		(property "Reference" "C79"
			(at 1.54 3.06 0)
			(layer "B.SilkS")
			(effects
				(font
					(size 0.7 0.7)
					(thickness 0.15)
				)
				(justify left bottom mirror)
			)
		)
		(property "Value" "C_22u_100V_2220"
			(at 0 -3.9 0)
			(layer "B.Fab")
			(effects
				(font
					(size 0.7 0.7)
					(thickness 0.15)
				)
				(justify left bottom mirror)
			)
		)
		(property "Footprint" "antmicro-footprints:C_2220_5650Metric"
			(at 0 0 180)
			(layer "F.Fab")
			(hide yes)
			(effects
				(font
					(size 1.27 1.27)
					(thickness 0.15)
				)
			)
		)
		(property "Datasheet" "https://product.tdk.com/en/search/capacitor/ceramic/mlcc/info?part_no=C5750X7S2A226M280KB"
			(at 0 0 180)
			(layer "F.Fab")
			(hide yes)
			(effects
				(font
					(size 1.27 1.27)
					(thickness 0.15)
				)
			)
		)
		(property "Author" "Antmicro"
			(at 83.48 206.46 0)
			(layer "B.Fab")
			(hide yes)
			(effects
				(font
					(size 1 1)
					(thickness 0.15)
				)
				(justify mirror)
			)
		)
		(property "Dielectric" "X7S"
			(at 83.48 206.46 0)
			(layer "B.Fab")
			(hide yes)
			(effects
				(font
					(size 1 1)
					(thickness 0.15)
				)
				(justify mirror)
			)
		)
		(property "License" "Apache-2.0"
			(at 83.48 206.46 0)
			(layer "B.Fab")
			(hide yes)
			(effects
				(font
					(size 1 1)
					(thickness 0.15)
				)
				(justify mirror)
			)
		)
		(property "MPN" "C5750X7S2A226M280KB"
			(at 83.48 206.46 0)
			(layer "B.Fab")
			(hide yes)
			(effects
				(font
					(size 1 1)
					(thickness 0.15)
				)
				(justify mirror)
			)
		)
		(property "Manufacturer" "TDK"
			(at 83.48 206.46 0)
			(layer "B.Fab")
			(hide yes)
			(effects
				(font
					(size 1 1)
					(thickness 0.15)
				)
				(justify mirror)
			)
		)
		(property "Public" "False"
			(at 83.48 206.46 0)
			(layer "B.Fab")
			(hide yes)
			(effects
				(font
					(size 1 1)
					(thickness 0.15)
				)
				(justify mirror)
			)
		)
		(property "Val" "22u"
			(at 83.48 206.46 0)
			(layer "B.Fab")
			(hide yes)
			(effects
				(font
					(size 1 1)
					(thickness 0.15)
				)
				(justify mirror)
			)
		)
		(property "Voltage" "100V"
			(at 83.48 206.46 0)
			(layer "B.Fab")
			(hide yes)
			(effects
				(font
					(size 1 1)
					(thickness 0.15)
				)
				(justify mirror)
			)
		)
		(sheetname "Ethernet")
		(sheetfile "ethernet.kicad_sch")
		(attr smd)
		(fp_line
			(start 1.415 2.61)
			(end -1.415 2.61)
			(stroke
				(width 0.15)
				(type solid)
			)
			(layer "B.SilkS")
		)
		(fp_line
			(start 1.415 -2.61)
			(end -1.415 -2.61)
			(stroke
				(width 0.15)
				(type solid)
			)
			(layer "B.SilkS")
		)
		(fp_rect
			(start -3.7 2.95)
			(end 3.7 -2.95)
			(stroke
				(width 0.05)
				(type solid)
			)
			(fill none)
			(layer "B.CrtYd")
		)
		(fp_rect
			(start -2.85 2.5)
			(end 2.85 -2.5)
			(stroke
				(width 0.15)
				(type solid)
			)
			(fill none)
			(layer "B.Fab")
		)
		(fp_text user "Author: Antmicro"
			(at -3.7 -7.9 0)
			(layer "B.Fab")
			(hide yes)
			(effects
				(font
					(size 0.7 0.7)
					(thickness 0.15)
				)
				(justify left bottom mirror)
			)
		)
		(fp_text user "License: Apache-2.0"
			(at -3.7 -6.9 0)
			(layer "B.Fab")
			(hide yes)
			(effects
				(font
					(size 0.7 0.7)
					(thickness 0.15)
				)
				(justify left bottom mirror)
			)
		)
		(fp_text user "${REFERENCE}"
			(at -3.7 -5.9 0)
			(layer "B.Fab")
			(hide yes)
			(effects
				(font
					(size 0.7 0.7)
					(thickness 0.15)
				)
				(justify left bottom mirror)
			)
		)
		(pad "1" smd roundrect
			(at -2.55 0 180)
			(size 1.8 5.4)
			(layers "B.Cu" "B.Paste" "B.Mask")
			(roundrect_rratio 0.138889)
			(net 106 "GNDD")
			(pintype "passive")
		)
		(pad "2" smd roundrect
			(at 2.55 0 180)
			(size 1.8 5.4)
			(layers "B.Cu" "B.Paste" "B.Mask")
			(roundrect_rratio 0.138889)
			(net 105 "/Ethernet/VDD")
			(pintype "passive")
		)
	)
	(footprint "antmicro-footprints:IC_TPS65987DDHRSHR"
		(layer "B.Cu")
		(at 66.3 103.1 90)
		(property "Reference" "U6"
			(at -1.8 4.7 -90)
			(layer "B.SilkS")
			(effects
				(font
					(size 0.7 0.7)
					(thickness 0.15)
				)
				(justify left bottom mirror)
			)
		)
		(property "Value" "TPS65988DHRSHR"
			(at 0 -4.9 -90)
			(layer "B.Fab")
			(effects
				(font
					(size 0.7 0.7)
					(thickness 0.15)
				)
				(justify left bottom mirror)
			)
		)
		(property "Footprint" "antmicro-footprints:IC_TPS65987DDHRSHR"
			(at 0 0 90)
			(layer "F.Fab")
			(hide yes)
			(effects
				(font
					(size 1.27 1.27)
					(thickness 0.15)
				)
			)
		)
		(property "Datasheet" "https://www.ti.com/lit/ds/symlink/tps65988.pdf?ts=1662726631004&ref_url=https%253A%252F%252Fwww.ti.com%252Fproduct%252FTPS65988"
			(at 0 0 90)
			(layer "F.Fab")
			(hide yes)
			(effects
				(font
					(size 1.27 1.27)
					(thickness 0.15)
				)
			)
		)
		(property "Author" "Antmicro"
			(at 169.4 36.8 0)
			(layer "B.Fab")
			(hide yes)
			(effects
				(font
					(size 1 1)
					(thickness 0.15)
				)
				(justify mirror)
			)
		)
		(property "License" "Apache-2.0"
			(at 169.4 36.8 0)
			(layer "B.Fab")
			(hide yes)
			(effects
				(font
					(size 1 1)
					(thickness 0.15)
				)
				(justify mirror)
			)
		)
		(property "MPN" "TPS65988DHRSHR "
			(at 169.4 36.8 0)
			(layer "B.Fab")
			(hide yes)
			(effects
				(font
					(size 1 1)
					(thickness 0.15)
				)
				(justify mirror)
			)
		)
		(property "Manufacturer" "Texas Instruments"
			(at 169.4 36.8 0)
			(layer "B.Fab")
			(hide yes)
			(effects
				(font
					(size 1 1)
					(thickness 0.15)
				)
				(justify mirror)
			)
		)
		(sheetname "USB Debug, DP")
		(sheetfile "usb.kicad_sch")
		(attr smd)
		(fp_poly
			(pts
				(xy -2.61 -1.574) (xy -1.141 -1.574) (xy -1.141 -2.725) (xy -2.61 -2.725)
			)
			(stroke
				(width 0.01)
				(type solid)
			)
			(fill solid)
			(layer "B.Paste")
		)
		(fp_poly
			(pts
				(xy 1.148 -1.419) (xy 2.62 -1.419) (xy 2.62 -2.539) (xy 1.148 -2.539)
			)
			(stroke
				(width 0.01)
				(type solid)
			)
			(fill solid)
			(layer "B.Paste")
		)
		(fp_poly
			(pts
				(xy -0.522 -1.419) (xy 0.949 -1.419) (xy 0.949 -2.539) (xy -0.522 -2.539)
			)
			(stroke
				(width 0.01)
				(type solid)
			)
			(fill solid)
			(layer "B.Paste")
		)
		(fp_poly
			(pts
				(xy -2.61 -0.225) (xy -1.141 -0.225) (xy -1.141 -1.374) (xy -2.61 -1.374)
			)
			(stroke
				(width 0.01)
				(type solid)
			)
			(fill solid)
			(layer "B.Paste")
		)
		(fp_poly
			(pts
				(xy 1.148 -0.1) (xy 2.62 -0.1) (xy 2.62 -1.219) (xy 1.148 -1.219)
			)
			(stroke
				(width 0.01)
				(type solid)
			)
			(fill solid)
			(layer "B.Paste")
		)
		(fp_poly
			(pts
				(xy -0.522 -0.1) (xy 0.949 -0.1) (xy 0.949 -1.219) (xy -0.522 -1.219)
			)
			(stroke
				(width 0.01)
				(type solid)
			)
			(fill solid)
			(layer "B.Paste")
		)
		(fp_poly
			(pts
				(xy 1.148 1.22) (xy 2.62 1.22) (xy 2.62 0.102) (xy 1.148 0.102)
			)
			(stroke
				(width 0.01)
				(type solid)
			)
			(fill solid)
			(layer "B.Paste")
		)
		(fp_poly
			(pts
				(xy -0.522 1.22) (xy 0.949 1.22) (xy 0.949 0.102) (xy -0.522 0.102)
			)
			(stroke
				(width 0.01)
				(type solid)
			)
			(fill solid)
			(layer "B.Paste")
		)
		(fp_poly
			(pts
				(xy -2.61 1.351) (xy -1.141 1.351) (xy -1.141 0.202) (xy -2.61 0.202)
			)
			(stroke
				(width 0.01)
				(type solid)
			)
			(fill solid)
			(layer "B.Paste")
		)
		(fp_poly
			(pts
				(xy 1.148 2.54) (xy 2.62 2.54) (xy 2.62 1.42) (xy 1.148 1.42)
			)
			(stroke
				(width 0.01)
				(type solid)
			)
			(fill solid)
			(layer "B.Paste")
		)
		(fp_poly
			(pts
				(xy -0.522 2.54) (xy 0.949 2.54) (xy 0.949 1.42) (xy -0.522 1.42)
			)
			(stroke
				(width 0.01)
				(type solid)
			)
			(fill solid)
			(layer "B.Paste")
		)
		(fp_poly
			(pts
				(xy -2.61 2.702) (xy -1.141 2.702) (xy -1.141 1.551) (xy -2.61 1.551)
			)
			(stroke
				(width 0.01)
				(type solid)
			)
			(fill solid)
			(layer "B.Paste")
		)
		(fp_poly
			(pts
				(xy -3.65 -2.1) (xy -3.051 -2.1) (xy -3.048 -2.1) (xy -3.045 -2.1) (xy -3.043 -2.1) (xy -3.04 -2.1)
				(xy -3.037 -2.1) (xy -3.036 -2.1) (xy -3.032 -2.103) (xy -3.031 -2.104) (xy -3.028 -2.104) (xy -3.025 -2.107)
				(xy -3.024 -2.108) (xy -3.021 -2.108) (xy -3.02 -2.111) (xy -3.017 -2.112) (xy -3.016 -2.115) (xy -3.013 -2.116)
				(xy -3.012 -2.119) (xy -3.011 -2.12) (xy -3.008 -2.123) (xy -3.008 -2.124) (xy -3.005 -2.125) (xy -3.004 -2.128)
				(xy -3.004 -2.132) (xy -3.003 -2.133) (xy -3.003 -2.136) (xy -3.001 -2.14) (xy -3 -2.144) (xy -3 -2.145)
				(xy -3 -2.148) (xy -3 -2.648) (xy -3 -2.652) (xy -3 -2.653) (xy -3.001 -2.656) (xy -3.001 -2.66)
				(xy -3.003 -2.661) (xy -3.003 -2.664) (xy -3.004 -2.668) (xy -3.005 -2.672) (xy -3.008 -2.673) (xy -3.008 -2.676)
				(xy -3.011 -2.677) (xy -3.012 -2.68) (xy -3.013 -2.681) (xy -3.016 -2.684) (xy -3.017 -2.685) (xy -3.02 -2.689)
				(xy -3.021 -2.689) (xy -3.024 -2.692) (xy -3.025 -2.693) (xy -3.028 -2.693) (xy -3.031 -2.696) (xy -3.032 -2.697)
				(xy -3.036 -2.697) (xy -3.037 -2.697) (xy -3.04 -2.697) (xy -3.043 -2.697) (xy -3.045 -2.7) (xy -3.048 -2.7)
				(xy -3.051 -2.7) (xy -3.65 -2.7) (xy -3.653 -2.7) (xy -3.656 -2.7) (xy -3.658 -2.697) (xy -3.661 -2.697)
				(xy -3.664 -2.697) (xy -3.665 -2.697) (xy -3.669 -2.697) (xy -3.67 -2.696) (xy -3.673 -2.693) (xy -3.676 -2.693)
				(xy -3.677 -2.692) (xy -3.68 -2.689) (xy -3.681 -2.689) (xy -3.684 -2.685) (xy -3.685 -2.684) (xy -3.688 -2.681)
				(xy -3.689 -2.68) (xy -3.69 -2.677) (xy -3.693 -2.676) (xy -3.693 -2.673) (xy -3.696 -2.672) (xy -3.697 -2.668)
				(xy -3.698 -2.664) (xy -3.698 -2.661) (xy -3.7 -2.66) (xy -3.7 -2.656) (xy -3.701 -2.653) (xy -3.701 -2.652)
				(xy -3.701 -2.648) (xy -3.701 -2.548) (xy -3.701 -2.547) (xy -3.701 -2.543) (xy -3.7 -2.54) (xy -3.7 -2.539)
				(xy -3.698 -2.535) (xy -3.697 -2.531) (xy -3.697 -2.528) (xy -3.696 -2.527) (xy -3.693 -2.523) (xy -3.69 -2.519)
				(xy -3.689 -2.519) (xy -3.688 -2.515) (xy -3.685 -2.515) (xy -3.684 -2.511) (xy -3.681 -2.511) (xy -3.68 -2.508)
				(xy -3.677 -2.507) (xy -3.676 -2.507) (xy -3.673 -2.503) (xy -3.67 -2.503) (xy -3.669 -2.503) (xy -3.665 -2.5)
				(xy -3.664 -2.5) (xy -3.661 -2.499) (xy -3.658 -2.499) (xy -3.656 -2.499) (xy -3.653 -2.499) (xy -3.65 -2.499)
				(xy -3.25 -2.499) (xy -3.247 -2.499) (xy -3.246 -2.499) (xy -3.242 -2.499) (xy -3.238 -2.498) (xy -3.235 -2.498)
				(xy -3.234 -2.495) (xy -3.23 -2.495) (xy -3.227 -2.495) (xy -3.226 -2.491) (xy -3.223 -2.491) (xy -3.222 -2.49)
				(xy -3.219 -2.487) (xy -3.218 -2.487) (xy -3.215 -2.483) (xy -3.214 -2.483) (xy -3.211 -2.479) (xy -3.21 -2.479)
				(xy -3.21 -2.475) (xy -3.207 -2.475) (xy -3.206 -2.471) (xy -3.206 -2.47) (xy -3.203 -2.467) (xy -3.202 -2.463)
				(xy -3.202 -2.459) (xy -3.202 -2.458) (xy -3.202 -2.455) (xy -3.202 -2.451) (xy -3.202 -2.45) (xy -3.202 -2.35)
				(xy -3.202 -2.346) (xy -3.202 -2.345) (xy -3.202 -2.342) (xy -3.202 -2.338) (xy -3.202 -2.337) (xy -3.202 -2.334)
				(xy -3.203 -2.33) (xy -3.206 -2.33) (xy -3.206 -2.326) (xy -3.207 -2.325) (xy -3.21 -2.322) (xy -3.21 -2.321)
				(xy -3.211 -2.318) (xy -3.214 -2.317) (xy -3.215 -2.314) (xy -3.218 -2.313) (xy -3.219 -2.31) (xy -3.222 -2.31)
				(xy -3.223 -2.306) (xy -3.226 -2.306) (xy -3.227 -2.305) (xy -3.23 -2.302) (xy -3.234 -2.301) (xy -3.235 -2.301)
				(xy -3.238 -2.301) (xy -3.242 -2.301) (xy -3.246 -2.298) (xy -3.247 -2.298) (xy -3.25 -2.298) (xy -3.65 -2.298)
				(xy -3.653 -2.298) (xy -3.656 -2.298) (xy -3.658 -2.297) (xy -3.661 -2.297) (xy -3.664 -2.297) (xy -3.665 -2.297)
				(xy -3.669 -2.297) (xy -3.67 -2.294) (xy -3.673 -2.293) (xy -3.676 -2.293) (xy -3.677 -2.29) (xy -3.68 -2.289)
				(xy -3.681 -2.289) (xy -3.684 -2.285) (xy -3.685 -2.285) (xy -3.688 -2.281) (xy -3.689 -2.281) (xy -3.69 -2.277)
				(xy -3.693 -2.277) (xy -3.693 -2.273) (xy -3.696 -2.273) (xy -3.697 -2.269) (xy -3.697 -2.266) (xy -3.698 -2.265)
				(xy -3.698 -2.261) (xy -3.7 -2.258) (xy -3.7 -2.257) (xy -3.701 -2.253) (xy -3.701 -2.249) (xy -3.701 -2.148)
				(xy -3.701 -2.145) (xy -3.701 -2.144) (xy -3.7 -2.14) (xy -3.698 -2.136) (xy -3.698 -2.133) (xy -3.697 -2.132)
				(xy -3.697 -2.128) (xy -3.696 -2.125) (xy -3.693 -2.124) (xy -3.693 -2.123) (xy -3.69 -2.12) (xy -3.689 -2.119)
				(xy -3.688 -2.116) (xy -3.685 -2.115) (xy -3.684 -2.112) (xy -3.681 -2.111) (xy -3.68 -2.108) (xy -3.677 -2.108)
				(xy -3.676 -2.107) (xy -3.673 -2.104) (xy -3.67 -2.104) (xy -3.669 -2.103) (xy -3.665 -2.1) (xy -3.664 -2.1)
				(xy -3.661 -2.1) (xy -3.658 -2.1) (xy -3.656 -2.1) (xy -3.653 -2.1) (xy -3.65 -2.1)
			)
			(stroke
				(width 0.0001)
				(type solid)
			)
			(fill solid)
			(layer "B.Paste")
		)
		(fp_poly
			(pts
				(xy -3.65 2.702) (xy -3.051 2.702) (xy -3.048 2.702) (xy -3.045 2.702) (xy -3.043 2.699) (xy -3.04 2.699)
				(xy -3.037 2.698) (xy -3.036 2.698) (xy -3.032 2.698) (xy -3.031 2.698) (xy -3.028 2.695) (xy -3.025 2.694)
				(xy -3.024 2.694) (xy -3.021 2.69) (xy -3.02 2.69) (xy -3.017 2.688) (xy -3.016 2.685) (xy -3.013 2.684)
				(xy -3.012 2.681) (xy -3.011 2.68) (xy -3.008 2.677) (xy -3.008 2.676) (xy -3.005 2.673) (xy -3.004 2.67)
				(xy -3.004 2.669) (xy -3.003 2.665) (xy -3.003 2.664) (xy -3.001 2.661) (xy -3.001 2.658) (xy -3 2.656)
				(xy -3 2.653) (xy -3 2.65) (xy -3 2.15) (xy -3 2.148) (xy -3 2.145) (xy -3.001 2.142) (xy -3.001 2.141)
				(xy -3.003 2.137) (xy -3.003 2.136) (xy -3.004 2.133) (xy -3.004 2.13) (xy -3.005 2.128) (xy -3.008 2.125)
				(xy -3.011 2.121) (xy -3.012 2.121) (xy -3.013 2.117) (xy -3.016 2.117) (xy -3.017 2.113) (xy -3.02 2.113)
				(xy -3.021 2.11) (xy -3.024 2.109) (xy -3.025 2.109) (xy -3.028 2.105) (xy -3.031 2.105) (xy -3.032 2.105)
				(xy -3.036 2.102) (xy -3.037 2.102) (xy -3.04 2.101) (xy -3.043 2.101) (xy -3.045 2.101) (xy -3.048 2.101)
				(xy -3.051 2.101) (xy -3.65 2.101) (xy -3.653 2.101) (xy -3.656 2.101) (xy -3.658 2.101) (xy -3.661 2.101)
				(xy -3.664 2.102) (xy -3.665 2.102) (xy -3.669 2.105) (xy -3.67 2.105) (xy -3.673 2.105) (xy -3.676 2.109)
				(xy -3.677 2.109) (xy -3.68 2.11) (xy -3.681 2.113) (xy -3.684 2.113) (xy -3.685 2.117) (xy -3.688 2.117)
				(xy -3.689 2.121) (xy -3.69 2.121) (xy -3.693 2.125) (xy -3.696 2.128) (xy -3.697 2.13) (xy -3.697 2.133)
				(xy -3.698 2.136) (xy -3.698 2.137) (xy -3.7 2.141) (xy -3.7 2.142) (xy -3.701 2.145) (xy -3.701 2.148)
				(xy -3.701 2.15) (xy -3.701 2.25) (xy -3.701 2.254) (xy -3.701 2.255) (xy -3.7 2.258) (xy -3.7 2.261)
				(xy -3.698 2.263) (xy -3.698 2.266) (xy -3.697 2.269) (xy -3.697 2.27) (xy -3.696 2.274) (xy -3.693 2.275)
				(xy -3.693 2.278) (xy -3.69 2.279) (xy -3.689 2.282) (xy -3.688 2.283) (xy -3.685 2.286) (xy -3.684 2.287)
				(xy -3.681 2.29) (xy -3.68 2.29) (xy -3.677 2.293) (xy -3.676 2.294) (xy -3.673 2.295) (xy -3.67 2.297)
				(xy -3.669 2.298) (xy -3.665 2.298) (xy -3.664 2.298) (xy -3.661 2.299) (xy -3.658 2.299) (xy -3.656 2.301)
				(xy -3.653 2.301) (xy -3.65 2.301) (xy -3.25 2.301) (xy -3.247 2.301) (xy -3.246 2.301) (xy -3.242 2.302)
				(xy -3.238 2.302) (xy -3.235 2.302) (xy -3.234 2.303) (xy -3.23 2.305) (xy -3.227 2.307) (xy -3.226 2.307)
				(xy -3.223 2.308) (xy -3.222 2.311) (xy -3.219 2.311) (xy -3.218 2.315) (xy -3.215 2.315) (xy -3.214 2.319)
				(xy -3.211 2.319) (xy -3.21 2.323) (xy -3.207 2.327) (xy -3.206 2.327) (xy -3.206 2.331) (xy -3.203 2.332)
				(xy -3.202 2.335) (xy -3.202 2.339) (xy -3.202 2.34) (xy -3.202 2.343) (xy -3.202 2.347) (xy -3.202 2.351)
				(xy -3.202 2.452) (xy -3.202 2.453) (xy -3.202 2.456) (xy -3.202 2.46) (xy -3.202 2.464) (xy -3.202 2.465)
				(xy -3.203 2.468) (xy -3.206 2.472) (xy -3.206 2.473) (xy -3.207 2.476) (xy -3.21 2.477) (xy -3.21 2.48)
				(xy -3.211 2.481) (xy -3.214 2.484) (xy -3.215 2.485) (xy -3.218 2.488) (xy -3.219 2.489) (xy -3.222 2.492)
				(xy -3.223 2.492) (xy -3.226 2.493) (xy -3.227 2.496) (xy -3.23 2.496) (xy -3.234 2.497) (xy -3.235 2.5)
				(xy -3.238 2.5) (xy -3.242 2.5) (xy -3.246 2.5) (xy -3.247 2.5) (xy -3.25 2.5) (xy -3.65 2.5) (xy -3.653 2.5)
				(xy -3.656 2.5) (xy -3.658 2.501) (xy -3.661 2.501) (xy -3.664 2.503) (xy -3.665 2.503) (xy -3.669 2.504)
				(xy -3.67 2.504) (xy -3.673 2.505) (xy -3.676 2.508) (xy -3.677 2.508) (xy -3.68 2.511) (xy -3.681 2.512)
				(xy -3.684 2.513) (xy -3.685 2.516) (xy -3.688 2.517) (xy -3.689 2.52) (xy -3.69 2.521) (xy -3.693 2.524)
				(xy -3.693 2.525) (xy -3.696 2.528) (xy -3.697 2.531) (xy -3.697 2.532) (xy -3.698 2.536) (xy -3.698 2.537)
				(xy -3.7 2.54) (xy -3.7 2.543) (xy -3.701 2.545) (xy -3.701 2.548) (xy -3.701 2.551) (xy -3.701 2.65)
				(xy -3.701 2.653) (xy -3.701 2.656) (xy -3.7 2.658) (xy -3.7 2.661) (xy -3.698 2.664) (xy -3.698 2.665)
				(xy -3.697 2.669) (xy -3.697 2.67) (xy -3.696 2.673) (xy -3.693 2.676) (xy -3.693 2.677) (xy -3.69 2.68)
				(xy -3.689 2.681) (xy -3.688 2.684) (xy -3.685 2.685) (xy -3.684 2.688) (xy -3.681 2.69) (xy -3.68 2.69)
				(xy -3.677 2.694) (xy -3.676 2.694) (xy -3.673 2.695) (xy -3.67 2.698) (xy -3.669 2.698) (xy -3.665 2.698)
				(xy -3.664 2.698) (xy -3.661 2.699) (xy -3.658 2.699) (xy -3.656 2.702) (xy -3.653 2.702) (xy -3.65 2.702)
			)
			(stroke
				(width 0.0001)
				(type solid)
			)
			(fill solid)
			(layer "B.Paste")
		)
		(fp_poly
			(pts
				(xy -3.65 -1.3) (xy -3.051 -1.3) (xy -3.048 -1.3) (xy -3.045 -1.3) (xy -3.043 -1.3) (xy -3.04 -1.3)
				(xy -3.037 -1.302) (xy -3.036 -1.302) (xy -3.032 -1.302) (xy -3.031 -1.304) (xy -3.028 -1.304) (xy -3.025 -1.306)
				(xy -3.024 -1.308) (xy -3.021 -1.31) (xy -3.02 -1.31) (xy -3.017 -1.312) (xy -3.016 -1.314) (xy -3.013 -1.316)
				(xy -3.012 -1.318) (xy -3.011 -1.32) (xy -3.008 -1.322) (xy -3.008 -1.324) (xy -3.005 -1.326) (xy -3.004 -1.33)
				(xy -3.004 -1.332) (xy -3.003 -1.334) (xy -3.003 -1.336) (xy -3.001 -1.34) (xy -3.001 -1.342) (xy -3 -1.344)
				(xy -3 -1.346) (xy -3 -1.35) (xy -3 -1.85) (xy -3 -1.852) (xy -3 -1.854) (xy -3.001 -1.858) (xy -3.001 -1.86)
				(xy -3.003 -1.862) (xy -3.003 -1.864) (xy -3.004 -1.868) (xy -3.004 -1.87) (xy -3.005 -1.872) (xy -3.008 -1.874)
				(xy -3.008 -1.876) (xy -3.011 -1.878) (xy -3.012 -1.88) (xy -3.013 -1.882) (xy -3.016 -1.884) (xy -3.017 -1.886)
				(xy -3.02 -1.888) (xy -3.021 -1.888) (xy -3.024 -1.89) (xy -3.025 -1.892) (xy -3.028 -1.894) (xy -3.031 -1.894)
				(xy -3.032 -1.896) (xy -3.036 -1.896) (xy -3.037 -1.896) (xy -3.04 -1.898) (xy -3.043 -1.898) (xy -3.045 -1.898)
				(xy -3.048 -1.898) (xy -3.051 -1.898) (xy -3.65 -1.898) (xy -3.653 -1.898) (xy -3.656 -1.898) (xy -3.658 -1.898)
				(xy -3.661 -1.898) (xy -3.664 -1.896) (xy -3.665 -1.896) (xy -3.669 -1.896) (xy -3.67 -1.894) (xy -3.673 -1.894)
				(xy -3.676 -1.892) (xy -3.677 -1.89) (xy -3.68 -1.888) (xy -3.681 -1.888) (xy -3.684 -1.886) (xy -3.685 -1.884)
				(xy -3.688 -1.882) (xy -3.689 -1.88) (xy -3.69 -1.878) (xy -3.693 -1.876) (xy -3.693 -1.874) (xy -3.696 -1.872)
				(xy -3.697 -1.87) (xy -3.697 -1.868) (xy -3.698 -1.864) (xy -3.698 -1.862) (xy -3.7 -1.86) (xy -3.7 -1.858)
				(xy -3.701 -1.854) (xy -3.701 -1.852) (xy -3.701 -1.85) (xy -3.701 -1.749) (xy -3.701 -1.747) (xy -3.701 -1.745)
				(xy -3.7 -1.741) (xy -3.7 -1.739) (xy -3.698 -1.737) (xy -3.698 -1.735) (xy -3.697 -1.731) (xy -3.697 -1.729)
				(xy -3.696 -1.727) (xy -3.693 -1.725) (xy -3.693 -1.723) (xy -3.69 -1.721) (xy -3.689 -1.719) (xy -3.688 -1.717)
				(xy -3.685 -1.715) (xy -3.684 -1.713) (xy -3.681 -1.711) (xy -3.68 -1.709) (xy -3.677 -1.707) (xy -3.676 -1.707)
				(xy -3.673 -1.705) (xy -3.67 -1.703) (xy -3.669 -1.703) (xy -3.665 -1.701) (xy -3.664 -1.701) (xy -3.661 -1.701)
				(xy -3.658 -1.701) (xy -3.656 -1.699) (xy -3.653 -1.699) (xy -3.65 -1.699) (xy -3.25 -1.699) (xy -3.247 -1.699)
				(xy -3.246 -1.699) (xy -3.242 -1.699) (xy -3.238 -1.697) (xy -3.235 -1.697) (xy -3.234 -1.697) (xy -3.23 -1.695)
				(xy -3.227 -1.695) (xy -3.226 -1.693) (xy -3.223 -1.691) (xy -3.222 -1.689) (xy -3.219 -1.689) (xy -3.218 -1.687)
				(xy -3.215 -1.685) (xy -3.214 -1.683) (xy -3.211 -1.681) (xy -3.21 -1.679) (xy -3.21 -1.677) (xy -3.207 -1.675)
				(xy -3.206 -1.673) (xy -3.206 -1.669) (xy -3.203 -1.667) (xy -3.202 -1.665) (xy -3.202 -1.662) (xy -3.202 -1.658)
				(xy -3.202 -1.656) (xy -3.202 -1.654) (xy -3.202 -1.652) (xy -3.202 -1.648) (xy -3.202 -1.55) (xy -3.202 -1.546)
				(xy -3.202 -1.544) (xy -3.202 -1.542) (xy -3.202 -1.54) (xy -3.202 -1.536) (xy -3.202 -1.533) (xy -3.203 -1.531)
				(xy -3.206 -1.529) (xy -3.206 -1.525) (xy -3.207 -1.523) (xy -3.21 -1.521) (xy -3.21 -1.519) (xy -3.211 -1.517)
				(xy -3.214 -1.515) (xy -3.215 -1.513) (xy -3.218 -1.511) (xy -3.219 -1.509) (xy -3.222 -1.509) (xy -3.223 -1.507)
				(xy -3.226 -1.505) (xy -3.227 -1.503) (xy -3.23 -1.503) (xy -3.234 -1.501) (xy -3.235 -1.501) (xy -3.238 -1.501)
				(xy -3.242 -1.499) (xy -3.246 -1.499) (xy -3.247 -1.499) (xy -3.25 -1.499) (xy -3.65 -1.499) (xy -3.653 -1.499)
				(xy -3.656 -1.499) (xy -3.658 -1.499) (xy -3.661 -1.499) (xy -3.664 -1.497) (xy -3.665 -1.497) (xy -3.669 -1.497)
				(xy -3.67 -1.495) (xy -3.673 -1.495) (xy -3.676 -1.493) (xy -3.677 -1.491) (xy -3.68 -1.489) (xy -3.681 -1.489)
				(xy -3.684 -1.487) (xy -3.685 -1.485) (xy -3.688 -1.483) (xy -3.689 -1.481) (xy -3.69 -1.479) (xy -3.693 -1.477)
				(xy -3.693 -1.475) (xy -3.696 -1.473) (xy -3.697 -1.469) (xy -3.697 -1.467) (xy -3.698 -1.465) (xy -3.698 -1.463)
				(xy -3.7 -1.459) (xy -3.7 -1.457) (xy -3.701 -1.455) (xy -3.701 -1.453) (xy -3.701 -1.449) (xy -3.701 -1.35)
				(xy -3.701 -1.346) (xy -3.701 -1.344) (xy -3.7 -1.342) (xy -3.7 -1.34) (xy -3.698 -1.336) (xy -3.698 -1.334)
				(xy -3.697 -1.332) (xy -3.697 -1.33) (xy -3.696 -1.326) (xy -3.693 -1.324) (xy -3.693 -1.322) (xy -3.69 -1.32)
				(xy -3.689 -1.318) (xy -3.688 -1.316) (xy -3.685 -1.314) (xy -3.684 -1.312) (xy -3.681 -1.31) (xy -3.68 -1.31)
				(xy -3.677 -1.308) (xy -3.676 -1.306) (xy -3.673 -1.304) (xy -3.67 -1.304) (xy -3.669 -1.302) (xy -3.665 -1.302)
				(xy -3.664 -1.302) (xy -3.661 -1.3) (xy -3.658 -1.3) (xy -3.656 -1.3) (xy -3.653 -1.3) (xy -3.65 -1.3)
			)
			(stroke
				(width 0.0001)
				(type solid)
			)
			(fill solid)
			(layer "B.Paste")
		)
		(fp_poly
			(pts
				(xy -3.65 1.901) (xy -3.051 1.901) (xy -3.048 1.901) (xy -3.045 1.901) (xy -3.043 1.899) (xy -3.04 1.899)
				(xy -3.037 1.899) (xy -3.036 1.899) (xy -3.032 1.897) (xy -3.031 1.897) (xy -3.028 1.895) (xy -3.025 1.893)
				(xy -3.024 1.893) (xy -3.021 1.891) (xy -3.02 1.889) (xy -3.017 1.887) (xy -3.016 1.885) (xy -3.013 1.883)
				(xy -3.012 1.881) (xy -3.011 1.879) (xy -3.008 1.877) (xy -3.008 1.875) (xy -3.005 1.873) (xy -3.004 1.871)
				(xy -3.004 1.869) (xy -3.003 1.865) (xy -3.003 1.863) (xy -3.001 1.861) (xy -3.001 1.859) (xy -3 1.855)
				(xy -3 1.853) (xy -3 1.851) (xy -3 1.351) (xy -3 1.347) (xy -3 1.345) (xy -3.001 1.343) (xy -3.001 1.341)
				(xy -3.003 1.337) (xy -3.003 1.335) (xy -3.004 1.333) (xy -3.004 1.331) (xy -3.005 1.327) (xy -3.008 1.325)
				(xy -3.008 1.323) (xy -3.011 1.321) (xy -3.012 1.319) (xy -3.013 1.317) (xy -3.016 1.315) (xy -3.017 1.313)
				(xy -3.02 1.311) (xy -3.021 1.311) (xy -3.024 1.309) (xy -3.025 1.307) (xy -3.028 1.305) (xy -3.031 1.305)
				(xy -3.032 1.303) (xy -3.036 1.303) (xy -3.037 1.303) (xy -3.04 1.301) (xy -3.043 1.301) (xy -3.045 1.301)
				(xy -3.048 1.301) (xy -3.051 1.301) (xy -3.65 1.301) (xy -3.653 1.301) (xy -3.656 1.301) (xy -3.658 1.301)
				(xy -3.661 1.301) (xy -3.664 1.303) (xy -3.665 1.303) (xy -3.669 1.303) (xy -3.67 1.305) (xy -3.673 1.305)
				(xy -3.676 1.307) (xy -3.677 1.309) (xy -3.68 1.311) (xy -3.681 1.311) (xy -3.684 1.313) (xy -3.685 1.315)
				(xy -3.688 1.317) (xy -3.689 1.319) (xy -3.69 1.321) (xy -3.693 1.323) (xy -3.693 1.325) (xy -3.696 1.327)
				(xy -3.697 1.331) (xy -3.697 1.333) (xy -3.698 1.335) (xy -3.698 1.337) (xy -3.7 1.341) (xy -3.7 1.343)
				(xy -3.701 1.345) (xy -3.701 1.347) (xy -3.701 1.351) (xy -3.701 1.45) (xy -3.701 1.454) (xy -3.701 1.456)
				(xy -3.7 1.458) (xy -3.7 1.46) (xy -3.698 1.464) (xy -3.698 1.466) (xy -3.697 1.468) (xy -3.697 1.47)
				(xy -3.696 1.474) (xy -3.693 1.476) (xy -3.693 1.478) (xy -3.69 1.48) (xy -3.689 1.482) (xy -3.688 1.484)
				(xy -3.685 1.486) (xy -3.684 1.488) (xy -3.681 1.49) (xy -3.68 1.49) (xy -3.677 1.492) (xy -3.676 1.494)
				(xy -3.673 1.496) (xy -3.67 1.496) (xy -3.669 1.498) (xy -3.665 1.498) (xy -3.664 1.498) (xy -3.661 1.5)
				(xy -3.658 1.5) (xy -3.656 1.5) (xy -3.653 1.5) (xy -3.65 1.5) (xy -3.25 1.5) (xy -3.247 1.5) (xy -3.246 1.5)
				(xy -3.242 1.502) (xy -3.238 1.502) (xy -3.235 1.502) (xy -3.234 1.504) (xy -3.23 1.504) (xy -3.227 1.506)
				(xy -3.226 1.508) (xy -3.223 1.508) (xy -3.222 1.51) (xy -3.219 1.512) (xy -3.218 1.514) (xy -3.215 1.516)
				(xy -3.214 1.518) (xy -3.211 1.52) (xy -3.21 1.522) (xy -3.21 1.524) (xy -3.207 1.526) (xy -3.206 1.528)
				(xy -3.206 1.53) (xy -3.203 1.532) (xy -3.202 1.536) (xy -3.202 1.537) (xy -3.202 1.541) (xy -3.202 1.543)
				(xy -3.202 1.545) (xy -3.202 1.547) (xy -3.202 1.551) (xy -3.202 1.651) (xy -3.202 1.653) (xy -3.202 1.655)
				(xy -3.202 1.659) (xy -3.202 1.661) (xy -3.202 1.663) (xy -3.202 1.666) (xy -3.203 1.668) (xy -3.206 1.67)
				(xy -3.206 1.674) (xy -3.207 1.676) (xy -3.21 1.678) (xy -3.21 1.68) (xy -3.211 1.682) (xy -3.214 1.684)
				(xy -3.215 1.686) (xy -3.218 1.688) (xy -3.219 1.69) (xy -3.222 1.69) (xy -3.223 1.692) (xy -3.226 1.694)
				(xy -3.227 1.696) (xy -3.23 1.696) (xy -3.234 1.698) (xy -3.235 1.698) (xy -3.238 1.698) (xy -3.242 1.7)
				(xy -3.246 1.7) (xy -3.247 1.7) (xy -3.25 1.7) (xy -3.65 1.7) (xy -3.653 1.7) (xy -3.656 1.7) (xy -3.658 1.702)
				(xy -3.661 1.702) (xy -3.664 1.702) (xy -3.665 1.702) (xy -3.669 1.704) (xy -3.67 1.704) (xy -3.673 1.706)
				(xy -3.676 1.708) (xy -3.677 1.708) (xy -3.68 1.71) (xy -3.681 1.712) (xy -3.684 1.714) (xy -3.685 1.716)
				(xy -3.688 1.718) (xy -3.689 1.72) (xy -3.69 1.722) (xy -3.693 1.724) (xy -3.693 1.726) (xy -3.696 1.728)
				(xy -3.697 1.73) (xy -3.697 1.732) (xy -3.698 1.736) (xy -3.698 1.738) (xy -3.7 1.74) (xy -3.7 1.742)
				(xy -3.701 1.746) (xy -3.701 1.748) (xy -3.701 1.75) (xy -3.701 1.851) (xy -3.701 1.853) (xy -3.701 1.855)
				(xy -3.7 1.859) (xy -3.7 1.861) (xy -3.698 1.863) (xy -3.698 1.865) (xy -3.697 1.869) (xy -3.697 1.871)
				(xy -3.696 1.873) (xy -3.693 1.875) (xy -3.693 1.877) (xy -3.69 1.879) (xy -3.689 1.881) (xy -3.688 1.883)
				(xy -3.685 1.885) (xy -3.684 1.887) (xy -3.681 1.889) (xy -3.68 1.891) (xy -3.677 1.893) (xy -3.676 1.893)
				(xy -3.673 1.895) (xy -3.67 1.897) (xy -3.669 1.897) (xy -3.665 1.899) (xy -3.664 1.899) (xy -3.661 1.899)
				(xy -3.658 1.899) (xy -3.656 1.901) (xy -3.653 1.901) (xy -3.65 1.901)
			)
			(stroke
				(width 0.0001)
				(type solid)
			)
			(fill solid)
			(layer "B.Paste")
		)
		(fp_line
			(start 3.499 -3.499)
			(end 2.898 -3.499)
			(stroke
				(width 0.15)
				(type solid)
			)
			(layer "B.SilkS")
		)
		(fp_line
			(start -3.5 -3.499)
			(end -2.9 -3.499)
			(stroke
				(width 0.15)
				(type solid)
			)
			(layer "B.SilkS")
		)
		(fp_line
			(start -3.5 -2.999)
			(end -3.5 -3.499)
			(stroke
				(width 0.15)
				(type solid)
			)
			(layer "B.SilkS")
		)
		(fp_line
			(start 3.499 -2.898)
			(end 3.499 -3.499)
			(stroke
				(width 0.15)
				(type solid)
			)
			(layer "B.SilkS")
		)
		(fp_line
			(start 3.499 2.9)
			(end 3.499 3.5)
			(stroke
				(width 0.15)
				(type solid)
			)
			(layer "B.SilkS")
		)
		(fp_line
			(start -3.5 3)
			(end -3.5 3.5)
			(stroke
				(width 0.15)
				(type solid)
			)
			(layer "B.SilkS")
		)
		(fp_line
			(start 3.499 3.5)
			(end 2.898 3.5)
			(stroke
				(width 0.15)
				(type solid)
			)
			(layer "B.SilkS")
		)
		(fp_line
			(start -3.5 3.5)
			(end -2.9 3.5)
			(stroke
				(width 0.15)
				(type solid)
			)
			(layer "B.SilkS")
		)
		(fp_circle
			(center -4.3 2.4)
			(end -4.25 2.36)
			(stroke
				(width 0.15)
				(type solid)
			)
			(fill solid)
			(layer "B.SilkS")
		)
		(fp_poly
			(pts
				(xy -3.65 -2.1) (xy -3.051 -2.1) (xy -3.048 -2.1) (xy -3.045 -2.1) (xy -3.043 -2.1) (xy -3.04 -2.1)
				(xy -3.037 -2.1) (xy -3.036 -2.1) (xy -3.032 -2.103) (xy -3.031 -2.104) (xy -3.028 -2.104) (xy -3.025 -2.107)
				(xy -3.024 -2.108) (xy -3.021 -2.108) (xy -3.02 -2.111) (xy -3.017 -2.112) (xy -3.016 -2.115) (xy -3.013 -2.116)
				(xy -3.012 -2.119) (xy -3.011 -2.12) (xy -3.008 -2.123) (xy -3.008 -2.124) (xy -3.005 -2.125) (xy -3.004 -2.128)
				(xy -3.004 -2.132) (xy -3.003 -2.133) (xy -3.003 -2.136) (xy -3.001 -2.14) (xy -3 -2.144) (xy -3 -2.145)
				(xy -3 -2.148) (xy -3 -2.648) (xy -3 -2.652) (xy -3 -2.653) (xy -3.001 -2.656) (xy -3.001 -2.66)
				(xy -3.003 -2.661) (xy -3.003 -2.664) (xy -3.004 -2.668) (xy -3.005 -2.672) (xy -3.008 -2.673) (xy -3.008 -2.676)
				(xy -3.011 -2.677) (xy -3.012 -2.68) (xy -3.013 -2.681) (xy -3.016 -2.684) (xy -3.017 -2.685) (xy -3.02 -2.689)
				(xy -3.021 -2.689) (xy -3.024 -2.692) (xy -3.025 -2.693) (xy -3.028 -2.693) (xy -3.031 -2.696) (xy -3.032 -2.697)
				(xy -3.036 -2.697) (xy -3.037 -2.697) (xy -3.04 -2.697) (xy -3.043 -2.697) (xy -3.045 -2.7) (xy -3.048 -2.7)
				(xy -3.051 -2.7) (xy -3.65 -2.7) (xy -3.653 -2.7) (xy -3.656 -2.7) (xy -3.658 -2.697) (xy -3.661 -2.697)
				(xy -3.664 -2.697) (xy -3.665 -2.697) (xy -3.669 -2.697) (xy -3.67 -2.696) (xy -3.673 -2.693) (xy -3.676 -2.693)
				(xy -3.677 -2.692) (xy -3.68 -2.689) (xy -3.681 -2.689) (xy -3.684 -2.685) (xy -3.685 -2.684) (xy -3.688 -2.681)
				(xy -3.689 -2.68) (xy -3.69 -2.677) (xy -3.693 -2.676) (xy -3.693 -2.673) (xy -3.696 -2.672) (xy -3.697 -2.668)
				(xy -3.698 -2.664) (xy -3.698 -2.661) (xy -3.7 -2.66) (xy -3.7 -2.656) (xy -3.701 -2.653) (xy -3.701 -2.652)
				(xy -3.701 -2.648) (xy -3.701 -2.548) (xy -3.701 -2.547) (xy -3.701 -2.543) (xy -3.7 -2.54) (xy -3.7 -2.539)
				(xy -3.698 -2.535) (xy -3.697 -2.531) (xy -3.697 -2.528) (xy -3.696 -2.527) (xy -3.693 -2.523) (xy -3.69 -2.519)
				(xy -3.689 -2.519) (xy -3.688 -2.515) (xy -3.685 -2.515) (xy -3.684 -2.511) (xy -3.681 -2.511) (xy -3.68 -2.508)
				(xy -3.677 -2.507) (xy -3.676 -2.507) (xy -3.673 -2.503) (xy -3.67 -2.503) (xy -3.669 -2.503) (xy -3.665 -2.5)
				(xy -3.664 -2.5) (xy -3.661 -2.499) (xy -3.658 -2.499) (xy -3.656 -2.499) (xy -3.653 -2.499) (xy -3.65 -2.499)
				(xy -3.25 -2.499) (xy -3.247 -2.499) (xy -3.246 -2.499) (xy -3.242 -2.499) (xy -3.238 -2.498) (xy -3.235 -2.498)
				(xy -3.234 -2.495) (xy -3.23 -2.495) (xy -3.227 -2.495) (xy -3.226 -2.491) (xy -3.223 -2.491) (xy -3.222 -2.49)
				(xy -3.219 -2.487) (xy -3.218 -2.487) (xy -3.215 -2.483) (xy -3.214 -2.483) (xy -3.211 -2.479) (xy -3.21 -2.479)
				(xy -3.21 -2.475) (xy -3.207 -2.475) (xy -3.206 -2.471) (xy -3.206 -2.47) (xy -3.203 -2.467) (xy -3.202 -2.463)
				(xy -3.202 -2.459) (xy -3.202 -2.458) (xy -3.202 -2.455) (xy -3.202 -2.451) (xy -3.202 -2.45) (xy -3.202 -2.35)
				(xy -3.202 -2.346) (xy -3.202 -2.345) (xy -3.202 -2.342) (xy -3.202 -2.338) (xy -3.202 -2.337) (xy -3.202 -2.334)
				(xy -3.203 -2.33) (xy -3.206 -2.33) (xy -3.206 -2.326) (xy -3.207 -2.325) (xy -3.21 -2.322) (xy -3.21 -2.321)
				(xy -3.211 -2.318) (xy -3.214 -2.317) (xy -3.215 -2.314) (xy -3.218 -2.313) (xy -3.219 -2.31) (xy -3.222 -2.31)
				(xy -3.223 -2.306) (xy -3.226 -2.306) (xy -3.227 -2.305) (xy -3.23 -2.302) (xy -3.234 -2.301) (xy -3.235 -2.301)
				(xy -3.238 -2.301) (xy -3.242 -2.301) (xy -3.246 -2.298) (xy -3.247 -2.298) (xy -3.25 -2.298) (xy -3.65 -2.298)
				(xy -3.653 -2.298) (xy -3.656 -2.298) (xy -3.658 -2.297) (xy -3.661 -2.297) (xy -3.664 -2.297) (xy -3.665 -2.297)
				(xy -3.669 -2.297) (xy -3.67 -2.294) (xy -3.673 -2.293) (xy -3.676 -2.293) (xy -3.677 -2.29) (xy -3.68 -2.289)
				(xy -3.681 -2.289) (xy -3.684 -2.285) (xy -3.685 -2.285) (xy -3.688 -2.281) (xy -3.689 -2.281) (xy -3.69 -2.277)
				(xy -3.693 -2.277) (xy -3.693 -2.273) (xy -3.696 -2.273) (xy -3.697 -2.269) (xy -3.697 -2.266) (xy -3.698 -2.265)
				(xy -3.698 -2.261) (xy -3.7 -2.258) (xy -3.7 -2.257) (xy -3.701 -2.253) (xy -3.701 -2.249) (xy -3.701 -2.148)
				(xy -3.701 -2.145) (xy -3.701 -2.144) (xy -3.7 -2.14) (xy -3.698 -2.136) (xy -3.698 -2.133) (xy -3.697 -2.132)
				(xy -3.697 -2.128) (xy -3.696 -2.125) (xy -3.693 -2.124) (xy -3.693 -2.123) (xy -3.69 -2.12) (xy -3.689 -2.119)
				(xy -3.688 -2.116) (xy -3.685 -2.115) (xy -3.684 -2.112) (xy -3.681 -2.111) (xy -3.68 -2.108) (xy -3.677 -2.108)
				(xy -3.676 -2.107) (xy -3.673 -2.104) (xy -3.67 -2.104) (xy -3.669 -2.103) (xy -3.665 -2.1) (xy -3.664 -2.1)
				(xy -3.661 -2.1) (xy -3.658 -2.1) (xy -3.656 -2.1) (xy -3.653 -2.1) (xy -3.65 -2.1)
			)
			(stroke
				(width 0.0001)
				(type solid)
			)
			(fill solid)
			(layer "B.Mask")
		)
		(fp_poly
			(pts
				(xy -3.65 2.701) (xy -3.051 2.701) (xy -3.048 2.701) (xy -3.045 2.701) (xy -3.043 2.698) (xy -3.04 2.698)
				(xy -3.037 2.697) (xy -3.036 2.697) (xy -3.032 2.697) (xy -3.031 2.697) (xy -3.028 2.694) (xy -3.025 2.693)
				(xy -3.024 2.693) (xy -3.021 2.689) (xy -3.02 2.689) (xy -3.017 2.687) (xy -3.016 2.684) (xy -3.013 2.683)
				(xy -3.012 2.68) (xy -3.011 2.679) (xy -3.008 2.676) (xy -3.008 2.675) (xy -3.005 2.672) (xy -3.004 2.669)
				(xy -3.004 2.668) (xy -3.003 2.664) (xy -3.003 2.663) (xy -3.001 2.66) (xy -3.001 2.657) (xy -3 2.655)
				(xy -3 2.652) (xy -3 2.649) (xy -3 2.149) (xy -3 2.147) (xy -3 2.144) (xy -3.001 2.141) (xy -3.001 2.14)
				(xy -3.003 2.136) (xy -3.003 2.135) (xy -3.004 2.132) (xy -3.004 2.129) (xy -3.005 2.127) (xy -3.008 2.124)
				(xy -3.011 2.12) (xy -3.012 2.12) (xy -3.013 2.116) (xy -3.016 2.116) (xy -3.017 2.112) (xy -3.02 2.112)
				(xy -3.021 2.109) (xy -3.024 2.108) (xy -3.025 2.108) (xy -3.028 2.104) (xy -3.031 2.104) (xy -3.032 2.104)
				(xy -3.036 2.101) (xy -3.037 2.101) (xy -3.04 2.1) (xy -3.043 2.1) (xy -3.045 2.1) (xy -3.048 2.1)
				(xy -3.051 2.1) (xy -3.65 2.1) (xy -3.653 2.1) (xy -3.656 2.1) (xy -3.658 2.1) (xy -3.661 2.1) (xy -3.664 2.101)
				(xy -3.665 2.101) (xy -3.669 2.104) (xy -3.67 2.104) (xy -3.673 2.104) (xy -3.676 2.108) (xy -3.677 2.108)
				(xy -3.68 2.109) (xy -3.681 2.112) (xy -3.684 2.112) (xy -3.685 2.116) (xy -3.688 2.116) (xy -3.689 2.12)
				(xy -3.69 2.12) (xy -3.693 2.124) (xy -3.696 2.127) (xy -3.697 2.129) (xy -3.697 2.132) (xy -3.698 2.135)
				(xy -3.698 2.136) (xy -3.7 2.14) (xy -3.7 2.141) (xy -3.701 2.144) (xy -3.701 2.147) (xy -3.701 2.149)
				(xy -3.701 2.249) (xy -3.701 2.253) (xy -3.701 2.254) (xy -3.7 2.257) (xy -3.7 2.26) (xy -3.698 2.262)
				(xy -3.698 2.265) (xy -3.697 2.268) (xy -3.697 2.269) (xy -3.696 2.273) (xy -3.693 2.274) (xy -3.693 2.277)
				(xy -3.69 2.278) (xy -3.689 2.281) (xy -3.688 2.282) (xy -3.685 2.285) (xy -3.684 2.286) (xy -3.681 2.289)
				(xy -3.68 2.289) (xy -3.677 2.292) (xy -3.676 2.293) (xy -3.673 2.294) (xy -3.67 2.296) (xy -3.669 2.297)
				(xy -3.665 2.297) (xy -3.664 2.297) (xy -3.661 2.298) (xy -3.658 2.298) (xy -3.656 2.3) (xy -3.653 2.3)
				(xy -3.65 2.3) (xy -3.25 2.3) (xy -3.247 2.3) (xy -3.246 2.3) (xy -3.242 2.301) (xy -3.238 2.301)
				(xy -3.235 2.301) (xy -3.234 2.302) (xy -3.23 2.304) (xy -3.227 2.306) (xy -3.226 2.306) (xy -3.223 2.307)
				(xy -3.222 2.31) (xy -3.219 2.31) (xy -3.218 2.314) (xy -3.215 2.314) (xy -3.214 2.318) (xy -3.211 2.318)
				(xy -3.21 2.322) (xy -3.207 2.326) (xy -3.206 2.326) (xy -3.206 2.33) (xy -3.203 2.331) (xy -3.202 2.334)
				(xy -3.202 2.338) (xy -3.202 2.339) (xy -3.202 2.342) (xy -3.202 2.346) (xy -3.202 2.35) (xy -3.202 2.451)
				(xy -3.202 2.452) (xy -3.202 2.455) (xy -3.202 2.459) (xy -3.202 2.463) (xy -3.202 2.464) (xy -3.203 2.467)
				(xy -3.206 2.471) (xy -3.206 2.472) (xy -3.207 2.475) (xy -3.21 2.476) (xy -3.21 2.479) (xy -3.211 2.48)
				(xy -3.214 2.483) (xy -3.215 2.484) (xy -3.218 2.487) (xy -3.219 2.488) (xy -3.222 2.491) (xy -3.223 2.491)
				(xy -3.226 2.492) (xy -3.227 2.495) (xy -3.23 2.495) (xy -3.234 2.496) (xy -3.235 2.499) (xy -3.238 2.499)
				(xy -3.242 2.499) (xy -3.246 2.499) (xy -3.247 2.499) (xy -3.25 2.499) (xy -3.65 2.499) (xy -3.653 2.499)
				(xy -3.656 2.499) (xy -3.658 2.5) (xy -3.661 2.5) (xy -3.664 2.502) (xy -3.665 2.502) (xy -3.669 2.503)
				(xy -3.67 2.503) (xy -3.673 2.504) (xy -3.676 2.507) (xy -3.677 2.507) (xy -3.68 2.51) (xy -3.681 2.511)
				(xy -3.684 2.512) (xy -3.685 2.515) (xy -3.688 2.516) (xy -3.689 2.519) (xy -3.69 2.52) (xy -3.693 2.523)
				(xy -3.693 2.524) (xy -3.696 2.527) (xy -3.697 2.53) (xy -3.697 2.531) (xy -3.698 2.535) (xy -3.698 2.536)
				(xy -3.7 2.539) (xy -3.7 2.542) (xy -3.701 2.544) (xy -3.701 2.547) (xy -3.701 2.55) (xy -3.701 2.649)
				(xy -3.701 2.652) (xy -3.701 2.655) (xy -3.7 2.657) (xy -3.7 2.66) (xy -3.698 2.663) (xy -3.698 2.664)
				(xy -3.697 2.668) (xy -3.697 2.669) (xy -3.696 2.672) (xy -3.693 2.675) (xy -3.693 2.676) (xy -3.69 2.679)
				(xy -3.689 2.68) (xy -3.688 2.683) (xy -3.685 2.684) (xy -3.684 2.687) (xy -3.681 2.689) (xy -3.68 2.689)
				(xy -3.677 2.693) (xy -3.676 2.693) (xy -3.673 2.694) (xy -3.67 2.697) (xy -3.669 2.697) (xy -3.665 2.697)
				(xy -3.664 2.697) (xy -3.661 2.698) (xy -3.658 2.698) (xy -3.656 2.701) (xy -3.653 2.701) (xy -3.65 2.701)
			)
			(stroke
				(width 0.0001)
				(type solid)
			)
			(fill solid)
			(layer "B.Mask")
		)
		(fp_poly
			(pts
				(xy -3.65 -1.3) (xy -3.051 -1.3) (xy -3.048 -1.3) (xy -3.045 -1.3) (xy -3.043 -1.3) (xy -3.04 -1.3)
				(xy -3.037 -1.302) (xy -3.036 -1.302) (xy -3.032 -1.302) (xy -3.031 -1.304) (xy -3.028 -1.304) (xy -3.025 -1.306)
				(xy -3.024 -1.308) (xy -3.021 -1.31) (xy -3.02 -1.31) (xy -3.017 -1.312) (xy -3.016 -1.314) (xy -3.013 -1.316)
				(xy -3.012 -1.318) (xy -3.011 -1.32) (xy -3.008 -1.322) (xy -3.008 -1.324) (xy -3.005 -1.326) (xy -3.004 -1.33)
				(xy -3.004 -1.332) (xy -3.003 -1.334) (xy -3.003 -1.336) (xy -3.001 -1.34) (xy -3.001 -1.342) (xy -3 -1.344)
				(xy -3 -1.346) (xy -3 -1.35) (xy -3 -1.85) (xy -3 -1.852) (xy -3 -1.854) (xy -3.001 -1.858) (xy -3.001 -1.86)
				(xy -3.003 -1.862) (xy -3.003 -1.864) (xy -3.004 -1.868) (xy -3.004 -1.87) (xy -3.005 -1.872) (xy -3.008 -1.874)
				(xy -3.008 -1.876) (xy -3.011 -1.878) (xy -3.012 -1.88) (xy -3.013 -1.882) (xy -3.016 -1.884) (xy -3.017 -1.886)
				(xy -3.02 -1.888) (xy -3.021 -1.888) (xy -3.024 -1.89) (xy -3.025 -1.892) (xy -3.028 -1.894) (xy -3.031 -1.894)
				(xy -3.032 -1.896) (xy -3.036 -1.896) (xy -3.037 -1.896) (xy -3.04 -1.898) (xy -3.043 -1.898) (xy -3.045 -1.898)
				(xy -3.048 -1.898) (xy -3.051 -1.898) (xy -3.65 -1.898) (xy -3.653 -1.898) (xy -3.656 -1.898) (xy -3.658 -1.898)
				(xy -3.661 -1.898) (xy -3.664 -1.896) (xy -3.665 -1.896) (xy -3.669 -1.896) (xy -3.67 -1.894) (xy -3.673 -1.894)
				(xy -3.676 -1.892) (xy -3.677 -1.89) (xy -3.68 -1.888) (xy -3.681 -1.888) (xy -3.684 -1.886) (xy -3.685 -1.884)
				(xy -3.688 -1.882) (xy -3.689 -1.88) (xy -3.69 -1.878) (xy -3.693 -1.876) (xy -3.693 -1.874) (xy -3.696 -1.872)
				(xy -3.697 -1.87) (xy -3.697 -1.868) (xy -3.698 -1.864) (xy -3.698 -1.862) (xy -3.7 -1.86) (xy -3.7 -1.858)
				(xy -3.701 -1.854) (xy -3.701 -1.852) (xy -3.701 -1.85) (xy -3.701 -1.749) (xy -3.701 -1.747) (xy -3.701 -1.745)
				(xy -3.7 -1.741) (xy -3.7 -1.739) (xy -3.698 -1.737) (xy -3.698 -1.735) (xy -3.697 -1.731) (xy -3.697 -1.729)
				(xy -3.696 -1.727) (xy -3.693 -1.725) (xy -3.693 -1.723) (xy -3.69 -1.721) (xy -3.689 -1.719) (xy -3.688 -1.717)
				(xy -3.685 -1.715) (xy -3.684 -1.713) (xy -3.681 -1.711) (xy -3.68 -1.709) (xy -3.677 -1.707) (xy -3.676 -1.707)
				(xy -3.673 -1.705) (xy -3.67 -1.703) (xy -3.669 -1.703) (xy -3.665 -1.701) (xy -3.664 -1.701) (xy -3.661 -1.701)
				(xy -3.658 -1.701) (xy -3.656 -1.699) (xy -3.653 -1.699) (xy -3.65 -1.699) (xy -3.25 -1.699) (xy -3.247 -1.699)
				(xy -3.246 -1.699) (xy -3.242 -1.699) (xy -3.238 -1.697) (xy -3.235 -1.697) (xy -3.234 -1.697) (xy -3.23 -1.695)
				(xy -3.227 -1.695) (xy -3.226 -1.693) (xy -3.223 -1.691) (xy -3.222 -1.689) (xy -3.219 -1.689) (xy -3.218 -1.687)
				(xy -3.215 -1.685) (xy -3.214 -1.683) (xy -3.211 -1.681) (xy -3.21 -1.679) (xy -3.21 -1.677) (xy -3.207 -1.675)
				(xy -3.206 -1.673) (xy -3.206 -1.669) (xy -3.203 -1.667) (xy -3.202 -1.665) (xy -3.202 -1.662) (xy -3.202 -1.658)
				(xy -3.202 -1.656) (xy -3.202 -1.654) (xy -3.202 -1.652) (xy -3.202 -1.648) (xy -3.202 -1.55) (xy -3.202 -1.546)
				(xy -3.202 -1.544) (xy -3.202 -1.542) (xy -3.202 -1.54) (xy -3.202 -1.536) (xy -3.202 -1.533) (xy -3.203 -1.531)
				(xy -3.206 -1.529) (xy -3.206 -1.525) (xy -3.207 -1.523) (xy -3.21 -1.521) (xy -3.21 -1.519) (xy -3.211 -1.517)
				(xy -3.214 -1.515) (xy -3.215 -1.513) (xy -3.218 -1.511) (xy -3.219 -1.509) (xy -3.222 -1.509) (xy -3.223 -1.507)
				(xy -3.226 -1.505) (xy -3.227 -1.503) (xy -3.23 -1.503) (xy -3.234 -1.501) (xy -3.235 -1.501) (xy -3.238 -1.501)
				(xy -3.242 -1.499) (xy -3.246 -1.499) (xy -3.247 -1.499) (xy -3.25 -1.499) (xy -3.65 -1.499) (xy -3.653 -1.499)
				(xy -3.656 -1.499) (xy -3.658 -1.499) (xy -3.661 -1.499) (xy -3.664 -1.497) (xy -3.665 -1.497) (xy -3.669 -1.497)
				(xy -3.67 -1.495) (xy -3.673 -1.495) (xy -3.676 -1.493) (xy -3.677 -1.491) (xy -3.68 -1.489) (xy -3.681 -1.489)
				(xy -3.684 -1.487) (xy -3.685 -1.485) (xy -3.688 -1.483) (xy -3.689 -1.481) (xy -3.69 -1.479) (xy -3.693 -1.477)
				(xy -3.693 -1.475) (xy -3.696 -1.473) (xy -3.697 -1.469) (xy -3.697 -1.467) (xy -3.698 -1.465) (xy -3.698 -1.463)
				(xy -3.7 -1.459) (xy -3.7 -1.457) (xy -3.701 -1.455) (xy -3.701 -1.453) (xy -3.701 -1.449) (xy -3.701 -1.35)
				(xy -3.701 -1.346) (xy -3.701 -1.344) (xy -3.7 -1.342) (xy -3.7 -1.34) (xy -3.698 -1.336) (xy -3.698 -1.334)
				(xy -3.697 -1.332) (xy -3.697 -1.33) (xy -3.696 -1.326) (xy -3.693 -1.324) (xy -3.693 -1.322) (xy -3.69 -1.32)
				(xy -3.689 -1.318) (xy -3.688 -1.316) (xy -3.685 -1.314) (xy -3.684 -1.312) (xy -3.681 -1.31) (xy -3.68 -1.31)
				(xy -3.677 -1.308) (xy -3.676 -1.306) (xy -3.673 -1.304) (xy -3.67 -1.304) (xy -3.669 -1.302) (xy -3.665 -1.302)
				(xy -3.664 -1.302) (xy -3.661 -1.3) (xy -3.658 -1.3) (xy -3.656 -1.3) (xy -3.653 -1.3) (xy -3.65 -1.3)
			)
			(stroke
				(width 0.0001)
				(type solid)
			)
			(fill solid)
			(layer "B.Mask")
		)
		(fp_poly
			(pts
				(xy -3.65 1.901) (xy -3.051 1.901) (xy -3.048 1.901) (xy -3.045 1.901) (xy -3.043 1.899) (xy -3.04 1.899)
				(xy -3.037 1.899) (xy -3.036 1.899) (xy -3.032 1.897) (xy -3.031 1.897) (xy -3.028 1.895) (xy -3.025 1.893)
				(xy -3.024 1.893) (xy -3.021 1.891) (xy -3.02 1.889) (xy -3.017 1.887) (xy -3.016 1.885) (xy -3.013 1.883)
				(xy -3.012 1.881) (xy -3.011 1.879) (xy -3.008 1.877) (xy -3.008 1.875) (xy -3.005 1.873) (xy -3.004 1.871)
				(xy -3.004 1.869) (xy -3.003 1.865) (xy -3.003 1.863) (xy -3.001 1.861) (xy -3.001 1.859) (xy -3 1.855)
				(xy -3 1.853) (xy -3 1.851) (xy -3 1.351) (xy -3 1.347) (xy -3 1.345) (xy -3.001 1.343) (xy -3.001 1.341)
				(xy -3.003 1.337) (xy -3.003 1.335) (xy -3.004 1.333) (xy -3.004 1.331) (xy -3.005 1.327) (xy -3.008 1.325)
				(xy -3.008 1.323) (xy -3.011 1.321) (xy -3.012 1.319) (xy -3.013 1.317) (xy -3.016 1.315) (xy -3.017 1.313)
				(xy -3.02 1.311) (xy -3.021 1.311) (xy -3.024 1.309) (xy -3.025 1.307) (xy -3.028 1.305) (xy -3.031 1.305)
				(xy -3.032 1.303) (xy -3.036 1.303) (xy -3.037 1.303) (xy -3.04 1.301) (xy -3.043 1.301) (xy -3.045 1.301)
				(xy -3.048 1.301) (xy -3.051 1.301) (xy -3.65 1.301) (xy -3.653 1.301) (xy -3.656 1.301) (xy -3.658 1.301)
				(xy -3.661 1.301) (xy -3.664 1.303) (xy -3.665 1.303) (xy -3.669 1.303) (xy -3.67 1.305) (xy -3.673 1.305)
				(xy -3.676 1.307) (xy -3.677 1.309) (xy -3.68 1.311) (xy -3.681 1.311) (xy -3.684 1.313) (xy -3.685 1.315)
				(xy -3.688 1.317) (xy -3.689 1.319) (xy -3.69 1.321) (xy -3.693 1.323) (xy -3.693 1.325) (xy -3.696 1.327)
				(xy -3.697 1.331) (xy -3.697 1.333) (xy -3.698 1.335) (xy -3.698 1.337) (xy -3.7 1.341) (xy -3.7 1.343)
				(xy -3.701 1.345) (xy -3.701 1.347) (xy -3.701 1.351) (xy -3.701 1.45) (xy -3.701 1.454) (xy -3.701 1.456)
				(xy -3.7 1.458) (xy -3.7 1.46) (xy -3.698 1.464) (xy -3.698 1.466) (xy -3.697 1.468) (xy -3.697 1.47)
				(xy -3.696 1.474) (xy -3.693 1.476) (xy -3.693 1.478) (xy -3.69 1.48) (xy -3.689 1.482) (xy -3.688 1.484)
				(xy -3.685 1.486) (xy -3.684 1.488) (xy -3.681 1.49) (xy -3.68 1.49) (xy -3.677 1.492) (xy -3.676 1.494)
				(xy -3.673 1.496) (xy -3.67 1.496) (xy -3.669 1.498) (xy -3.665 1.498) (xy -3.664 1.498) (xy -3.661 1.5)
				(xy -3.658 1.5) (xy -3.656 1.5) (xy -3.653 1.5) (xy -3.65 1.5) (xy -3.25 1.5) (xy -3.247 1.5) (xy -3.246 1.5)
				(xy -3.242 1.502) (xy -3.238 1.502) (xy -3.235 1.502) (xy -3.234 1.504) (xy -3.23 1.504) (xy -3.227 1.506)
				(xy -3.226 1.508) (xy -3.223 1.508) (xy -3.222 1.51) (xy -3.219 1.512) (xy -3.218 1.514) (xy -3.215 1.516)
				(xy -3.214 1.518) (xy -3.211 1.52) (xy -3.21 1.522) (xy -3.21 1.524) (xy -3.207 1.526) (xy -3.206 1.528)
				(xy -3.206 1.53) (xy -3.203 1.532) (xy -3.202 1.536) (xy -3.202 1.537) (xy -3.202 1.541) (xy -3.202 1.543)
				(xy -3.202 1.545) (xy -3.202 1.547) (xy -3.202 1.551) (xy -3.202 1.651) (xy -3.202 1.653) (xy -3.202 1.655)
				(xy -3.202 1.659) (xy -3.202 1.661) (xy -3.202 1.663) (xy -3.202 1.666) (xy -3.203 1.668) (xy -3.206 1.67)
				(xy -3.206 1.674) (xy -3.207 1.676) (xy -3.21 1.678) (xy -3.21 1.68) (xy -3.211 1.682) (xy -3.214 1.684)
				(xy -3.215 1.686) (xy -3.218 1.688) (xy -3.219 1.69) (xy -3.222 1.69) (xy -3.223 1.692) (xy -3.226 1.694)
				(xy -3.227 1.696) (xy -3.23 1.696) (xy -3.234 1.698) (xy -3.235 1.698) (xy -3.238 1.698) (xy -3.242 1.7)
				(xy -3.246 1.7) (xy -3.247 1.7) (xy -3.25 1.7) (xy -3.65 1.7) (xy -3.653 1.7) (xy -3.656 1.7) (xy -3.658 1.702)
				(xy -3.661 1.702) (xy -3.664 1.702) (xy -3.665 1.702) (xy -3.669 1.704) (xy -3.67 1.704) (xy -3.673 1.706)
				(xy -3.676 1.708) (xy -3.677 1.708) (xy -3.68 1.71) (xy -3.681 1.712) (xy -3.684 1.714) (xy -3.685 1.716)
				(xy -3.688 1.718) (xy -3.689 1.72) (xy -3.69 1.722) (xy -3.693 1.724) (xy -3.693 1.726) (xy -3.696 1.728)
				(xy -3.697 1.73) (xy -3.697 1.732) (xy -3.698 1.736) (xy -3.698 1.738) (xy -3.7 1.74) (xy -3.7 1.742)
				(xy -3.701 1.746) (xy -3.701 1.748) (xy -3.701 1.75) (xy -3.701 1.851) (xy -3.701 1.853) (xy -3.701 1.855)
				(xy -3.7 1.859) (xy -3.7 1.861) (xy -3.698 1.863) (xy -3.698 1.865) (xy -3.697 1.869) (xy -3.697 1.871)
				(xy -3.696 1.873) (xy -3.693 1.875) (xy -3.693 1.877) (xy -3.69 1.879) (xy -3.689 1.881) (xy -3.688 1.883)
				(xy -3.685 1.885) (xy -3.684 1.887) (xy -3.681 1.889) (xy -3.68 1.891) (xy -3.677 1.893) (xy -3.676 1.893)
				(xy -3.673 1.895) (xy -3.67 1.897) (xy -3.669 1.897) (xy -3.665 1.899) (xy -3.664 1.899) (xy -3.661 1.899)
				(xy -3.658 1.899) (xy -3.656 1.901) (xy -3.653 1.901) (xy -3.65 1.901)
			)
			(stroke
				(width 0.0001)
				(type solid)
			)
			(fill solid)
			(layer "B.Mask")
		)
		(fp_rect
			(start -3.95 3.95)
			(end 3.95 -3.95)
			(stroke
				(width 0.05)
				(type solid)
			)
			(fill none)
			(layer "B.CrtYd")
		)
		(fp_line
			(start 3.499 -3.499)
			(end 3.499 3.5)
			(stroke
				(width 0.15)
				(type solid)
			)
			(layer "B.Fab")
		)
		(fp_line
			(start -3.5 -3.499)
			(end 3.499 -3.499)
			(stroke
				(width 0.15)
				(type solid)
			)
			(layer "B.Fab")
		)
		(fp_line
			(start -3.5 2.5)
			(end -3.5 -3.499)
			(stroke
				(width 0.15)
				(type solid)
			)
			(layer "B.Fab")
		)
		(fp_line
			(start 3.499 3.5)
			(end -2.5 3.5)
			(stroke
				(width 0.15)
				(type solid)
			)
			(layer "B.Fab")
		)
		(fp_line
			(start -2.5 3.5)
			(end -3.5 2.5)
			(stroke
				(width 0.15)
				(type solid)
			)
			(layer "B.Fab")
		)
		(fp_text user "License: Apache-2.0"
			(at -4.401 -9.079 -90)
			(layer "B.Fab")
			(hide yes)
			(effects
				(font
					(size 0.7 0.7)
					(thickness 0.15)
				)
				(justify left bottom mirror)
			)
		)
		(fp_text user "Author: Antmicro"
			(at -4.401 -8.079 -90)
			(layer "B.Fab")
			(hide yes)
			(effects
				(font
					(size 0.7 0.7)
					(thickness 0.15)
				)
				(justify left bottom mirror)
			)
		)
		(fp_text user "${REFERENCE}"
			(at -4.401 -7.078 -90)
			(layer "B.Fab")
			(hide yes)
			(effects
				(font
					(size 0.7 0.7)
					(thickness 0.15)
				)
				(justify left bottom mirror)
			)
		)
		(pad "1" smd roundrect
			(at -3.351 2.4 90)
			(size 0.8 0.65)
			(layers "B.Cu")
			(roundrect_rratio 0.09)
			(net 481 "USBPD2_HV")
			(pinfunction "PP_HV2")
			(pintype "bidirectional")
		)
		(pad "3" smd roundrect
			(at -3.351 1.601 90)
			(size 0.8 0.65)
			(layers "B.Cu")
			(roundrect_rratio 0.09)
			(net 261 "/USB Debug, DP/USBC0_VBUS")
			(pinfunction "VBUS2")
			(pintype "bidirectional")
		)
		(pad "5" smd roundrect
			(at -3.351 1 90)
			(size 0.7 0.2)
			(layers "B.Cu" "B.Paste" "B.Mask")
			(roundrect_rratio 0.25)
			(net 87 "+3V3")
			(pinfunction "VIN_3V3")
			(pintype "power_in")
		)
		(pad "6" smd roundrect
			(at -3.351 0.6 90)
			(size 0.7 0.2)
			(layers "B.Cu" "B.Paste" "B.Mask")
			(roundrect_rratio 0.25)
			(net 286 "/USB Debug, DP/PDC_ADCIN1")
			(pinfunction "ADCIN1")
			(pintype "input")
		)
		(pad "7" smd roundrect
			(at -3.351 0.202 90)
			(size 0.7 0.2)
			(layers "B.Cu" "B.Paste" "B.Mask")
			(roundrect_rratio 0.25)
			(net 404 "/USB Debug, DP/DRAIN1")
			(pinfunction "DRAIN2")
			(pintype "passive")
		)
		(pad "8" smd roundrect
			(at -3.351 -0.2 90)
			(size 0.7 0.2)
			(layers "B.Cu" "B.Paste" "B.Mask")
			(roundrect_rratio 0.25)
			(net 403 "/USB Debug, DP/DRAIN2")
			(pinfunction "DRAIN1")
			(pintype "passive")
		)
		(pad "9" smd roundrect
			(at -3.351 -0.598 90)
			(size 0.7 0.2)
			(layers "B.Cu" "B.Paste" "B.Mask")
			(roundrect_rratio 0.25)
			(net 134 "/USB Debug, DP/PDC_LDO_3V3")
			(pinfunction "LDO_3V3")
			(pintype "power_out")
		)
		(pad "10" smd roundrect
			(at -3.351 -0.998 90)
			(size 0.7 0.2)
			(layers "B.Cu" "B.Paste" "B.Mask")
			(roundrect_rratio 0.25)
			(net 287 "/USB Debug, DP/PDC_ADCIN2")
			(pinfunction "ADCIN2")
			(pintype "input")
		)
		(pad "11" smd roundrect
			(at -3.351 -1.6 90)
			(size 0.8 0.65)
			(layers "B.Cu")
			(roundrect_rratio 0.09)
			(net 480 "USBPD1_HV")
			(pinfunction "PP_HV1")
			(pintype "bidirectional")
		)
		(pad "13" smd roundrect
			(at -3.351 -2.398 90)
			(size 0.8 0.65)
			(layers "B.Cu")
			(roundrect_rratio 0.09)
			(net 196 "/USB Debug, DP/USBC3_VBUS")
			(pinfunction "VBUS1")
			(pintype "bidirectional")
		)
		(pad "15" smd roundrect
			(at -2.601 -3.35)
			(size 0.7 0.2)
			(layers "B.Cu" "B.Paste" "B.Mask")
			(roundrect_rratio 0.25)
			(net 403 "/USB Debug, DP/DRAIN2")
			(pinfunction "DRAIN1")
			(pintype "passive")
		)
		(pad "16" smd roundrect
			(at -2.202 -3.35)
			(size 0.7 0.2)
			(layers "B.Cu" "B.Paste" "B.Mask")
			(roundrect_rratio 0.25)
			(net 296 "/USB Debug, DP/PDC_FLIP")
			(pinfunction "GPIO0")
			(pintype "bidirectional")
		)
		(pad "17" smd roundrect
			(at -1.801 -3.35)
			(size 0.7 0.2)
			(layers "B.Cu" "B.Paste" "B.Mask")
			(roundrect_rratio 0.25)
			(net 298 "/USB Debug, DP/PDC_CTL0")
			(pinfunction "GPIO1")
			(pintype "bidirectional")
		)
		(pad "18" smd roundrect
			(at -1.401 -3.35)
			(size 0.7 0.2)
			(layers "B.Cu" "B.Paste" "B.Mask")
			(roundrect_rratio 0.25)
			(net 294 "/USB Debug, DP/PDC_CTL1")
			(pinfunction "GPIO2")
			(pintype "bidirectional")
		)
		(pad "19" smd roundrect
			(at -1 -3.35)
			(size 0.7 0.2)
			(layers "B.Cu" "B.Paste" "B.Mask")
			(roundrect_rratio 0.25)
			(net 403 "/USB Debug, DP/DRAIN2")
			(pinfunction "DRAIN1")
			(pintype "passive")
		)
		(pad "20" smd roundrect
			(at -0.6 -3.35)
			(size 0.7 0.2)
			(layers "B.Cu" "B.Paste" "B.Mask")
			(roundrect_rratio 0.25)
			(net 1 "GND")
			(pinfunction "GND")
			(pintype "power_in")
		)
		(pad "21" smd roundrect
			(at -0.202 -3.35)
			(size 0.7 0.2)
			(layers "B.Cu" "B.Paste" "B.Mask")
			(roundrect_rratio 0.25)
			(net 639 "/USB Debug, DP/PDC_I2C3_SCL")
			(pinfunction "I2C3_SCL/GPIO5")
			(pintype "bidirectional")
		)
		(pad "22" smd roundrect
			(at 0.2 -3.35)
			(size 0.7 0.2)
			(layers "B.Cu" "B.Paste" "B.Mask")
			(roundrect_rratio 0.25)
			(net 299 "/USB Debug, DP/PDC_I2C3_SDA")
			(pinfunction "I2C3_SDA/GPIO6")
			(pintype "bidirectional")
		)
		(pad "23" smd roundrect
			(at 0.598 -3.35)
			(size 0.7 0.2)
			(layers "B.Cu" "B.Paste" "B.Mask")
			(roundrect_rratio 0.25)
			(net 708 "/USB Debug, DP/~{PDC_I2C3_IRQ}")
			(pinfunction "~{I2C3_IRQ}/GPIO7")
			(pintype "bidirectional")
		)
		(pad "24" smd roundrect
			(at 0.998 -3.35)
			(size 0.7 0.2)
			(layers "B.Cu" "B.Paste" "B.Mask")
			(roundrect_rratio 0.25)
			(net 273 "/USB Debug, DP/USBC3_CC1")
			(pinfunction "C1_CC1")
			(pintype "bidirectional")
		)
		(pad "25" smd roundrect
			(at 1.398 -3.35)
			(size 0.7 0.2)
			(layers "B.Cu" "B.Paste" "B.Mask")
			(roundrect_rratio 0.25)
			(net 99 "+5V")
			(pinfunction "PP1_CABLE")
			(pintype "power_in")
		)
		(pad "26" smd roundrect
			(at 1.8 -3.35)
			(size 0.7 0.2)
			(layers "B.Cu" "B.Paste" "B.Mask")
			(roundrect_rratio 0.25)
			(net 276 "/USB Debug, DP/USBC3_CC2")
			(pinfunction "C1_CC2")
			(pintype "bidirectional")
		)
		(pad "27" smd roundrect
			(at 2.2 -3.35)
			(size 0.7 0.2)
			(layers "B.Cu" "B.Paste" "B.Mask")
			(roundrect_rratio 0.25)
			(net 302 "/USB Debug, DP/PDC_I2C1_SCL")
			(pinfunction "I2C1_SCL")
			(pintype "bidirectional")
		)
		(pad "28" smd roundrect
			(at 2.6 -3.35)
			(size 0.7 0.2)
			(layers "B.Cu" "B.Paste" "B.Mask")
			(roundrect_rratio 0.25)
			(net 303 "/USB Debug, DP/PDC_I2C1_SDA")
			(pinfunction "I2C1_SDA")
			(pintype "bidirectional")
		)
		(pad "29" smd roundrect
			(at 3.35 -2.6 90)
			(size 0.7 0.2)
			(layers "B.Cu" "B.Paste" "B.Mask")
			(roundrect_rratio 0.25)
			(net 713 "/USB Debug, DP/PDC_I2C1_IRQn")
			(pinfunction "~{I2C1_IRQ}")
			(pintype "output")
		)
		(pad "30" smd roundrect
			(at 3.35 -2.2 90)
			(size 0.7 0.2)
			(layers "B.Cu" "B.Paste" "B.Mask")
			(roundrect_rratio 0.25)
			(net 691 "Net-(U6A-GPIO3{slash}HPD1)")
			(pinfunction "GPIO3/HPD1")
			(pintype "bidirectional")
		)
		(pad "31" smd roundrect
			(at 3.35 -1.8 90)
			(size 0.7 0.2)
			(layers "B.Cu" "B.Paste" "B.Mask")
			(roundrect_rratio 0.25)
			(net 670 "/USB Debug, DP/PDC_HPD2")
			(pinfunction "GPIO4/HPD2")
			(pintype "bidirectional")
		)
		(pad "32" smd roundrect
			(at 3.35 -1.398 90)
			(size 0.7 0.2)
			(layers "B.Cu" "B.Paste" "B.Mask")
			(roundrect_rratio 0.25)
			(net 395 "/USB Debug, DP/PDC_I2C2_SCL")
			(pinfunction "I2C2_SCL")
			(pintype "bidirectional")
		)
		(pad "33" smd roundrect
			(at 3.35 -0.998 90)
			(size 0.7 0.2)
			(layers "B.Cu" "B.Paste" "B.Mask")
			(roundrect_rratio 0.25)
			(net 396 "/USB Debug, DP/PDC_I2C2_SDA")
			(pinfunction "I2C2_SDA")
			(pintype "bidirectional")
		)
		(pad "34" smd roundrect
			(at 3.35 -0.598 90)
			(size 0.7 0.2)
			(layers "B.Cu" "B.Paste" "B.Mask")
			(roundrect_rratio 0.25)
			(net 394 "/USB Debug, DP/PDC_I2C2_IRQn")
			(pinfunction "~{I2C2_IRQ}")
			(pintype "output")
		)
		(pad "35" smd roundrect
			(at 3.35 -0.2 90)
			(size 0.7 0.2)
			(layers "B.Cu" "B.Paste" "B.Mask")
			(roundrect_rratio 0.25)
			(net 133 "/USB Debug, DP/PDC_LDO_1V8")
			(pinfunction "LDO_1V8")
			(pintype "power_out")
		)
		(pad "36" smd roundrect
			(at 3.35 0.202 90)
			(size 0.7 0.2)
			(layers "B.Cu" "B.Paste" "B.Mask")
			(roundrect_rratio 0.25)
			(net 255 "PDC_MISO")
			(pinfunction "SPI_POCI/GPIO8")
			(pintype "bidirectional")
		)
		(pad "37" smd roundrect
			(at 3.35 0.6 90)
			(size 0.7 0.2)
			(layers "B.Cu" "B.Paste" "B.Mask")
			(roundrect_rratio 0.25)
			(net 256 "PDC_MOSI")
			(pinfunction "SPI_PICO/GPIO9")
			(pintype "bidirectional")
		)
		(pad "38" smd roundrect
			(at 3.35 1 90)
			(size 0.7 0.2)
			(layers "B.Cu" "B.Paste" "B.Mask")
			(roundrect_rratio 0.25)
			(net 254 "PDC_SCLK")
			(pinfunction "SPI_CLK/GPIO10")
			(pintype "bidirectional")
		)
		(pad "39" smd roundrect
			(at 3.35 1.401 90)
			(size 0.7 0.2)
			(layers "B.Cu" "B.Paste" "B.Mask")
			(roundrect_rratio 0.25)
			(net 253 "~{PDC_CS}")
			(pinfunction "~{SPI_CS}/GPIO11")
			(pintype "bidirectional")
		)
		(pad "40" smd roundrect
			(at 3.35 1.801 90)
			(size 0.7 0.2)
			(layers "B.Cu" "B.Paste" "B.Mask")
			(roundrect_rratio 0.25)
			(net 693 "unconnected-(U6A-GPIO12-Pad40)")
			(pinfunction "GPIO12")
			(pintype "bidirectional+no_connect")
		)
		(pad "41" smd roundrect
			(at 3.35 2.202 90)
			(size 0.7 0.2)
			(layers "B.Cu" "B.Paste" "B.Mask")
			(roundrect_rratio 0.25)
			(net 694 "unconnected-(U6A-GPIO13-Pad41)")
			(pinfunction "GPIO13")
			(pintype "bidirectional+no_connect")
		)
		(pad "42" smd roundrect
			(at 3.35 2.601 90)
			(size 0.7 0.2)
			(layers "B.Cu" "B.Paste" "B.Mask")
			(roundrect_rratio 0.25)
			(net 300 "/USB Debug, DP/PDC_GPIO14")
			(pinfunction "GPIO14/PWM1")
			(pintype "bidirectional")
		)
		(pad "43" smd roundrect
			(at 2.6 3.351)
			(size 0.7 0.2)
			(layers "B.Cu" "B.Paste" "B.Mask")
			(roundrect_rratio 0.25)
			(net 301 "/USB Debug, DP/PDC_GPIO15")
			(pinfunction "GPIO15/PWM2")
			(pintype "bidirectional")
		)
		(pad "44" smd roundrect
			(at 2.2 3.351)
			(size 0.7 0.2)
			(layers "B.Cu" "B.Paste" "B.Mask")
			(roundrect_rratio 0.25)
			(net 285 "/USB Debug, DP/PDC_RESET")
			(pinfunction "HRESET")
			(pintype "input")
		)
		(pad "45" smd roundrect
			(at 1.8 3.351)
			(size 0.7 0.2)
			(layers "B.Cu" "B.Paste" "B.Mask")
			(roundrect_rratio 0.25)
			(net 277 "/USB Debug, DP/USBC0_CC1")
			(pinfunction "C2_CC1")
			(pintype "bidirectional")
		)
		(pad "46" smd roundrect
			(at 1.398 3.351)
			(size 0.7 0.2)
			(layers "B.Cu" "B.Paste" "B.Mask")
			(roundrect_rratio 0.25)
			(net 99 "+5V")
			(pinfunction "PP2_CABLE")
			(pintype "power_in")
		)
		(pad "47" smd roundrect
			(at 0.998 3.351)
			(size 0.7 0.2)
			(layers "B.Cu" "B.Paste" "B.Mask")
			(roundrect_rratio 0.25)
			(net 278 "/USB Debug, DP/USBC0_CC2")
			(pinfunction "C2_CC2")
			(pintype "bidirectional")
		)
		(pad "48" smd roundrect
			(at 0.598 3.351)
			(size 0.7 0.2)
			(layers "B.Cu" "B.Paste" "B.Mask")
			(roundrect_rratio 0.25)
			(net 549 "/USB Debug, DP/USBC3_5V_PEN")
			(pinfunction "GPIO16/PP_EXT1")
			(pintype "bidirectional")
		)
		(pad "49" smd roundrect
			(at 0.2 3.351)
			(size 0.7 0.2)
			(layers "B.Cu" "B.Paste" "B.Mask")
			(roundrect_rratio 0.25)
			(net 553 "/USB Debug, DP/USBC0_5V_PEN")
			(pinfunction "GPIO17/PP_EXT2")
			(pintype "bidirectional")
		)
		(pad "50" smd roundrect
			(at -0.202 3.351)
			(size 0.7 0.2)
			(layers "B.Cu" "B.Paste" "B.Mask")
			(roundrect_rratio 0.25)
			(net 695 "unconnected-(U6B-C1_USB_P{slash}GPIO18-Pad50)")
			(pinfunction "C1_USB_P/GPIO18")
			(pintype "bidirectional+no_connect")
		)
		(pad "51" smd roundrect
			(at -0.6 3.351)
			(size 0.7 0.2)
			(layers "B.Cu" "B.Paste" "B.Mask")
			(roundrect_rratio 0.25)
			(net 1 "GND")
			(pinfunction "GND")
			(pintype "passive")
		)
		(pad "52" smd roundrect
			(at -1 3.351)
			(size 0.7 0.2)
			(layers "B.Cu" "B.Paste" "B.Mask")
			(roundrect_rratio 0.25)
			(net 404 "/USB Debug, DP/DRAIN1")
			(pinfunction "DRAIN2")
			(pintype "passive")
		)
		(pad "53" smd roundrect
			(at -1.401 3.351)
			(size 0.7 0.2)
			(layers "B.Cu" "B.Paste" "B.Mask")
			(roundrect_rratio 0.25)
			(net 696 "unconnected-(U6B-C1_USB_N{slash}GPIO19-Pad53)")
			(pinfunction "C1_USB_N/GPIO19")
			(pintype "bidirectional+no_connect")
		)
		(pad "54" smd roundrect
			(at -1.801 3.351)
			(size 0.7 0.2)
			(layers "B.Cu" "B.Paste" "B.Mask")
			(roundrect_rratio 0.25)
			(net 697 "unconnected-(U6C-C2_USB_P{slash}GPIO20-Pad54)")
			(pinfunction "C2_USB_P/GPIO20")
			(pintype "bidirectional+no_connect")
		)
		(pad "55" smd roundrect
			(at -2.202 3.351)
			(size 0.7 0.2)
			(layers "B.Cu" "B.Paste" "B.Mask")
			(roundrect_rratio 0.25)
			(net 698 "unconnected-(U6C-C2_USB_N{slash}GPIO21-Pad55)")
			(pinfunction "C2_USB_N/GPIO21")
			(pintype "bidirectional+no_connect")
		)
		(pad "56" smd roundrect
			(at -2.601 3.351)
			(size 0.7 0.2)
			(layers "B.Cu" "B.Paste" "B.Mask")
			(roundrect_rratio 0.25)
			(net 404 "/USB Debug, DP/DRAIN1")
			(pinfunction "DRAIN2")
			(pintype "passive")
		)
		(pad "57" thru_hole circle
			(at -2.351 0.576 90)
			(size 0.45 0.45)
			(drill 0.1)
			(layers "*.Cu")
			(remove_unused_layers no)
			(net 404 "/USB Debug, DP/DRAIN1")
			(pinfunction "DRAIN2")
			(pintype "passive")
		)
		(pad "57" thru_hole circle
			(at -2.351 1.45 90)
			(size 0.45 0.45)
			(drill 0.1)
			(layers "*.Cu")
			(remove_unused_layers no)
			(net 404 "/USB Debug, DP/DRAIN1")
			(pinfunction "DRAIN2")
			(pintype "passive")
		)
		(pad "57" thru_hole circle
			(at -2.351 2.327 90)
			(size 0.45 0.45)
			(drill 0.1)
			(layers "*.Cu")
			(remove_unused_layers no)
			(net 404 "/USB Debug, DP/DRAIN1")
			(pinfunction "DRAIN2")
			(pintype "passive")
		)
		(pad "57" smd roundrect
			(at -1.875 1.45)
			(size 2.6 1.75)
			(layers "B.Cu" "B.Mask")
			(roundrect_rratio 0.05714285714)
			(net 404 "/USB Debug, DP/DRAIN1")
			(pinfunction "DRAIN2")
			(pintype "passive")
			(solder_mask_margin 0.05)
		)
		(pad "57" thru_hole circle
			(at -1.401 0.577 90)
			(size 0.45 0.45)
			(drill 0.1)
			(layers "*.Cu")
			(remove_unused_layers no)
			(net 404 "/USB Debug, DP/DRAIN1")
			(pinfunction "DRAIN2")
			(pintype "passive")
		)
		(pad "57" thru_hole circle
			(at -1.401 1.45 90)
			(size 0.45 0.45)
			(drill 0.1)
			(layers "*.Cu")
			(remove_unused_layers no)
			(net 404 "/USB Debug, DP/DRAIN1")
			(pinfunction "DRAIN2")
			(pintype "passive")
		)
		(pad "57" thru_hole circle
			(at -1.401 2.327 90)
			(size 0.45 0.45)
			(drill 0.1)
			(layers "*.Cu")
			(remove_unused_layers no)
			(net 404 "/USB Debug, DP/DRAIN1")
			(pinfunction "DRAIN2")
			(pintype "passive")
		)
		(pad "58" thru_hole circle
			(at -2.351 -2.35 90)
			(size 0.45 0.45)
			(drill 0.1)
			(layers "*.Cu")
			(remove_unused_layers no)
			(net 403 "/USB Debug, DP/DRAIN2")
			(pinfunction "DRAIN1")
			(pintype "passive")
		)
		(pad "58" thru_hole circle
			(at -2.351 -1.475 90)
			(size 0.45 0.45)
			(drill 0.1)
			(layers "*.Cu")
			(remove_unused_layers no)
			(net 403 "/USB Debug, DP/DRAIN2")
			(pinfunction "DRAIN1")
			(pintype "passive")
		)
		(pad "58" thru_hole circle
			(at -2.351 -0.598 90)
			(size 0.45 0.45)
			(drill 0.1)
			(layers "*.Cu")
			(remove_unused_layers no)
			(net 403 "/USB Debug, DP/DRAIN2")
			(pinfunction "DRAIN1")
			(pintype "passive")
		)
		(pad "58" smd roundrect
			(at -1.875 -1.475)
			(size 2.55 1.75)
			(layers "B.Cu" "B.Mask")
			(roundrect_rratio 0.05714285714)
			(net 403 "/USB Debug, DP/DRAIN2")
			(pinfunction "DRAIN1")
			(pintype "passive")
			(solder_mask_margin 0.05)
		)
		(pad "58" thru_hole circle
			(at -1.401 -2.349 90)
			(size 0.45 0.45)
			(drill 0.1)
			(layers "*.Cu")
			(remove_unused_layers no)
			(net 403 "/USB Debug, DP/DRAIN2")
			(pinfunction "DRAIN1")
			(pintype "passive")
		)
		(pad "58" thru_hole circle
			(at -1.401 -1.475 90)
			(size 0.45 0.45)
			(drill 0.1)
			(layers "*.Cu")
			(remove_unused_layers no)
			(net 403 "/USB Debug, DP/DRAIN2")
			(pinfunction "DRAIN1")
			(pintype "passive")
		)
		(pad "58" thru_hole circle
			(at -1.401 -0.598 90)
			(size 0.45 0.45)
			(drill 0.1)
			(layers "*.Cu")
			(remove_unused_layers no)
			(net 403 "/USB Debug, DP/DRAIN2")
			(pinfunction "DRAIN1")
			(pintype "passive")
		)
		(pad "59" thru_hole circle
			(at -0.152 -1.322 90)
			(size 0.45 0.45)
			(drill 0.1)
			(layers "*.Cu")
			(remove_unused_layers no)
			(net 1 "GND")
			(pinfunction "GND_EP")
			(pintype "power_in")
		)
		(pad "59" thru_hole circle
			(at -0.15 0 90)
			(size 0.45 0.45)
			(drill 0.1)
			(layers "*.Cu")
			(remove_unused_layers no)
			(net 1 "GND")
			(pinfunction "GND_EP")
			(pintype "power_in")
		)
		(pad "59" thru_hole circle
			(at -0.15 1.321 90)
			(size 0.45 0.45)
			(drill 0.1)
			(layers "*.Cu")
			(remove_unused_layers no)
			(net 1 "GND")
			(pinfunction "GND_EP")
			(pintype "power_in")
		)
		(pad "59" thru_hole circle
			(at 1.048 -2.496 90)
			(size 0.45 0.45)
			(drill 0.1)
			(layers "*.Cu")
			(remove_unused_layers no)
			(net 1 "GND")
			(pinfunction "GND_EP")
			(pintype "power_in")
		)
		(pad "59" thru_hole circle
			(at 1.048 -1.322 90)
			(size 0.45 0.45)
			(drill 0.1)
			(layers "*.Cu")
			(remove_unused_layers no)
			(net 1 "GND")
			(pinfunction "GND_EP")
			(pintype "power_in")
		)
		(pad "59" thru_hole circle
			(at 1.048 1.327 90)
			(size 0.45 0.45)
			(drill 0.1)
			(layers "*.Cu")
			(remove_unused_layers no)
			(net 1 "GND")
			(pinfunction "GND_EP")
			(pintype "power_in")
		)
		(pad "59" thru_hole circle
			(at 1.048 2.504 90)
			(size 0.45 0.45)
			(drill 0.1)
			(layers "*.Cu")
			(remove_unused_layers no)
			(net 1 "GND")
			(pinfunction "GND_EP")
			(pintype "power_in")
		)
		(pad "59" thru_hole circle
			(at 1.05 0 90)
			(size 0.45 0.45)
			(drill 0.1)
			(layers "*.Cu")
			(remove_unused_layers no)
			(net 1 "GND")
			(pinfunction "GND_EP")
			(pintype "power_in")
		)
		(pad "59" smd roundrect
			(at 1.05 0)
			(size 5.5 3.4)
			(layers "B.Cu" "B.Mask")
			(roundrect_rratio 0.02941176471)
			(net 1 "GND")
			(pinfunction "GND_EP")
			(pintype "power_in")
			(solder_mask_margin 0.05)
		)
		(pad "59" thru_hole circle
			(at 2.248 -1.322 90)
			(size 0.45 0.45)
			(drill 0.1)
			(layers "*.Cu")
			(remove_unused_layers no)
			(net 1 "GND")
			(pinfunction "GND_EP")
			(pintype "power_in")
		)
		(pad "59" thru_hole circle
			(at 2.248 0.001 90)
			(size 0.45 0.45)
			(drill 0.1)
			(layers "*.Cu")
			(remove_unused_layers no)
			(net 1 "GND")
			(pinfunction "GND_EP")
			(pintype "power_in")
		)
		(pad "59" thru_hole circle
			(at 2.248 1.327 90)
			(size 0.45 0.45)
			(drill 0.1)
			(layers "*.Cu")
			(remove_unused_layers no)
			(net 1 "GND")
			(pinfunction "GND_EP")
			(pintype "power_in")
		)
	)
	(footprint "antmicro-footprints:SOT-23-3"
		(layer "B.Cu")
		(at 49.625 80.1)
		(property "Reference" "Q18"
			(at -1.875 -2.925 90)
			(layer "B.SilkS")
			(effects
				(font
					(size 0.7 0.7)
					(thickness 0.15)
				)
				(justify left bottom mirror)
			)
		)
		(property "Value" "SSM3J332R"
			(at -1.9 -2.7 180)
			(layer "B.Fab")
			(effects
				(font
					(size 0.7 0.7)
					(thickness 0.15)
				)
				(justify left bottom mirror)
			)
		)
		(property "Footprint" "antmicro-footprints:SOT-23-3"
			(at 0 0 0)
			(layer "F.Fab")
			(hide yes)
			(effects
				(font
					(size 1.27 1.27)
					(thickness 0.15)
				)
			)
		)
		(property "Datasheet" "https://www.mouser.com/datasheet/2/408/SSM3J332R_datasheet_en_20181015-1150575.pdf"
			(at 0 0 0)
			(layer "F.Fab")
			(hide yes)
			(effects
				(font
					(size 1.27 1.27)
					(thickness 0.15)
				)
			)
		)
		(property "Author" "Antmicro"
			(at 0 0 0)
			(layer "B.Fab")
			(hide yes)
			(effects
				(font
					(size 1 1)
					(thickness 0.15)
				)
				(justify mirror)
			)
		)
		(property "License" "Apache-2.0"
			(at 0 0 0)
			(layer "B.Fab")
			(hide yes)
			(effects
				(font
					(size 1 1)
					(thickness 0.15)
				)
				(justify mirror)
			)
		)
		(property "MPN" "SSM3J332R,LF"
			(at 0 0 0)
			(layer "B.Fab")
			(hide yes)
			(effects
				(font
					(size 1 1)
					(thickness 0.15)
				)
				(justify mirror)
			)
		)
		(property "Manufacturer" "Toshiba"
			(at 0 0 0)
			(layer "B.Fab")
			(hide yes)
			(effects
				(font
					(size 1 1)
					(thickness 0.15)
				)
				(justify mirror)
			)
		)
		(sheetname "Supply")
		(sheetfile "supply.kicad_sch")
		(attr smd)
		(fp_line
			(start -0.85 1.35)
			(end -1.45 1.35)
			(stroke
				(width 0.15)
				(type solid)
			)
			(layer "B.SilkS")
		)
		(fp_line
			(start -0.7 -1.5)
			(end 0.7 -1.5)
			(stroke
				(width 0.15)
				(type solid)
			)
			(layer "B.SilkS")
		)
		(fp_line
			(start -0.7 -1.35)
			(end -0.7 -1.5)
			(stroke
				(width 0.15)
				(type solid)
			)
			(layer "B.SilkS")
		)
		(fp_line
			(start -0.7 1.5)
			(end -0.85 1.35)
			(stroke
				(width 0.15)
				(type solid)
			)
			(layer "B.SilkS")
		)
		(fp_line
			(start -0.7 1.5)
			(end 0.7 1.5)
			(stroke
				(width 0.15)
				(type solid)
			)
			(layer "B.SilkS")
		)
		(fp_line
			(start 0.7 -1.5)
			(end 0.7 -0.4)
			(stroke
				(width 0.15)
				(type solid)
			)
			(layer "B.SilkS")
		)
		(fp_line
			(start 0.7 1.5)
			(end 0.7 0.4)
			(stroke
				(width 0.15)
				(type solid)
			)
			(layer "B.SilkS")
		)
		(fp_line
			(start -1.75 -1.4)
			(end -0.85 -1.4)
			(stroke
				(width 0.05)
				(type solid)
			)
			(layer "B.CrtYd")
		)
		(fp_line
			(start -1.75 -0.5)
			(end -1.75 -1.4)
			(stroke
				(width 0.05)
				(type solid)
			)
			(layer "B.CrtYd")
		)
		(fp_line
			(start -1.75 0.5)
			(end -0.85 0.5)
			(stroke
				(width 0.05)
				(type solid)
			)
			(layer "B.CrtYd")
		)
		(fp_line
			(start -1.75 1.4)
			(end -1.75 0.5)
			(stroke
				(width 0.05)
				(type solid)
			)
			(layer "B.CrtYd")
		)
		(fp_line
			(start -1.75 1.4)
			(end -0.9 1.4)
			(stroke
				(width 0.05)
				(type solid)
			)
			(layer "B.CrtYd")
		)
		(fp_line
			(start -0.9 1.4)
			(end -0.9 1.6)
			(stroke
				(width 0.05)
				(type solid)
			)
			(layer "B.CrtYd")
		)
		(fp_line
			(start -0.85 -1.65)
			(end 0.85 -1.65)
			(stroke
				(width 0.05)
				(type solid)
			)
			(layer "B.CrtYd")
		)
		(fp_line
			(start -0.85 -1.4)
			(end -0.85 -1.65)
			(stroke
				(width 0.05)
				(type solid)
			)
			(layer "B.CrtYd")
		)
		(fp_line
			(start -0.85 -0.5)
			(end -1.75 -0.5)
			(stroke
				(width 0.05)
				(type solid)
			)
			(layer "B.CrtYd")
		)
		(fp_line
			(start -0.85 0.5)
			(end -0.85 -0.5)
			(stroke
				(width 0.05)
				(type solid)
			)
			(layer "B.CrtYd")
		)
		(fp_line
			(start 0.825 0.45)
			(end 0.825 1.6)
			(stroke
				(width 0.05)
				(type solid)
			)
			(layer "B.CrtYd")
		)
		(fp_line
			(start 0.825 1.6)
			(end -0.9 1.6)
			(stroke
				(width 0.05)
				(type solid)
			)
			(layer "B.CrtYd")
		)
		(fp_line
			(start 0.85 -1.65)
			(end 0.85 -0.45)
			(stroke
				(width 0.05)
				(type solid)
			)
			(layer "B.CrtYd")
		)
		(fp_line
			(start 0.85 -0.45)
			(end 1.75 -0.45)
			(stroke
				(width 0.05)
				(type solid)
			)
			(layer "B.CrtYd")
		)
		(fp_line
			(start 1.75 -0.45)
			(end 1.75 0.45)
			(stroke
				(width 0.05)
				(type solid)
			)
			(layer "B.CrtYd")
		)
		(fp_line
			(start 1.75 0.45)
			(end 0.825 0.45)
			(stroke
				(width 0.05)
				(type solid)
			)
			(layer "B.CrtYd")
		)
		(fp_line
			(start -0.712 -1.523)
			(end -0.712 1.325)
			(stroke
				(width 0.15)
				(type solid)
			)
			(layer "B.Fab")
		)
		(fp_line
			(start -0.712 1.325)
			(end -0.437 1.526)
			(stroke
				(width 0.15)
				(type solid)
			)
			(layer "B.Fab")
		)
		(fp_line
			(start 0.688 -1.519)
			(end -0.712 -1.519)
			(stroke
				(width 0.15)
				(type solid)
			)
			(layer "B.Fab")
		)
		(fp_line
			(start 0.688 1.52)
			(end 0.688 -1.519)
			(stroke
				(width 0.15)
				(type solid)
			)
			(layer "B.Fab")
		)
		(fp_line
			(start 0.688 1.526)
			(end -0.437 1.526)
			(stroke
				(width 0.15)
				(type solid)
			)
			(layer "B.Fab")
		)
		(fp_text user "${REFERENCE}"
			(at -1.837 -4 180)
			(layer "B.Fab")
			(hide yes)
			(effects
				(font
					(size 0.7 0.7)
					(thickness 0.15)
				)
				(justify left bottom mirror)
			)
		)
		(fp_text user "Author: Antmicro"
			(at -1.837 -5.3 180)
			(layer "B.Fab")
			(hide yes)
			(effects
				(font
					(size 0.7 0.7)
					(thickness 0.15)
				)
				(justify left bottom mirror)
			)
		)
		(fp_text user "License: Apache-2.0"
			(at -1.8 -6.8 180)
			(layer "B.Fab")
			(hide yes)
			(effects
				(font
					(size 0.7 0.7)
					(thickness 0.15)
				)
				(justify left bottom mirror)
			)
		)
		(pad "1" smd roundrect
			(at -1.1 0.951)
			(size 1 0.6)
			(layers "B.Cu" "B.Paste" "B.Mask")
			(roundrect_rratio 0.15)
			(net 135 "Net-(Q18-G)")
			(pinfunction "G")
			(pintype "bidirectional")
		)
		(pad "2" smd roundrect
			(at -1.1 -0.949)
			(size 1 0.6)
			(layers "B.Cu" "B.Paste" "B.Mask")
			(roundrect_rratio 0.15)
			(net 328 "/Supply/VCC_IN")
			(pinfunction "S")
			(pintype "bidirectional")
		)
		(pad "3" smd roundrect
			(at 1.1 0.0005)
			(size 1 0.6)
			(layers "B.Cu" "B.Paste" "B.Mask")
			(roundrect_rratio 0.15)
			(net 115 "VCC")
			(pinfunction "D")
			(pintype "bidirectional")
		)
	)
	(footprint "antmicro-footprints:Conn_FFC_WE_68715014x22"
		(layer "B.Cu")
		(at 145.29 94.73 -90)
		(property "Reference" "J7"
			(at 0 3.4 90)
			(layer "B.SilkS")
			(effects
				(font
					(size 0.7 0.7)
					(thickness 0.15)
				)
				(justify left bottom mirror)
			)
		)
		(property "Value" "Conn_FFC_WE_68715014522"
			(at 0 -4.499 90)
			(layer "B.Fab")
			(effects
				(font
					(size 0.7 0.7)
					(thickness 0.15)
				)
				(justify left bottom mirror)
			)
		)
		(property "Footprint" "antmicro-footprints:Conn_FFC_WE_68715014x22"
			(at 0 0 -90)
			(layer "F.Fab")
			(hide yes)
			(effects
				(font
					(size 1.27 1.27)
					(thickness 0.15)
				)
			)
		)
		(property "Datasheet" "https://www.we-online.com/components/products/datasheet/68715014522.pdf"
			(at 0 0 -90)
			(layer "F.Fab")
			(hide yes)
			(effects
				(font
					(size 1.27 1.27)
					(thickness 0.15)
				)
			)
		)
		(property "Author" "Antmicro"
			(at 50.56 240.02 0)
			(layer "B.Fab")
			(hide yes)
			(effects
				(font
					(size 1 1)
					(thickness 0.15)
				)
				(justify mirror)
			)
		)
		(property "License" "Apache-2.0"
			(at 50.56 240.02 0)
			(layer "B.Fab")
			(hide yes)
			(effects
				(font
					(size 1 1)
					(thickness 0.15)
				)
				(justify mirror)
			)
		)
		(property "MPN" "68715014522"
			(at 50.56 240.02 0)
			(layer "B.Fab")
			(hide yes)
			(effects
				(font
					(size 1 1)
					(thickness 0.15)
				)
				(justify mirror)
			)
		)
		(property "Manufacturer" "Würth Elektronik"
			(at 50.56 240.02 0)
			(layer "B.Fab")
			(hide yes)
			(effects
				(font
					(size 1 1)
					(thickness 0.15)
				)
				(justify mirror)
			)
		)
		(sheetname "CSI")
		(sheetfile "csi.kicad_sch")
		(attr smd)
		(fp_line
			(start -12.5 2.976)
			(end -12.5 2.15)
			(stroke
				(width 0.15)
				(type solid)
			)
			(layer "B.SilkS")
		)
		(fp_line
			(start 12.499 2.976)
			(end -12.5 2.976)
			(stroke
				(width 0.15)
				(type solid)
			)
			(layer "B.SilkS")
		)
		(fp_line
			(start 12.499 2.976)
			(end 12.499 2.15)
			(stroke
				(width 0.15)
				(type solid)
			)
			(layer "B.SilkS")
		)
		(fp_line
			(start -15.85 2.15)
			(end -15.85 -2.7)
			(stroke
				(width 0.15)
				(type solid)
			)
			(layer "B.SilkS")
		)
		(fp_line
			(start -12.5 2.15)
			(end -15.85 2.15)
			(stroke
				(width 0.15)
				(type solid)
			)
			(layer "B.SilkS")
		)
		(fp_line
			(start 12.499 2.15)
			(end 15.85 2.15)
			(stroke
				(width 0.15)
				(type solid)
			)
			(layer "B.SilkS")
		)
		(fp_line
			(start 15.85 2.15)
			(end 15.85 -2.7)
			(stroke
				(width 0.15)
				(type solid)
			)
			(layer "B.SilkS")
		)
		(fp_line
			(start -15.85 -2.7)
			(end 15.85 -2.7)
			(stroke
				(width 0.15)
				(type solid)
			)
			(layer "B.SilkS")
		)
		(fp_circle
			(center -12.9 2.9)
			(end -12.85 2.85)
			(stroke
				(width 0.15)
				(type solid)
			)
			(fill solid)
			(layer "B.SilkS")
		)
		(fp_rect
			(start -16.2 3.25)
			(end 16.2 -3.55)
			(stroke
				(width 0.05)
				(type solid)
			)
			(fill none)
			(layer "B.CrtYd")
		)
		(fp_text user "Author: Antmicro"
			(at -16.2 -6.499 90)
			(layer "B.Fab")
			(hide yes)
			(effects
				(font
					(size 0.7 0.7)
					(thickness 0.15)
				)
				(justify left bottom mirror)
			)
		)
		(fp_text user "License: Apache-2.0"
			(at -16.2 -7.7 90)
			(layer "B.Fab")
			(hide yes)
			(effects
				(font
					(size 0.7 0.7)
					(thickness 0.15)
				)
				(justify left bottom mirror)
			)
		)
		(fp_text user "${REFERENCE}"
			(at -16.2 -8.9 90)
			(layer "B.Fab")
			(hide yes)
			(effects
				(font
					(size 0.7 0.7)
					(thickness 0.15)
				)
				(justify left bottom mirror)
			)
		)
		(pad "1" smd roundrect
			(at -12.25 2.15 270)
			(size 0.3 1.2)
			(layers "B.Cu" "B.Paste" "B.Mask")
			(roundrect_rratio 0.25)
			(net 204 "/CSI/CSI1_0_D1_N")
			(pintype "passive")
		)
		(pad "2" smd roundrect
			(at -11.75 2.15 270)
			(size 0.3 1.2)
			(layers "B.Cu" "B.Paste" "B.Mask")
			(roundrect_rratio 0.25)
			(net 205 "/CSI/CSI1_0_D1_P")
			(pintype "passive")
		)
		(pad "3" smd roundrect
			(at -11.25 2.15 270)
			(size 0.3 1.2)
			(layers "B.Cu" "B.Paste" "B.Mask")
			(roundrect_rratio 0.25)
			(net 206 "/CSI/CSI1_0_D0_N")
			(pintype "passive")
		)
		(pad "4" smd roundrect
			(at -10.75 2.15 270)
			(size 0.3 1.2)
			(layers "B.Cu" "B.Paste" "B.Mask")
			(roundrect_rratio 0.25)
			(net 207 "/CSI/CSI1_0_D0_P")
			(pintype "passive")
		)
		(pad "5" smd roundrect
			(at -10.25 2.15 270)
			(size 0.3 1.2)
			(layers "B.Cu" "B.Paste" "B.Mask")
			(roundrect_rratio 0.25)
			(net 11 "CSI0_D1_N")
			(pintype "passive")
		)
		(pad "6" smd roundrect
			(at -9.75 2.15 270)
			(size 0.3 1.2)
			(layers "B.Cu" "B.Paste" "B.Mask")
			(roundrect_rratio 0.25)
			(net 13 "CSI0_D1_P")
			(pintype "passive")
		)
		(pad "7" smd roundrect
			(at -9.25 2.15 270)
			(size 0.3 1.2)
			(layers "B.Cu" "B.Paste" "B.Mask")
			(roundrect_rratio 0.25)
			(net 3 "CSI0_D0_N")
			(pintype "passive")
		)
		(pad "8" smd roundrect
			(at -8.75 2.15 270)
			(size 0.3 1.2)
			(layers "B.Cu" "B.Paste" "B.Mask")
			(roundrect_rratio 0.25)
			(net 5 "CSI0_D0_P")
			(pintype "passive")
		)
		(pad "9" smd roundrect
			(at -8.25 2.15 270)
			(size 0.3 1.2)
			(layers "B.Cu" "B.Paste" "B.Mask")
			(roundrect_rratio 0.25)
			(net 1 "GND")
			(pintype "passive")
		)
		(pad "10" smd roundrect
			(at -7.75 2.15 270)
			(size 0.3 1.2)
			(layers "B.Cu" "B.Paste" "B.Mask")
			(roundrect_rratio 0.25)
			(net 7 "CSI0_CLK_N")
			(pintype "passive")
		)
		(pad "11" smd roundrect
			(at -7.25 2.15 270)
			(size 0.3 1.2)
			(layers "B.Cu" "B.Paste" "B.Mask")
			(roundrect_rratio 0.25)
			(net 9 "CSI0_CLK_P")
			(pintype "passive")
		)
		(pad "12" smd roundrect
			(at -6.75 2.15 270)
			(size 0.3 1.2)
			(layers "B.Cu" "B.Paste" "B.Mask")
			(roundrect_rratio 0.25)
			(net 1 "GND")
			(pintype "passive")
		)
		(pad "13" smd roundrect
			(at -6.25 2.15 270)
			(size 0.3 1.2)
			(layers "B.Cu" "B.Paste" "B.Mask")
			(roundrect_rratio 0.25)
			(net 326 "unconnected-(J7-Pad13)")
			(pintype "passive+no_connect")
		)
		(pad "14" smd roundrect
			(at -5.75 2.15 270)
			(size 0.3 1.2)
			(layers "B.Cu" "B.Paste" "B.Mask")
			(roundrect_rratio 0.25)
			(net 339 "unconnected-(J7-Pad14)")
			(pintype "passive+no_connect")
		)
		(pad "15" smd roundrect
			(at -5.25 2.15 270)
			(size 0.3 1.2)
			(layers "B.Cu" "B.Paste" "B.Mask")
			(roundrect_rratio 0.25)
			(net 1 "GND")
			(pintype "passive")
		)
		(pad "16" smd roundrect
			(at -4.75 2.15 270)
			(size 0.3 1.2)
			(layers "B.Cu" "B.Paste" "B.Mask")
			(roundrect_rratio 0.25)
			(net 340 "unconnected-(J7-Pad16)")
			(pintype "passive+no_connect")
		)
		(pad "17" smd roundrect
			(at -4.25 2.15 270)
			(size 0.3 1.2)
			(layers "B.Cu" "B.Paste" "B.Mask")
			(roundrect_rratio 0.25)
			(net 626 "unconnected-(J7-Pad17)")
			(pintype "passive+no_connect")
		)
		(pad "18" smd roundrect
			(at -3.75 2.15 270)
			(size 0.3 1.2)
			(layers "B.Cu" "B.Paste" "B.Mask")
			(roundrect_rratio 0.25)
			(net 1 "GND")
			(pintype "passive")
		)
		(pad "19" smd roundrect
			(at -3.25 2.15 270)
			(size 0.3 1.2)
			(layers "B.Cu" "B.Paste" "B.Mask")
			(roundrect_rratio 0.25)
			(net 212 "/CSI/CSI3_0_D1_N")
			(pintype "passive")
		)
		(pad "20" smd roundrect
			(at -2.75 2.15 270)
			(size 0.3 1.2)
			(layers "B.Cu" "B.Paste" "B.Mask")
			(roundrect_rratio 0.25)
			(net 213 "/CSI/CSI3_0_D1_P")
			(pintype "passive")
		)
		(pad "21" smd roundrect
			(at -2.25 2.15 270)
			(size 0.3 1.2)
			(layers "B.Cu" "B.Paste" "B.Mask")
			(roundrect_rratio 0.25)
			(net 214 "/CSI/CSI3_0_D0_N")
			(pintype "passive")
		)
		(pad "22" smd roundrect
			(at -1.75 2.15 270)
			(size 0.3 1.2)
			(layers "B.Cu" "B.Paste" "B.Mask")
			(roundrect_rratio 0.25)
			(net 215 "/CSI/CSI3_0_D0_P")
			(pintype "passive")
		)
		(pad "23" smd roundrect
			(at -1.25 2.15 270)
			(size 0.3 1.2)
			(layers "B.Cu" "B.Paste" "B.Mask")
			(roundrect_rratio 0.25)
			(net 23 "CSI2_D1_N")
			(pintype "passive")
		)
		(pad "24" smd roundrect
			(at -0.75 2.15 270)
			(size 0.3 1.2)
			(layers "B.Cu" "B.Paste" "B.Mask")
			(roundrect_rratio 0.25)
			(net 25 "CSI2_D1_P")
			(pintype "passive")
		)
		(pad "25" smd roundrect
			(at -0.25 2.15 270)
			(size 0.3 1.2)
			(layers "B.Cu" "B.Paste" "B.Mask")
			(roundrect_rratio 0.25)
			(net 15 "CSI2_D0_N")
			(pintype "passive")
		)
		(pad "26" smd roundrect
			(at 0.248 2.15 270)
			(size 0.3 1.2)
			(layers "B.Cu" "B.Paste" "B.Mask")
			(roundrect_rratio 0.25)
			(net 17 "CSI2_D0_P")
			(pintype "passive")
		)
		(pad "27" smd roundrect
			(at 0.748 2.15 270)
			(size 0.3 1.2)
			(layers "B.Cu" "B.Paste" "B.Mask")
			(roundrect_rratio 0.25)
			(net 1 "GND")
			(pintype "passive")
		)
		(pad "28" smd roundrect
			(at 1.249 2.15 270)
			(size 0.3 1.2)
			(layers "B.Cu" "B.Paste" "B.Mask")
			(roundrect_rratio 0.25)
			(net 19 "CSI2_CLK_N")
			(pintype "passive")
		)
		(pad "29" smd roundrect
			(at 1.749 2.15 270)
			(size 0.3 1.2)
			(layers "B.Cu" "B.Paste" "B.Mask")
			(roundrect_rratio 0.25)
			(net 21 "CSI2_CLK_P")
			(pintype "passive")
		)
		(pad "30" smd roundrect
			(at 2.249 2.15 270)
			(size 0.3 1.2)
			(layers "B.Cu" "B.Paste" "B.Mask")
			(roundrect_rratio 0.25)
			(net 1 "GND")
			(pintype "passive")
		)
		(pad "31" smd roundrect
			(at 2.749 2.15 270)
			(size 0.3 1.2)
			(layers "B.Cu" "B.Paste" "B.Mask")
			(roundrect_rratio 0.25)
			(net 627 "unconnected-(J7-Pad31)")
			(pintype "passive+no_connect")
		)
		(pad "32" smd roundrect
			(at 3.249 2.15 270)
			(size 0.3 1.2)
			(layers "B.Cu" "B.Paste" "B.Mask")
			(roundrect_rratio 0.25)
			(net 360 "/CSI/VSYNC_CAM0_3V3")
			(pintype "passive")
		)
		(pad "33" smd roundrect
			(at 3.749 2.15 270)
			(size 0.3 1.2)
			(layers "B.Cu" "B.Paste" "B.Mask")
			(roundrect_rratio 0.25)
			(net 361 "unconnected-(J7-Pad33)")
			(pintype "passive+no_connect")
		)
		(pad "34" smd roundrect
			(at 4.248 2.15 270)
			(size 0.3 1.2)
			(layers "B.Cu" "B.Paste" "B.Mask")
			(roundrect_rratio 0.25)
			(net 371 "/CSI/VSYNC_CAM1_3V3")
			(pintype "passive")
		)
		(pad "35" smd roundrect
			(at 4.748 2.15 270)
			(size 0.3 1.2)
			(layers "B.Cu" "B.Paste" "B.Mask")
			(roundrect_rratio 0.25)
			(net 372 "unconnected-(J7-Pad35)")
			(pintype "passive+no_connect")
		)
		(pad "36" smd roundrect
			(at 5.248 2.15 270)
			(size 0.3 1.2)
			(layers "B.Cu" "B.Paste" "B.Mask")
			(roundrect_rratio 0.25)
			(net 373 "unconnected-(J7-Pad36)")
			(pintype "passive+no_connect")
		)
		(pad "37" smd roundrect
			(at 5.749 2.15 270)
			(size 0.3 1.2)
			(layers "B.Cu" "B.Paste" "B.Mask")
			(roundrect_rratio 0.25)
			(net 374 "unconnected-(J7-Pad37)")
			(pintype "passive+no_connect")
		)
		(pad "38" smd roundrect
			(at 6.249 2.15 270)
			(size 0.3 1.2)
			(layers "B.Cu" "B.Paste" "B.Mask")
			(roundrect_rratio 0.25)
			(net 376 "unconnected-(J7-Pad38)")
			(pintype "passive+no_connect")
		)
		(pad "39" smd roundrect
			(at 6.749 2.15 270)
			(size 0.3 1.2)
			(layers "B.Cu" "B.Paste" "B.Mask")
			(roundrect_rratio 0.25)
			(net 554 "Net-(R50-R1.2)")
			(pintype "passive")
		)
		(pad "40" smd roundrect
			(at 7.249 2.15 270)
			(size 0.3 1.2)
			(layers "B.Cu" "B.Paste" "B.Mask")
			(roundrect_rratio 0.25)
			(net 559 "Net-(R50-R2.2)")
			(pintype "passive")
		)
		(pad "41" smd roundrect
			(at 7.749 2.15 270)
			(size 0.3 1.2)
			(layers "B.Cu" "B.Paste" "B.Mask")
			(roundrect_rratio 0.25)
			(net 560 "Net-(R50-R3.2)")
			(pintype "passive")
		)
		(pad "42" smd roundrect
			(at 8.249 2.15 270)
			(size 0.3 1.2)
			(layers "B.Cu" "B.Paste" "B.Mask")
			(roundrect_rratio 0.25)
			(net 563 "Net-(R50-R4.2)")
			(pintype "passive")
		)
		(pad "43" smd roundrect
			(at 8.749 2.15 270)
			(size 0.3 1.2)
			(layers "B.Cu" "B.Paste" "B.Mask")
			(roundrect_rratio 0.25)
			(net 377 "unconnected-(J7-Pad43)")
			(pintype "passive+no_connect")
		)
		(pad "44" smd roundrect
			(at 9.249 2.15 270)
			(size 0.3 1.2)
			(layers "B.Cu" "B.Paste" "B.Mask")
			(roundrect_rratio 0.25)
			(net 378 "unconnected-(J7-Pad44)")
			(pintype "passive+no_connect")
		)
		(pad "45" smd roundrect
			(at 9.749 2.15 270)
			(size 0.3 1.2)
			(layers "B.Cu" "B.Paste" "B.Mask")
			(roundrect_rratio 0.25)
			(net 379 "unconnected-(J7-Pad45)")
			(pintype "passive+no_connect")
		)
		(pad "46" smd roundrect
			(at 10.249 2.15 270)
			(size 0.3 1.2)
			(layers "B.Cu" "B.Paste" "B.Mask")
			(roundrect_rratio 0.25)
			(net 380 "unconnected-(J7-Pad46)")
			(pintype "passive+no_connect")
		)
		(pad "47" smd roundrect
			(at 10.749 2.15 270)
			(size 0.3 1.2)
			(layers "B.Cu" "B.Paste" "B.Mask")
			(roundrect_rratio 0.25)
			(net 108 "/CSI/CSIA_3V3")
			(pintype "passive")
		)
		(pad "48" smd roundrect
			(at 11.249 2.15 270)
			(size 0.3 1.2)
			(layers "B.Cu" "B.Paste" "B.Mask")
			(roundrect_rratio 0.25)
			(net 108 "/CSI/CSIA_3V3")
			(pintype "passive")
		)
		(pad "49" smd roundrect
			(at 11.749 2.15 270)
			(size 0.3 1.2)
			(layers "B.Cu" "B.Paste" "B.Mask")
			(roundrect_rratio 0.25)
			(net 109 "/CSI/CSIA_5V")
			(pintype "passive")
		)
		(pad "50" smd roundrect
			(at 12.249 2.15 270)
			(size 0.3 1.2)
			(layers "B.Cu" "B.Paste" "B.Mask")
			(roundrect_rratio 0.25)
			(net 109 "/CSI/CSIA_5V")
			(pintype "passive")
		)
		(pad "MP1" smd roundrect
			(at -14.198 0.3 270)
			(size 2.7 3)
			(layers "B.Cu" "B.Paste" "B.Mask")
			(roundrect_rratio 0.05)
			(net 1 "GND")
			(pinfunction "MP")
			(pintype "passive")
		)
		(pad "MP2" smd roundrect
			(at 14.198 0.3 270)
			(size 2.7 3)
			(layers "B.Cu" "B.Paste" "B.Mask")
			(roundrect_rratio 0.05)
			(net 1 "GND")
			(pinfunction "MP")
			(pintype "passive")
		)
	)
	(gr_line
		(start 29.95 68.75)
		(end 149.5 68.75)
		(stroke
			(width 0.12)
			(type solid)
		)
		(layer "Edge.Cuts")
	)
	(gr_arc
		(start 29.75 68.95)
		(mid 29.808579 68.808579)
		(end 29.95 68.75)
		(stroke
			(width 0.12)
			(type solid)
		)
		(layer "Edge.Cuts")
	)
	(gr_arc
		(start 30 128.75)
		(mid 29.823223 128.676777)
		(end 29.75 128.5)
		(stroke
			(width 0.12)
			(type solid)
		)
		(layer "Edge.Cuts")
	)
	(gr_line
		(start 29.75 128.5)
		(end 29.75 68.95)
		(stroke
			(width 0.12)
			(type solid)
		)
		(layer "Edge.Cuts")
	)
	(gr_line
		(start 149.5 128.75)
		(end 30 128.75)
		(stroke
			(width 0.12)
			(type solid)
		)
		(layer "Edge.Cuts")
	)
	(gr_line
		(start 149.75 69)
		(end 149.75 128.5)
		(stroke
			(width 0.12)
			(type solid)
		)
		(layer "Edge.Cuts")
	)
	(gr_arc
		(start 149.5 68.75)
		(mid 149.676777 68.823223)
		(end 149.75 69)
		(stroke
			(width 0.12)
			(type solid)
		)
		(layer "Edge.Cuts")
	)
	(gr_arc
		(start 149.75 128.5)
		(mid 149.676777 128.676777)
		(end 149.5 128.75)
		(stroke
			(width 0.12)
			(type solid)
		)
		(layer "Edge.Cuts")
	)
	(gr_text "Jetson Orin Baseboard\nRev. ${REVISION}   3/2025"
		(at 136 78.5 0)
		(layer "F.Cu")
		(effects
			(font
				(size 0.5 0.5)
				(thickness 0.125)
			)
			(justify left)
		)
	)
	(segment
		(start 101.952 126.702)
		(end 102.454 126.2)
		(width 0.155)
		(layer "F.Cu")
		(net 1)
	)
	(segment
		(start 113.765584 103.084416)
		(end 113.765584 103.684416)
		(width 0.15)
		(layer "F.Cu")
		(net 1)
	)
	(segment
		(start 91.180619 92.680619)
		(end 91.75 93.25)
		(width 0.15)
		(layer "F.Cu")
		(net 1)
	)
	(segment
		(start 112.347323 81.339529)
		(end 112.347323 80.205136)
		(width 0.125)
		(layer "F.Cu")
		(net 1)
	)
	(segment
		(start 74.097323 72.005136)
		(end 74.097323 69.802677)
		(width 0.2)
		(layer "F.Cu")
		(net 1)
	)
	(segment
		(start 117.097323 70.782677)
		(end 117.097323 72.005136)
		(width 0.125)
		(layer "F.Cu")
		(net 1)
	)
	(segment
		(start 124.59 70.89)
		(end 124.597323 70.897323)
		(width 0.125)
		(layer "F.Cu")
		(net 1)
	)
	(segment
		(start 110.847323 79.077323)
		(end 110.59 78.82)
		(width 0.3)
		(layer "F.Cu")
		(net 1)
	)
	(segment
		(start 64.32 100.52)
		(end 63.79 100.52)
		(width 0.125)
		(layer "F.Cu")
		(net 1)
	)
	(segment
		(start 58.16 105.695)
		(end 58.16 106.14)
		(width 0.2)
		(layer "F.Cu")
		(net 1)
	)
	(segment
		(start 125.44 93.99)
		(end 125.35 93.9)
		(width 0.3)
		(layer "F.Cu")
		(net 1)
	)
	(segment
		(start 108.865438 103.789938)
		(end 108.889938 103.814438)
		(width 0.15)
		(layer "F.Cu")
		(net 1)
	)
	(segment
		(start 123.47 101.4)
		(end 123.01 100.94)
		(width 0.3)
		(layer "F.Cu")
		(net 1)
	)
	(segment
		(start 113.15 73.5)
		(end 113.4725 73.5)
		(width 0.125)
		(layer "F.Cu")
		(net 1)
	)
	(segment
		(start 135.815 119.7)
		(end 135.815 120.675)
		(width 0.2)
		(layer "F.Cu")
		(net 1)
	)
	(segment
		(start 93.95 122)
		(end 93.95 121.15)
		(width 0.2)
		(layer "F.Cu")
		(net 1)
	)
	(segment
		(start 125.48 95.4)
		(end 125.6 95.28)
		(width 0.3)
		(layer "F.Cu")
		(net 1)
	)
	(segment
		(start 80.323 114.127)
		(end 80.08 114.37)
		(width 0.2)
		(layer "F.Cu")
		(net 1)
	)
	(segment
		(start 69.55 109.435)
		(end 70 109.885)
		(width 0.3)
		(layer "F.Cu")
		(net 1)
	)
	(segment
		(start 112.52 86.395)
		(end 112.8 86.675)
		(width 0.15)
		(layer "F.Cu")
		(net 1)
	)
	(segment
		(start 87.597323 70.802677)
		(end 87.6 70.8)
		(width 0.125)
		(layer "F.Cu")
		(net 1)
	)
	(segment
		(start 81.941624 81.371)
		(end 81.847323 81.276699)
		(width 0.125)
		(layer "F.Cu")
		(net 1)
	)
	(segment
		(start 146 83.95)
		(end 146.73 83.95)
		(width 0.125)
		(layer "F.Cu")
		(net 1)
	)
	(segment
		(start 111.097323 72.005136)
		(end 111.097323 73.137323)
		(width 0.3)
		(layer "F.Cu")
		(net 1)
	)
	(segment
		(start 70 109.885)
		(end 70 110.982469)
		(width 0.3)
		(layer "F.Cu")
		(net 1)
	)
	(segment
		(start 108.889938 108.745)
		(end 108.889938 106.545)
		(width 0.2)
		(layer "F.Cu")
		(net 1)
	)
	(segment
		(start 81.847323 81.276699)
		(end 81.847323 80.205136)
		(width 0.125)
		(layer "F.Cu")
		(net 1)
	)
	(segment
		(start 125.54 96.9)
		(end 125.58 96.86)
		(width 0.3)
		(layer "F.Cu")
		(net 1)
	)
	(segment
		(start 93.347323 80.205136)
		(end 93.347323 81.262)
		(width 0.3)
		(layer "F.Cu")
		(net 1)
	)
	(segment
		(start 79.25 95.15)
		(end 79 94.9)
		(width 0.15)
		(layer "F.Cu")
		(net 1)
	)
	(segment
		(start 137.2 108.0255)
		(end 136.9245 108.0255)
		(width 0.3)
		(layer "F.Cu")
		(net 1)
	)
	(segment
		(start 58.16 106.14)
		(end 57.9 106.4)
		(width 0.2)
		(layer "F.Cu")
		(net 1)
	)
	(segment
		(start 87.029 74.539999)
		(end 87.597323 73.971676)
		(width 0.125)
		(layer "F.Cu")
		(net 1)
	)
	(segment
		(start 110.6 119.45)
		(end 110.6 118.25)
		(width 0.2)
		(layer "F.Cu")
		(net 1)
	)
	(segment
		(start 84.3225 116.59)
		(end 84.3225 116.0175)
		(width 0.15)
		(layer "F.Cu")
		(net 1)
	)
	(segment
		(start 120.85 125.1)
		(end 120.85 125.15)
		(width 0.155)
		(layer "F.Cu")
		(net 1)
	)
	(segment
		(start 87.3705 127.4715)
		(end 87.3 127.401)
		(width 0.15)
		(layer "F.Cu")
		(net 1)
	)
	(segment
		(start 124.5 93.9)
		(end 123.2 93.9)
		(width 0.3)
		(layer "F.Cu")
		(net 1)
	)
	(segment
		(start 91.65 79)
		(end 90.55 79)
		(width 0.2)
		(layer "F.Cu")
		(net 1)
	)
	(segment
		(start 124.5 99.9)
		(end 125.35 99.9)
		(width 0.3)
		(layer "F.Cu")
		(net 1)
	)
	(segment
		(start 101.7 122.9)
		(end 101.75 122.85)
		(width 0.2)
		(layer "F.Cu")
		(net 1)
	)
	(segment
		(start 137.156098 92.95)
		(end 136.24 92.95)
		(width 0.3)
		(layer "F.Cu")
		(net 1)
	)
	(segment
		(start 61.115 106)
		(end 61.115 106.635)
		(width 0.3)
		(layer "F.Cu")
		(net 1)
	)
	(segment
		(start 121.59 70.65)
		(end 121.597323 70.657323)
		(width 0.125)
		(layer "F.Cu")
		(net 1)
	)
	(segment
		(start 146.65 93.55)
		(end 145.35 93.55)
		(width 0.125)
		(layer "F.Cu")
		(net 1)
	)
	(segment
		(start 116.55 115.793749)
		(end 116.55 117.375)
		(width 0.2)
		(layer "F.Cu")
		(net 1)
	)
	(segment
		(start 147.7 120)
		(end 147.7 119.385)
		(width 0.3)
		(layer "F.Cu")
		(net 1)
	)
	(segment
		(start 140.75 112.75)
		(end 140.65 112.85)
		(width 0.3)
		(layer "F.Cu")
		(net 1)
	)
	(segment
		(start 54.9 107.7)
		(end 54.525 108.075)
		(width 0.3)
		(layer "F.Cu")
		(net 1)
	)
	(segment
		(start 112.597323 70.707323)
		(end 112.597323 72.005136)
		(width 0.125)
		(layer "F.Cu")
		(net 1)
	)
	(segment
		(start 142.41 97.27)
		(end 142.41 97.01)
		(width 0.15)
		(layer "F.Cu")
		(net 1)
	)
	(segment
		(start 90.55 79)
		(end 90.347323 79.202677)
		(width 0.2)
		(layer "F.Cu")
		(net 1)
	)
	(segment
		(start 69.811 87.489)
		(end 70.48 86.82)
		(width 0.3)
		(layer "F.Cu")
		(net 1)
	)
	(segment
		(start 110.847323 80.205136)
		(end 110.847323 79.077323)
		(width 0.3)
		(layer "F.Cu")
		(net 1)
	)
	(segment
		(start 145.1245 107.15)
		(end 145 107.2745)
		(width 0.3)
		(layer "F.Cu")
		(net 1)
	)
	(segment
		(start 93.95 122)
		(end 93.95 122.85)
		(width 0.2)
		(layer "F.Cu")
		(net 1)
	)
	(segment
		(start 74.097323 69.802677)
		(end 74.1 69.8)
		(width 0.2)
		(layer "F.Cu")
		(net 1)
	)
	(segment
		(start 134.8 119.7)
		(end 134.45 119.35)
		(width 0.2)
		(layer "F.Cu")
		(net 1)
	)
	(segment
		(start 126.85 125.1)
		(end 126.85 125.15)
		(width 0.155)
		(layer "F.Cu")
		(net 1)
	)
	(segment
		(start 89.3 115.1)
		(end 89.2 115)
		(width 0.2)
		(layer "F.Cu")
		(net 1)
	)
	(segment
		(start 113.55 115.793749)
		(end 113.55 114.95)
		(width 0.15)
		(layer "F.Cu")
		(net 1)
	)
	(segment
		(start 144.987667 103.487333)
		(end 144.987667 102.962333)
		(width 0.15)
		(layer "F.Cu")
		(net 1)
	)
	(segment
		(start 124.597323 70.897323)
		(end 124.597323 72.005136)
		(width 0.125)
		(layer "F.Cu")
		(net 1)
	)
	(segment
		(start 88.01 80.367813)
		(end 87.847323 80.205136)
		(width 0.125)
		(layer "F.Cu")
		(net 1)
	)
	(segment
		(start 142.17 90.35)
		(end 141.5 90.35)
		(width 0.15)
		(layer "F.Cu")
		(net 1)
	)
	(segment
		(start 125.74 100.29)
		(end 125.35 99.9)
		(width 0.3)
		(layer "F.Cu")
		(net 1)
	)
	(segment
		(start 138.5 85.75)
		(end 137.8 85.75)
		(width 0.15)
		(layer "F.Cu")
		(net 1)
	)
	(segment
		(start 147.25 89.15)
		(end 146.875 88.775)
		(width 0.125)
		(layer "F.Cu")
		(net 1)
	)
	(segment
		(start 141.5 112.75)
		(end 140.75 112.75)
		(width 0.3)
		(layer "F.Cu")
		(net 1)
	)
	(segment
		(start 148.995 113.3)
		(end 148.485 112.79)
		(width 0.3)
		(layer "F.Cu")
		(net 1)
	)
	(segment
		(start 72.45 84.9)
		(end 72.47 84.88)
		(width 0.15)
		(layer "F.Cu")
		(net 1)
	)
	(segment
		(start 64.85 99.99)
		(end 64.32 100.52)
		(width 0.125)
		(layer "F.Cu")
		(net 1)
	)
	(segment
		(start 96.35 122)
		(end 96.35 121.15)
		(width 0.2)
		(layer "F.Cu")
		(net 1)
	)
	(segment
		(start 137.75 82.1)
		(end 137.75 82.4)
		(width 0.15)
		(layer "F.Cu")
		(net 1)
	)
	(segment
		(start 146.86 83.15)
		(end 146 83.15)
		(width 0.125)
		(layer "F.Cu")
		(net 1)
	)
	(segment
		(start 96.35 121.15)
		(end 96.675 120.825)
		(width 0.2)
		(layer "F.Cu")
		(net 1)
	)
	(segment
		(start 127.6 125.6)
		(end 127.8 125.4)
		(width 0.155)
		(layer "F.Cu")
		(net 1)
	)
	(segment
		(start 146.875 91.15)
		(end 146.85 91.175)
		(width 0.125)
		(layer "F.Cu")
		(net 1)
	)
	(segment
		(start 94.097323 70.497677)
		(end 94.097323 72.005136)
		(width 0.15)
		(layer "F.Cu")
		(net 1)
	)
	(segment
		(start 122.9 125.4)
		(end 123.1 125.6)
		(width 0.155)
		(layer "F.Cu")
		(net 1)
	)
	(segment
		(start 92.75 122)
		(end 92.75 122.85)
		(width 0.2)
		(layer "F.Cu")
		(net 1)
	)
	(segment
		(start 145.2 97.55)
		(end 145.1 97.65)
		(width 0.125)
		(layer "F.Cu")
		(net 1)
	)
	(segment
		(start 78.62 111.37)
		(end 78.34 111.65)
		(width 0.2)
		(layer "F.Cu")
		(net 1)
	)
	(segment
		(start 135.1 90.15)
		(end 134.35 90.15)
		(width 0.3)
		(layer "F.Cu")
		(net 1)
	)
	(segment
		(start 110.85 81.46)
		(end 110.847323 81.457323)
		(width 0.125)
		(layer "F.Cu")
		(net 1)
	)
	(segment
		(start 131.95 117.9)
		(end 131.6 118.25)
		(width 0.2)
		(layer "F.Cu")
		(net 1)
	)
	(segment
		(start 92.597323 70.997323)
		(end 92.597323 72.005136)
		(width 0.15)
		(layer "F.Cu")
		(net 1)
	)
	(segment
		(start 132.55 108.71)
		(end 132.49 108.65)
		(width 0.15)
		(layer "F.Cu")
		(net 1)
	)
	(segment
		(start 100.853485 79.391161)
		(end 100.847323 79.397323)
		(width 0.15)
		(layer "F.Cu")
		(net 1)
	)
	(segment
		(start 138.064 84.5)
		(end 137.8 84.5)
		(width 0.15)
		(layer "F.Cu")
		(net 1)
	)
	(segment
		(start 147.45 91.15)
		(end 146.875 91.15)
		(width 0.125)
		(layer "F.Cu")
		(net 1)
	)
	(segment
		(start 67.5 119.485)
		(end 68.6 119.485)
		(width 0.3)
		(layer "F.Cu")
		(net 1)
	)
	(segment
		(start 61.1 106.65)
		(end 61.115 106.635)
		(width 0.3)
		(layer "F.Cu")
		(net 1)
	)
	(segment
		(start 112.597323 73.251677)
		(end 112.597323 72.005136)
		(width 0.3)
		(layer "F.Cu")
		(net 1)
	)
	(segment
		(start 137.2 92.906098)
		(end 137.156098 92.95)
		(width 0.3)
		(layer "F.Cu")
		(net 1)
	)
	(segment
		(start 121.347323 81.159944)
		(end 121.347323 80.205136)
		(width 0.125)
		(layer "F.Cu")
		(net 1)
	)
	(segment
		(start 123.2 93.9)
		(end 123.15 93.95)
		(width 0.3)
		(layer "F.Cu")
		(net 1)
	)
	(segment
		(start 107.3 102.165)
		(end 106.3 102.165)
		(width 0.15)
		(layer "F.Cu")
		(net 1)
	)
	(segment
		(start 147.1 88.55)
		(end 146.875 88.775)
		(width 0.125)
		(layer "F.Cu")
		(net 1)
	)
	(segment
		(start 61.3 110.2)
		(end 60.985 109.885)
		(width 0.3)
		(layer "F.Cu")
		(net 1)
	)
	(segment
		(start 130.45 125.6)
		(end 130.95 125.1)
		(width 0.155)
		(layer "F.Cu")
		(net 1)
	)
	(segment
		(start 116.15 117.775)
		(end 116.15 118.2)
		(width 0.2)
		(layer "F.Cu")
		(net 1)
	)
	(segment
		(start 104.1 126.2)
		(end 104.3 126.2)
		(width 0.155)
		(layer "F.Cu")
		(net 1)
	)
	(segment
		(start 88.01 81.35)
		(end 88.01 80.367813)
		(width 0.125)
		(layer "F.Cu")
		(net 1)
	)
	(segment
		(start 104.3 126.3)
		(end 104.3 128)
		(width 0.155)
		(layer "F.Cu")
		(net 1)
	)
	(segment
		(start 145.15 112.75)
		(end 144.7 113.2)
		(width 0.3)
		(layer "F.Cu")
		(net 1)
	)
	(segment
		(start 123.32 98.43)
		(end 124.47 98.43)
		(width 0.3)
		(layer "F.Cu")
		(net 1)
	)
	(segment
		(start 116.55 117.375)
		(end 116.15 117.775)
		(width 0.2)
		(layer "F.Cu")
		(net 1)
	)
	(segment
		(start 115.597323 72.005136)
		(end 115.597323 73.397323)
		(width 0.15)
		(layer "F.Cu")
		(net 1)
	)
	(segment
		(start 121.22 78.56)
		(end 121.41 78.75)
		(width 0.125)
		(layer "F.Cu")
		(net 1)
	)
	(segment
		(start 71.99992 118.115)
		(end 71.99992 116.69008)
		(width 0.3)
		(layer "F.Cu")
		(net 1)
	)
	(segment
		(start 67.235 108.685)
		(end 67.75 109.2)
		(width 0.15)
		(layer "F.Cu")
		(net 1)
	)
	(segment
		(start 93.347323 81.262)
		(end 93.435323 81.35)
		(width 0.3)
		(layer "F.Cu")
		(net 1)
	)
	(segment
		(start 67.065 126.755)
		(end 66.303 126.755)
		(width 0.15)
		(layer "F.Cu")
		(net 1)
	)
	(segment
		(start 118.347323 80.205136)
		(end 118.347323 78.922677)
		(width 0.125)
		(layer "F.Cu")
		(net 1)
	)
	(segment
		(start 141.5 97.55)
		(end 140.55 97.55)
		(width 0.125)
		(layer "F.Cu")
		(net 1)
	)
	(segment
		(start 104.3 128)
		(end 104.35 128.05)
		(width 0.155)
		(layer "F.Cu")
		(net 1)
	)
	(segment
		(start 106.84 127.9)
		(end 106.72 128.02)
		(width 0.2)
		(layer "F.Cu")
		(net 1)
	)
	(segment
		(start 147.45 83.95)
		(end 147.04 83.95)
		(width 0.125)
		(layer "F.Cu")
		(net 1)
	)
	(segment
		(start 66.65 126.3)
		(end 66.25 126.7)
		(width 0.15)
		(layer "F.Cu")
		(net 1)
	)
	(segment
		(start 106.248 126.702)
		(end 106.25 126.7)
		(width 0.155)
		(layer "F.Cu")
		(net 1)
	)
	(segment
		(start 140.525 85.55)
		(end 141.5 85.55)
		(width 0.125)
		(layer "F.Cu")
		(net 1)
	)
	(segment
		(start 147.45 88.55)
		(end 147.1 88.55)
		(width 0.125)
		(layer "F.Cu")
		(net 1)
	)
	(segment
		(start 58.092533 90.275)
		(end 57.63 90.275)
		(width 0.125)
		(layer "F.Cu")
		(net 1)
	)
	(segment
		(start 97.55 122.75)
		(end 97.45 122.85)
		(width 0.2)
		(layer "F.Cu")
		(net 1)
	)
	(segment
		(start 106.735891 78.89666)
		(end 106.347323 79.285228)
		(width 0.125)
		(layer "F.Cu")
		(net 1)
	)
	(segment
		(start 65.8 126.2)
		(end 66.25 126.65)
		(width 0.155)
		(layer "F.Cu")
		(net 1)
	)
	(segment
		(start 107.075 102.09)
		(end 107.075 101.525)
		(width 0.15)
		(layer "F.Cu")
		(net 1)
	)
	(segment
		(start 142.13 97.55)
		(end 142.41 97.27)
		(width 0.15)
		(layer "F.Cu")
		(net 1)
	)
	(segment
		(start 126.08 73.34)
		(end 126.08 72.022459)
		(width 0.125)
		(layer "F.Cu")
		(net 1)
	)
	(segment
		(start 57.195 105.35)
		(end 57.815 105.35)
		(width 0.2)
		(layer "F.Cu")
		(net 1)
	)
	(segment
		(start 115.347323 79.072677)
		(end 115.52 78.9)
		(width 0.125)
		(layer "F.Cu")
		(net 1)
	)
	(segment
		(start 57.9 106.4)
		(end 57.9 106.515)
		(width 0.2)
		(layer "F.Cu")
		(net 1)
	)
	(segment
		(start 125.65 105.25)
		(end 125.65 104.8)
		(width 0.2)
		(layer "F.Cu")
		(net 1)
	)
	(segment
		(start 55.800167 108.700167)
		(end 56.1 109)
		(width 0.15)
		(layer "F.Cu")
		(net 1)
	)
	(segment
		(start 125.63 87.59)
		(end 125.44 87.4)
		(width 0.3)
		(layer "F.Cu")
		(net 1)
	)
	(segment
		(start 86.85 100.7)
		(end 86.85 101.51)
		(width 0.15)
		(layer "F.Cu")
		(net 1)
	)
	(segment
		(start 87.85 78.9)
		(end 87.85 80.202459)
		(width 0.125)
		(layer "F.Cu")
		(net 1)
	)
	(segment
		(start 108.889938 103.814438)
		(end 108.889938 104.345)
		(width 0.15)
		(layer "F.Cu")
		(net 1)
	)
	(segment
		(start 146.9 83.11)
		(end 146.86 83.15)
		(width 0.125)
		(layer "F.Cu")
		(net 1)
	)
	(segment
		(start 52.95 120.1)
		(end 53.45 120.1)
		(width 0.3)
		(layer "F.Cu")
		(net 1)
	)
	(segment
		(start 137.017 90.95)
		(end 136.24 90.95)
		(width 0.3)
		(layer "F.Cu")
		(net 1)
	)
	(segment
		(start 84.3225 116.0175)
		(end 84.54 115.8)
		(width 0.15)
		(layer "F.Cu")
		(net 1)
	)
	(segment
		(start 125.74 100.66)
		(end 125.74 100.29)
		(width 0.3)
		(layer "F.Cu")
		(net 1)
	)
	(segment
		(start 130.3 123.75)
		(end 129.5 123.75)
		(width 0.15)
		(layer "F.Cu")
		(net 1)
	)
	(segment
		(start 115.347323 81.512677)
		(end 115.347323 80.205136)
		(width 0.3)
		(layer "F.Cu")
		(net 1)
	)
	(segment
		(start 143.824481 103.849481)
		(end 142.325 102.35)
		(width 0.15)
		(layer "F.Cu")
		(net 1)
	)
	(segment
		(start 125.65 104.8)
		(end 125.25 104.4)
		(width 0.3)
		(layer "F.Cu")
		(net 1)
	)
	(segment
		(start 88.5155 127.4715)
		(end 87.3705 127.4715)
		(width 0.15)
		(layer "F.Cu")
		(net 1)
	)
	(segment
		(start 107.847323 81.312677)
		(end 107.847323 80.205136)
		(width 0.125)
		(layer "F.Cu")
		(net 1)
	)
	(segment
		(start 122.9 125.4)
		(end 122.9 125.05)
		(width 0.155)
		(layer "F.Cu")
		(net 1)
	)
	(segment
		(start 65.4 126.2)
		(end 62.6 126.2)
		(width 0.155)
		(layer "F.Cu")
		(net 1)
	)
	(segment
		(start 67.2 108.685)
		(end 67.235 108.685)
		(width 0.15)
		(layer "F.Cu")
		(net 1)
	)
	(segment
		(start 110.6 118.25)
		(end 110.65 118.2)
		(width 0.2)
		(layer "F.Cu")
		(net 1)
	)
	(segment
		(start 96.597323 70.902677)
		(end 96.597323 72.005136)
		(width 0.15)
		(layer "F.Cu")
		(net 1)
	)
	(segment
		(start 86.05 112.7)
		(end 86.05 111.05)
		(width 0.15)
		(layer "F.Cu")
		(net 1)
	)
	(segment
		(start 104.6 126.2)
		(end 105.548 126.2)
		(width 0.155)
		(layer "F.Cu")
		(net 1)
	)
	(segment
		(start 125.47 85.9)
		(end 124.5 85.9)
		(width 0.3)
		(layer "F.Cu")
		(net 1)
	)
	(segment
		(start 116.15 119.4)
		(end 116.2 119.45)
		(width 0.2)
		(layer "F.Cu")
		(net 1)
	)
	(segment
		(start 112.347323 79.142677)
		(end 112.347323 80.205136)
		(width 0.125)
		(layer "F.Cu")
		(net 1)
	)
	(segment
		(start 145.14 83.35)
		(end 145.34 83.15)
		(width 0.125)
		(layer "F.Cu")
		(net 1)
	)
	(segment
		(start 127.8 125.6)
		(end 128.05 125.6)
		(width 0.155)
		(layer "F.Cu")
		(net 1)
	)
	(segment
		(start 127.55 125.6)
		(end 127.8 125.6)
		(width 0.155)
		(layer "F.Cu")
		(net 1)
	)
	(segment
		(start 90.895 117.25)
		(end 91.373763 117.25)
		(width 0.2)
		(layer "F.Cu")
		(net 1)
	)
	(segment
		(start 138.65 85.6)
		(end 138.5 85.75)
		(width 0.15)
		(layer "F.Cu")
		(net 1)
	)
	(segment
		(start 66.59 73.27)
		(end 66.597323 73.262677)
		(width 0.3)
		(layer "F.Cu")
		(net 1)
	)
	(segment
		(start 106.597323 72.005136)
		(end 106.597323 70.732677)
		(width 0.15)
		(layer "F.Cu")
		(net 1)
	)
	(segment
		(start 104.2 126.2)
		(end 104.3 126.3)
		(width 0.155)
		(layer "F.Cu")
		(net 1)
	)
	(segment
		(start 83.352866 81.347134)
		(end 83.35 81.344268)
		(width 0.125)
		(layer "F.Cu")
		(net 1)
	)
	(segment
		(start 123.14 87.4)
		(end 124.5 87.4)
		(width 0.3)
		(layer "F.Cu")
		(net 1)
	)
	(segment
		(start 90.844646 70.7)
		(end 91.097323 70.952677)
		(width 0.2)
		(layer "F.Cu")
		(net 1)
	)
	(segment
		(start 116.15 118.2)
		(end 116.15 119.4)
		(width 0.2)
		(layer "F.Cu")
		(net 1)
	)
	(segment
		(start 57.815 105.35)
		(end 58.16 105.695)
		(width 0.2)
		(layer "F.Cu")
		(net 1)
	)
	(segment
		(start 125.57 86)
		(end 125.47 85.9)
		(width 0.3)
		(layer "F.Cu")
		(net 1)
	)
	(segment
		(start 67.9 113.35)
		(end 67.85 113.3)
		(width 0.3)
		(layer "F.Cu")
		(net 1)
	)
	(segment
		(start 98.097323 72.005136)
		(end 98.097323 70.827677)
		(width 0.15)
		(layer "F.Cu")
		(net 1)
	)
	(segment
		(start 125.35 93.9)
		(end 124.5 93.9)
		(width 0.3)
		(layer "F.Cu")
		(net 1)
	)
	(segment
		(start 95.1 70.37)
		(end 95.097323 70.372677)
		(width 0.15)
		(layer "F.Cu")
		(net 1)
	)
	(segment
		(start 84.597323 70.702677)
		(end 84.597323 72.005136)
		(width 0.125)
		(layer "F.Cu")
		(net 1)
	)
	(segment
		(start 61.115 106.635)
		(end 61.115 107)
		(width 0.3)
		(layer "F.Cu")
		(net 1)
	)
	(segment
		(start 140.5 113)
		(end 140.65 112.85)
		(width 0.3)
		(layer "F.Cu")
		(net 1)
	)
	(segment
		(start 144.142909 103.849481)
		(end 143.824481 103.849481)
		(width 0.15)
		(layer "F.Cu")
		(net 1)
	)
	(segment
		(start 89.3 118.9)
		(end 89.3 118.435)
		(width 0.2)
		(layer "F.Cu")
		(net 1)
	)
	(segment
		(start 112.35 79.14)
		(end 112.347323 79.142677)
		(width 0.125)
		(layer "F.Cu")
		(net 1)
	)
	(segment
		(start 140.85 92.75)
		(end 141.5 92.75)
		(width 0.125)
		(layer "F.Cu")
		(net 1)
	)
	(segment
		(start 121.114209 81.393058)
		(end 121.347323 81.159944)
		(width 0.125)
		(layer "F.Cu")
		(net 1)
	)
	(segment
		(start 70.47992 127.62008)
		(end 70.47992 125.245)
		(width 0.2)
		(layer "F.Cu")
		(net 1)
	)
	(segment
		(start 91.373763 117.25)
		(end 91.945769 117.822006)
		(width 0.2)
		(layer "F.Cu")
		(net 1)
	)
	(segment
		(start 83.5 74.25)
		(end 83.5 73.45)
		(width 0.125)
		(layer "F.Cu")
		(net 1)
	)
	(segment
		(start 65.73 99.99)
		(end 64.85 99.99)
		(width 0.125)
		(layer "F.Cu")
		(net 1)
	)
	(segment
		(start 124.5 101.4)
		(end 123.47 101.4)
		(width 0.3)
		(layer "F.Cu")
		(net 1)
	)
	(segment
		(start 140.72 93.08)
		(end 140.72 92.88)
		(width 0.125)
		(layer "F.Cu")
		(net 1)
	)
	(segment
		(start 123.1 73.25)
		(end 123.097323 73.247323)
		(width 0.125)
		(layer "F.Cu")
		(net 1)
	)
	(segment
		(start 113.847323 81.447323)
		(end 113.847323 80.205136)
		(width 0.125)
		(layer "F.Cu")
		(net 1)
	)
	(segment
		(start 54.98 90.275)
		(end 54.81 90.105)
		(width 0.125)
		(layer "F.Cu")
		(net 1)
	)
	(segment
		(start 142.42 85.83)
		(end 142.14 85.55)
		(width 0.15)
		(layer "F.Cu")
		(net 1)
	)
	(segment
		(start 100.853485 78.702711)
		(end 100.853485 79.391161)
		(width 0.15)
		(layer "F.Cu")
		(net 1)
	)
	(segment
		(start 135.815 120.675)
		(end 135.8 120.69)
		(width 0.2)
		(layer "F.Cu")
		(net 1)
	)
	(segment
		(start 93.625 120.825)
		(end 93.625 120.285)
		(width 0.2)
		(layer "F.Cu")
		(net 1)
	)
	(segment
		(start 109.483979 73.6229)
		(end 109.483979 73.236021)
		(width 0.125)
		(layer "F.Cu")
		(net 1)
	)
	(segment
		(start 112.25 73.599)
		(end 112.597323 73.251677)
		(width 0.3)
		(layer "F.Cu")
		(net 1)
	)
	(segment
		(start 96.65 70.85)
		(end 96.597323 70.902677)
		(width 0.15)
		(layer "F.Cu")
		(net 1)
	)
	(segment
		(start 93.625 119.515)
		(end 93.625 120.285)
		(width 0.2)
		(layer "F.Cu")
		(net 1)
	)
	(segment
		(start 134.3 117.9)
		(end 131.95 117.9)
		(width 0.2)
		(layer "F.Cu")
		(net 1)
	)
	(segment
		(start 145.34 83.15)
		(end 146 83.15)
		(width 0.125)
		(layer "F.Cu")
		(net 1)
	)
	(segment
		(start 127.8 125.6)
		(end 127.8 125.4)
		(width 0.155)
		(layer "F.Cu")
		(net 1)
	)
	(segment
		(start 145.2 86.375)
		(end 145.975 86.375)
		(width 0.125)
		(layer "F.Cu")
		(net 1)
	)
	(segment
		(start 147.7 119.385)
		(end 147.785 119.3)
		(width 0.3)
		(layer "F.Cu")
		(net 1)
	)
	(segment
		(start 74.347323 81.552677)
		(end 74.347323 80.205136)
		(width 0.15)
		(layer "F.Cu")
		(net 1)
	)
	(segment
		(start 122.847323 81.452677)
		(end 122.75 81.55)
		(width 0.125)
		(layer "F.Cu")
		(net 1)
	)
	(segment
		(start 87.05 120.8)
		(end 87.05 122.5)
		(width 0.2)
		(layer "F.Cu")
		(net 1)
	)
	(segment
		(start 128.05 125.6)
		(end 128 125.6)
		(width 0.155)
		(layer "F.Cu")
		(net 1)
	)
	(segment
		(start 123.24 86.26)
		(end 123.6 85.9)
		(width 0.3)
		(layer "F.Cu")
		(net 1)
	)
	(segment
		(start 81.87 78.9)
		(end 81.87 80.182459)
		(width 0.125)
		(layer "F.Cu")
		(net 1)
	)
	(segment
		(start 105.097323 70.787323)
		(end 105.097323 72.005136)
		(width 0.15)
		(layer "F.Cu")
		(net 1)
	)
	(segment
		(start 123.24 86.48)
		(end 123.24 86.26)
		(width 0.3)
		(layer "F.Cu")
		(net 1)
	)
	(segment
		(start 91.75 93.25)
		(end 92.35 93.25)
		(width 0.15)
		(layer "F.Cu")
		(net 1)
	)
	(segment
		(start 83.5 73.45)
		(end 83.097323 73.047323)
		(width 0.125)
		(layer "F.Cu")
		(net 1)
	)
	(segment
		(start 109.347323 79.024382)
		(end 109.107954 78.785013)
		(width 0.125)
		(layer "F.Cu")
		(net 1)
	)
	(segment
		(start 109.347323 81.327323)
		(end 109.46 81.44)
		(width 0.15)
		(layer "F.Cu")
		(net 1)
	)
	(segment
		(start 122.847323 78.933847)
		(end 122.847323 81.452677)
		(width 0.125)
		(layer "F.Cu")
		(net 1)
	)
	(segment
		(start 68.9 87.489)
		(end 69.811 87.489)
		(width 0.3)
		(layer "F.Cu")
		(net 1)
	)
	(segment
		(start 91.847323 80.205136)
		(end 91.847323 79.197323)
		(width 0.2)
		(layer "F.Cu")
		(net 1)
	)
	(segment
		(start 114.097323 72.875177)
		(end 114.097323 72.005136)
		(width 0.125)
		(layer "F.Cu")
		(net 1)
	)
	(segment
		(start 140.72 92.88)
		(end 140.85 92.75)
		(width 0.125)
		(layer "F.Cu")
		(net 1)
	)
	(segment
		(start 113.847323 78.687323)
		(end 113.847323 80.205136)
		(width 0.125)
		(layer "F.Cu")
		(net 1)
	)
	(segment
		(start 145.225 88.75)
		(end 146 88.75)
		(width 0.125)
		(layer "F.Cu")
		(net 1)
	)
	(segment
		(start 72 115.115)
		(end 72 115.885)
		(width 0.13)
		(layer "F.Cu")
		(net 1)
	)
	(segment
		(start 104.1 126.2)
		(end 104.2 126.2)
		(width 0.155)
		(layer "F.Cu")
		(net 1)
	)
	(segment
		(start 80.347323 81.433115)
		(end 80.347323 80.205136)
		(width 0.125)
		(layer "F.Cu")
		(net 1)
	)
	(segment
		(start 80.414208 81.5)
		(end 80.347323 81.433115)
		(width 0.125)
		(layer "F.Cu")
		(net 1)
	)
	(segment
		(start 117.14 70.74)
		(end 117.097323 70.782677)
		(width 0.125)
		(layer "F.Cu")
		(net 1)
	)
	(segment
		(start 116.05 90.15)
		(end 117 90.15)
		(width 0.3)
		(layer "F.Cu")
		(net 1)
	)
	(segment
		(start 140.525 83.15)
		(end 141.5 83.15)
		(width 0.125)
		(layer "F.Cu")
		(net 1)
	)
	(segment
		(start 119.847323 80.205136)
		(end 119.847323 78.68212)
		(width 0.125)
		(layer "F.Cu")
		(net 1)
	)
	(segment
		(start 112.52 86.3)
		(end 112.52 86.395)
		(width 0.15)
		(layer "F.Cu")
		(net 1)
	)
	(segment
		(start 120.14 70.41)
		(end 120.097323 70.452677)
		(width 0.125)
		(layer "F.Cu")
		(net 1)
	)
	(segment
		(start 115.696953 89.549538)
		(end 115.696953 89.796953)
		(width 0.3)
		(layer "F.Cu")
		(net 1)
	)
	(segment
		(start 106.597323 70.732677)
		(end 106.6 70.73)
		(width 0.15)
		(layer "F.Cu")
		(net 1)
	)
	(segment
		(start 120.097323 70.452677)
		(end 120.097323 72.005136)
		(width 0.125)
		(layer "F.Cu")
		(net 1)
	)
	(segment
		(start 72.47 84.88)
		(end 74.94 84.88)
		(width 0.15)
		(layer "F.Cu")
		(net 1)
	)
	(segment
		(start 123.6 85.9)
		(end 124.5 85.9)
		(width 0.3)
		(layer "F.Cu")
		(net 1)
	)
	(segment
		(start 100.847323 79.397323)
		(end 100.847323 80.205136)
		(width 0.15)
		(layer "F.Cu")
		(net 1)
	)
	(segment
		(start 78 115.885)
		(end 78 115.115)
		(width 0.15)
		(layer "F.Cu")
		(net 1)
	)
	(segment
		(start 65.4 126.2)
		(end 65.8 126.2)
		(width 0.155)
		(layer "F.Cu")
		(net 1)
	)
	(segment
		(start 131.6 118.25)
		(end 131.6 119.7)
		(width 0.2)
		(layer "F.Cu")
		(net 1)
	)
	(segment
		(start 93.95 121.15)
		(end 93.625 120.825)
		(width 0.2)
		(layer "F.Cu")
		(net 1)
	)
	(segment
		(start 72.212 102.65)
		(end 71.915 102.65)
		(width 0.3)
		(layer "F.Cu")
		(net 1)
	)
	(segment
		(start 142 97.55)
		(end 141.5 97.55)
		(width 0.125)
		(layer "F.Cu")
		(net 1)
	)
	(segment
		(start 101.2 115.515)
		(end 101.2 114.725)
		(width 0.3)
		(layer "F.Cu")
		(net 1)
	)
	(segment
		(start 65.43 94.35)
		(end 65.43 93.83)
		(width 0.125)
		(layer "F.Cu")
		(net 1)
	)
	(segment
		(start 142.325 102.35)
		(end 141.5 102.35)
		(width 0.15)
		(layer "F.Cu")
		(net 1)
	)
	(segment
		(start 140.45 87.95)
		(end 140.425 87.975)
		(width 0.125)
		(layer "F.Cu")
		(net 1)
	)
	(segment
		(start 141.5 90.35)
		(end 140.6 90.35)
		(width 0.125)
		(layer "F.Cu")
		(net 1)
	)
	(segment
		(start 125.847323 79.072677)
		(end 125.847323 80.205136)
		(width 0.125)
		(layer "F.Cu")
		(net 1)
	)
	(segment
		(start 137.85 82)
		(end 137.75 82.1)
		(width 0.15)
		(layer "F.Cu")
		(net 1)
	)
	(segment
		(start 124.347323 81.347323)
		(end 124.347323 80.205136)
		(width 0.125)
		(layer "F.Cu")
		(net 1)
	)
	(segment
		(start 146.85 88.75)
		(end 146.875 88.775)
		(width 0.125)
		(layer "F.Cu")
		(net 1)
	)
	(segment
		(start 138.539 84.975)
		(end 138.064 84.5)
		(width 0.15)
		(layer "F.Cu")
		(net 1)
	)
	(segment
		(start 123.01 100.94)
		(end 123.01 100.86)
		(width 0.3)
		(layer "F.Cu")
		(net 1)
	)
	(segment
		(start 125.808002 81.391998)
		(end 125.85 81.35)
		(width 0.125)
		(layer "F.Cu")
		(net 1)
	)
	(segment
		(start 145.1 111.1)
		(end 145.15 111.15)
		(width 0.3)
		(layer "F.Cu")
		(net 1)
	)
	(segment
		(start 87.597323 73.971676)
		(end 87.597323 70.802677)
		(width 0.125)
		(layer "F.Cu")
		(net 1)
	)
	(segment
		(start 104.4 126.2)
		(end 104.3 126.3)
		(width 0.155)
		(layer "F.Cu")
		(net 1)
	)
	(segment
		(start 96.675 119.515)
		(end 96.675 120.285)
		(width 0.2)
		(layer "F.Cu")
		(net 1)
	)
	(segment
		(start 69.55 108.835)
		(end 69.415 108.7)
		(width 0.2)
		(layer "F.Cu")
		(net 1)
	)
	(segment
		(start 118.478081 81.52704)
		(end 118.347323 81.396282)
		(width 0.3)
		(layer "F.Cu")
		(net 1)
	)
	(segment
		(start 121.597323 70.657323)
		(end 121.597323 72.005136)
		(width 0.125)
		(layer "F.Cu")
		(net 1)
	)
	(segment
		(start 113.55 116.563749)
		(end 113.55 115.793749)
		(width 0.15)
		(layer "F.Cu")
		(net 1)
	)
	(segment
		(start 146.875 86.275)
		(end 147.095 86.275)
		(width 0.125)
		(layer "F.Cu")
		(net 1)
	)
	(segment
		(start 109.597323 73.122677)
		(end 109.597323 72.005136)
		(width 0.125)
		(layer "F.Cu")
		(net 1)
	)
	(segment
		(start 90.6 119.515)
		(end 90.6 120.285)
		(width 0.2)
		(layer "F.Cu")
		(net 1)
	)
	(segment
		(start 83.097323 72.005136)
		(end 83.097323 71.107323)
		(width 0.125)
		(layer "F.Cu")
		(net 1)
	)
	(segment
		(start 89.75 81.3)
		(end 89.96 81.3)
		(width 0.3)
		(layer "F.Cu")
		(net 1)
	)
	(segment
		(start 115.696953 89.796953)
		(end 116.05 90.15)
		(width 0.3)
		(layer "F.Cu")
		(net 1)
	)
	(segment
		(start 71.99992 116.69008)
		(end 72.14 116.55)
		(width 0.3)
		(layer "F.Cu")
		(net 1)
	)
	(segment
		(start 146 107.15)
		(end 145.1245 107.15)
		(width 0.3)
		(layer "F.Cu")
		(net 1)
	)
	(segment
		(start 126.85 125.15)
		(end 127.3 125.6)
		(width 0.155)
		(layer "F.Cu")
		(net 1)
	)
	(segment
		(start 91.180619 92.3)
		(end 91.180619 92.680619)
		(width 0.15)
		(layer "F.Cu")
		(net 1)
	)
	(segment
		(start 124.5 96.9)
		(end 125.54 96.9)
		(width 0.3)
		(layer "F.Cu")
		(net 1)
	)
	(segment
		(start 125.95 78.97)
		(end 125.847323 79.072677)
		(width 0.125)
		(layer "F.Cu")
		(net 1)
	)
	(segment
		(start 60.985 109.885)
		(end 60.7 109.885)
		(width 0.3)
		(layer "F.Cu")
		(net 1)
	)
	(segment
		(start 128 125.6)
		(end 127.8 125.4)
		(width 0.155)
		(layer "F.Cu")
		(net 1)
	)
	(segment
		(start 146 91.15)
		(end 146.825 91.15)
		(width 0.125)
		(layer "F.Cu")
		(net 1)
	)
	(segment
		(start 72 116.41)
		(end 72.14 116.55)
		(width 0.13)
		(layer "F.Cu")
		(net 1)
	)
	(segment
		(start 58.555 125.995)
		(end 57.911 125.995)
		(width 0.15)
		(layer "F.Cu")
		(net 1)
	)
	(segment
		(start 58.2598 90.107733)
		(end 58.092533 90.275)
		(width 0.125)
		(layer "F.Cu")
		(net 1)
	)
	(segment
		(start 86.08 70.77)
		(end 86.08 71.987813)
		(width 0.125)
		(layer "F.Cu")
		(net 1)
	)
	(segment
		(start 112.2 78.9)
		(end 112.2 78.99)
		(width 0.125)
		(layer "F.Cu")
		(net 1)
	)
	(segment
		(start 113.4725 73.5)
		(end 114.097323 72.875177)
		(width 0.125)
		(layer "F.Cu")
		(net 1)
	)
	(segment
		(start 92.226064 70.626064)
		(end 92.597323 70.997323)
		(width 0.15)
		(layer "F.Cu")
		(net 1)
	)
	(segment
		(start 99.597323 70.777677)
		(end 99.6 70.775)
		(width 0.15)
		(layer "F.Cu")
		(net 1)
	)
	(segment
		(start 106.05 118.35)
		(end 106.025 118.35)
		(width 0.15)
		(layer "F.Cu")
		(net 1)
	)
	(segment
		(start 115.195585 81.664415)
		(end 115.347323 81.512677)
		(width 0.3)
		(layer "F.Cu")
		(net 1)
	)
	(segment
		(start 131.6 119.7)
		(end 131.6 120.6475)
		(width 0.2)
		(layer "F.Cu")
		(net 1)
	)
	(segment
		(start 104.669938 108)
		(end 103.45 108)
		(width 0.15)
		(layer "F.Cu")
		(net 1)
	)
	(segment
		(start 123.1 125.6)
		(end 124.45 125.6)
		(width 0.155)
		(layer "F.Cu")
		(net 1)
	)
	(segment
		(start 123.13 87.39)
		(end 123.14 87.4)
		(width 0.3)
		(layer "F.Cu")
		(net 1)
	)
	(segment
		(start 78.62 110.825)
		(end 78.62 111.37)
		(width 0.2)
		(layer "F.Cu")
		(net 1)
	)
	(segment
		(start 123.1 95.441)
		(end 123.141 95.4)
		(width 0.3)
		(layer "F.Cu")
		(net 1)
	)
	(segment
		(start 84.83 78.94)
		(end 84.83 80.187813)
		(width 0.125)
		(layer "F.Cu")
		(net 1)
	)
	(segment
		(start 134.35 90.15)
		(end 134.19 90.31)
		(width 0.3)
		(layer "F.Cu")
		(net 1)
	)
	(segment
		(start 108.097323 73.366323)
		(end 108.097323 72.005136)
		(width 0.125)
		(layer "F.Cu")
		(net 1)
	)
	(segment
		(start 102.454 126.2)
		(end 104.1 126.2)
		(width 0.155)
		(layer "F.Cu")
		(net 1)
	)
	(segment
		(start 101.215 122.9)
		(end 101.2 122.885)
		(width 0.2)
		(layer "F.Cu")
		(net 1)
	)
	(segment
		(start 55.83 89.825)
		(end 55.175 89.825)
		(width 0.125)
		(layer "F.Cu")
		(net 1)
	)
	(segment
		(start 127.8 125.4)
		(end 127.8 125.05)
		(width 0.155)
		(layer "F.Cu")
		(net 1)
	)
	(segment
		(start 87.55 123)
		(end 88.525 123)
		(width 0.2)
		(layer "F.Cu")
		(net 1)
	)
	(segment
		(start 140.6 90.35)
		(end 140.5 90.45)
		(width 0.125)
		(layer "F.Cu")
		(net 1)
	)
	(segment
		(start 80.1 71.2)
		(end 80.097323 71.202677)
		(width 0.125)
		(layer "F.Cu")
		(net 1)
	)
	(segment
		(start 127.3 125.6)
		(end 127.55 125.6)
		(width 0.155)
		(layer "F.Cu")
		(net 1)
	)
	(segment
		(start 68.8 127.85)
		(end 70.25 127.85)
		(width 0.2)
		(layer "F.Cu")
		(net 1)
	)
	(segment
		(start 146 112.75)
		(end 145.15 112.75)
		(width 0.3)
		(layer "F.Cu")
		(net 1)
	)
	(segment
		(start 142.14 85.55)
		(end 141.5 85.55)
		(width 0.15)
		(layer "F.Cu")
		(net 1)
	)
	(segment
		(start 111.097323 73.137323)
		(end 111.52 73.56)
		(width 0.3)
		(layer "F.Cu")
		(net 1)
	)
	(segment
		(start 136.63 108.32)
		(end 136.63 109.05)
		(width 0.3)
		(layer "F.Cu")
		(net 1)
	)
	(segment
		(start 68.6 119.485)
		(end 69.515 119.485)
		(width 0.3)
		(layer "F.Cu")
		(net 1)
	)
	(segment
		(start 95.097323 70.372677)
		(end 95.097323 72.005136)
		(width 0.15)
		(layer "F.Cu")
		(net 1)
	)
	(segment
		(start 55.175 89.825)
		(end 54.9 90.1)
		(width 0.125)
		(layer "F.Cu")
		(net 1)
	)
	(segment
		(start 124.47 98.43)
		(end 124.5 98.4)
		(width 0.3)
		(layer "F.Cu")
		(net 1)
	)
	(segment
		(start 145.175 91.125)
		(end 145.975 91.125)
		(width 0.125)
		(layer "F.Cu")
		(net 1)
	)
	(segment
		(start 147.04 83.95)
		(end 146.876533 84.113467)
		(width 0.125)
		(layer "F.Cu")
		(net 1)
	)
	(segment
		(start 142.42 86.49)
		(end 142.42 85.83)
		(width 0.15)
		(layer "F.Cu")
		(net 1)
	)
	(segment
		(start 141.5 87.95)
		(end 142.35 87.95)
		(width 0.125)
		(layer "F.Cu")
		(net 1)
	)
	(segment
		(start 118.597323 70.747323)
		(end 118.597323 72.005136)
		(width 0.125)
		(layer "F.Cu")
		(net 1)
	)
	(segment
		(start 90.15 70.7)
		(end 90.844646 70.7)
		(width 0.2)
		(layer "F.Cu")
		(net 1)
	)
	(segment
		(start 74.2 81.7)
		(end 74.347323 81.552677)
		(width 0.15)
		(layer "F.Cu")
		(net 1)
	)
	(segment
		(start 83.35 81.344268)
		(end 83.35 80.207813)
		(width 0.125)
		(layer "F.Cu")
		(net 1)
	)
	(segment
		(start 146.9 93.8)
		(end 146.65 93.55)
		(width 0.125)
		(layer "F.Cu")
		(net 1)
	)
	(segment
		(start 134.45 118.05)
		(end 134.3 117.9)
		(width 0.2)
		(layer "F.Cu")
		(net 1)
	)
	(segment
		(start 71.99992 118.115)
		(end 71.99992 119.315)
		(width 0.3)
		(layer "F.Cu")
		(net 1)
	)
	(segment
		(start 84.847323 81.357323)
		(end 84.847323 80.205136)
		(width 0.125)
		(layer "F.Cu")
		(net 1)
	)
	(segment
		(start 107.71 81.45)
		(end 107.847323 81.312677)
		(width 0.125)
		(layer "F.Cu")
		(net 1)
	)
	(segment
		(start 146 97.55)
		(end 145.2 97.55)
		(width 0.125)
		(layer "F.Cu")
		(net 1)
	)
	(segment
		(start 140 113)
		(end 140.5 113)
		(width 0.3)
		(layer "F.Cu")
		(net 1)
	)
	(segment
		(start 123.54 102.9)
		(end 122.98 103.46)
		(width 0.3)
		(layer "F.Cu")
		(net 1)
	)
	(segment
		(start 126.097323 72.005136)
		(end 126.097323 70.652677)
		(width 0.125)
		(layer "F.Cu")
		(net 1)
	)
	(segment
		(start 91.097323 70.952677)
		(end 91.097323 72.005136)
		(width 0.2)
		(layer "F.Cu")
		(net 1)
	)
	(segment
		(start 113.76 78.6)
		(end 113.847323 78.687323)
		(width 0.125)
		(layer "F.Cu")
		(net 1)
	)
	(segment
		(start 149.0245 113.3)
		(end 148.995 113.3)
		(width 0.3)
		(layer "F.Cu")
		(net 1)
	)
	(segment
		(start 124.35 81.35)
		(end 124.347323 81.347323)
		(width 0.125)
		(layer "F.Cu")
		(net 1)
	)
	(segment
		(start 104.3 126.2)
		(end 104.3 126.3)
		(width 0.155)
		(layer "F.Cu")
		(net 1)
	)
	(segment
		(start 72 115.885)
		(end 72 116.41)
		(width 0.13)
		(layer "F.Cu")
		(net 1)
	)
	(segment
		(start 119.84 81.46)
		(end 119.84 80.212459)
		(width 0.3)
		(layer "F.Cu")
		(net 1)
	)
	(segment
		(start 146 97.55)
		(end 146.86 97.55)
		(width 0.3)
		(layer "F.Cu")
		(net 1)
	)
	(segment
		(start 110.55 115.793749)
		(end 110.55 116.563749)
		(width 0.2)
		(layer "F.Cu")
		(net 1)
	)
	(segment
		(start 101.7 122.9)
		(end 101.215 122.9)
		(width 0.2)
		(layer "F.Cu")
		(net 1)
	)
	(segment
		(start 136.915 113.365)
		(end 137.25 113.7)
		(width 0.5)
		(layer "F.Cu")
		(net 1)
	)
	(segment
		(start 84.6 70.7)
		(end 84.597323 70.702677)
		(width 0.125)
		(layer "F.Cu")
		(net 1)
	)
	(segment
		(start 84.597323 73.197323)
		(end 84.597323 72.005136)
		(width 0.125)
		(layer "F.Cu")
		(net 1)
	)
	(segment
		(start 86.05 111.05)
		(end 86.325 110.775)
		(width 0.15)
		(layer "F.Cu")
		(net 1)
	)
	(segment
		(start 74.94 85.34)
		(end 74.94 84.88)
		(width 0.15)
		(layer "F.Cu")
		(net 1)
	)
	(segment
		(start 70 111.752469)
		(end 70 110.982469)
		(width 0.3)
		(layer "F.Cu")
		(net 1)
	)
	(segment
		(start 115.347323 80.205136)
		(end 115.347323 79.072677)
		(width 0.125)
		(layer "F.Cu")
		(net 1)
	)
	(segment
		(start 109.347323 80.205136)
		(end 109.347323 81.327323)
		(width 0.15)
		(layer "F.Cu")
		(net 1)
	)
	(segment
		(start 89.96 81.3)
		(end 90.347323 80.912677)
		(width 0.3)
		(layer "F.Cu")
		(net 1)
	)
	(segment
		(start 59.3 124.1)
		(end 59.3 125.25)
		(width 0.15)
		(layer "F.Cu")
		(net 1)
	)
	(segment
		(start 123.141 95.4)
		(end 125.48 95.4)
		(width 0.3)
		(layer "F.Cu")
		(net 1)
	)
	(segment
		(start 109.483979 73.236021)
		(end 109.597323 73.122677)
		(width 0.125)
		(layer "F.Cu")
		(net 1)
	)
	(segment
		(start 75 115.115)
		(end 75 115.885)
		(width 0.15)
		(layer "F.Cu")
		(net 1)
	)
	(segment
		(start 146 88.75)
		(end 146.85 88.75)
		(width 0.125)
		(layer "F.Cu")
		(net 1)
	)
	(segment
		(start 81.61 70.72)
		(end 81.61 71.992459)
		(width 0.125)
		(layer "F.Cu")
		(net 1)
	)
	(segment
		(start 127.55 125.6)
		(end 127.6 125.6)
		(width 0.155)
		(layer "F.Cu")
		(net 1)
	)
	(segment
		(start 95.15 122)
		(end 95.15 122.85)
		(width 0.2)
		(layer "F.Cu")
		(net 1)
	)
	(segment
		(start 69.515 119.485)
		(end 70.47992 120.44992)
		(width 0.3)
		(layer "F.Cu")
		(net 1)
	)
	(segment
		(start 146.73 83.95)
		(end 146.876533 84.096533)
		(width 0.125)
		(layer "F.Cu")
		(net 1)
	)
	(segment
		(start 108.11 73.379)
		(end 108.097323 73.366323)
		(width 0.125)
		(layer "F.Cu")
		(net 1)
	)
	(segment
		(start 85 74.25)
		(end 85 73.6)
		(width 0.125)
		(layer "F.Cu")
		(net 1)
	)
	(segment
		(start 83.097323 73.047323)
		(end 83.097323 72.005136)
		(width 0.125)
		(layer "F.Cu")
		(net 1)
	)
	(segment
		(start 105.548 126.2)
		(end 106.05 126.702)
		(width 0.155)
		(layer "F.Cu")
		(net 1)
	)
	(segment
		(start 62.7 110.2)
		(end 63 110.5)
		(width 0.3)
		(layer "F.Cu")
		(net 1)
	)
	(segment
		(start 125.6 93.99)
		(end 125.44 93.99)
		(width 0.3)
		(layer "F.Cu")
		(net 1)
	)
	(segment
		(start 124.5 102.9)
		(end 123.54 102.9)
		(width 0.3)
		(layer "F.Cu")
		(net 1)
	)
	(segment
		(start 67.7 126.3)
		(end 66.65 126.3)
		(width 0.15)
		(layer "F.Cu")
		(net 1)
	)
	(segment
		(start 137.95 87.9)
		(end 138.75 87.9)
		(width 0.15)
		(layer "F.Cu")
		(net 1)
	)
	(segment
		(start 106.025 118.35)
		(end 105.65 118.725)
		(width 0.15)
		(layer "F.Cu")
		(net 1)
	)
	(segment
		(start 122.9 125.6)
		(end 122.9 125.4)
		(width 0.155)
		(layer "F.Cu")
		(net 1)
	)
	(segment
		(start 102.2 115.515)
		(end 101.2 115.515)
		(width 0.3)
		(layer "F.Cu")
		(net 1)
	)
	(segment
		(start 90.6 119.515)
		(end 90.6 118.6)
		(width 0.2)
		(layer "F.Cu")
		(net 1)
	)
	(segment
		(start 83.097323 71.107323)
		(end 82.74 70.75)
		(width 0.125)
		(layer "F.Cu")
		(net 1)
	)
	(segment
		(start 125.63 88.1)
		(end 125.63 87.59)
		(width 0.3)
		(layer "F.Cu")
		(net 1)
	)
	(segment
		(start 146.86 97.55)
		(end 146.95 97.64)
		(width 0.3)
		(layer "F.Cu")
		(net 1)
	)
	(segment
		(start 66.597323 73.262677)
		(end 66.597323 72.005136)
		(width 0.3)
		(layer "F.Cu")
		(net 1)
	)
	(segment
		(start 124.5 98.4)
		(end 125.42 98.4)
		(width 0.3)
		(layer "F.Cu")
		(net 1)
	)
	(segment
		(start 86.85 101.51)
		(end 86.97 101.63)
		(width 0.15)
		(layer "F.Cu")
		(net 1)
	)
	(segment
		(start 75 114.6)
		(end 75 115.115)
		(width 0.15)
		(layer "F.Cu")
		(net 1)
	)
	(segment
		(start 121.3 125.6)
		(end 122.7 125.6)
		(width 0.155)
		(layer "F.Cu")
		(net 1)
	)
	(segment
		(start 99.597323 72.005136)
		(end 99.597323 70.777677)
		(width 0.15)
		(layer "F.Cu")
		(net 1)
	)
	(segment
		(start 59.3 125.25)
		(end 58.555 125.995)
		(width 0.15)
		(layer "F.Cu")
		(net 1)
	)
	(segment
		(start 144.987667 102.962333)
		(end 145.6 102.35)
		(width 0.15)
		(layer "F.Cu")
		(net 1)
	)
	(segment
		(start 62.15 126.65)
		(end 62.15 126.7)
		(width 0.155)
		(layer "F.Cu")
		(net 1)
	)
	(segment
		(start 104.3 126.2)
		(end 104.6 126.2)
		(width 0.155)
		(layer "F.Cu")
		(net 1)
	)
	(segment
		(start 74.94 84.88)
		(end 74.94 84.34)
		(width 0.15)
		(layer "F.Cu")
		(net 1)
	)
	(segment
		(start 142.45 90.63)
		(end 142.17 90.35)
		(width 0.15)
		(layer "F.Cu")
		(net 1)
	)
	(segment
		(start 115.56 70.75)
		(end 115.597323 70.787323)
		(width 0.125)
		(layer "F.Cu")
		(net 1)
	)
	(segment
		(start 66.5 119.485)
		(end 67.5 119.485)
		(width 0.125)
		(layer "F.Cu")
		(net 1)
	)
	(segment
		(start 96.35 122)
		(end 96.35 122.85)
		(width 0.2)
		(layer "F.Cu")
		(net 1)
	)
	(segment
		(start 54.525 108.075)
		(end 53.55 108.075)
		(width 0.3)
		(layer "F.Cu")
		(net 1)
	)
	(segment
		(start 126.097323 70.652677)
		(end 126.1 70.65)
		(width 0.125)
		(layer "F.Cu")
		(net 1)
	)
	(segment
		(start 120.85 125.15)
		(end 121.3 125.6)
		(width 0.155)
		(layer "F.Cu")
		(net 1)
	)
	(segment
		(start 118.55 70.7)
		(end 118.597323 70.747323)
		(width 0.125)
		(layer "F.Cu")
		(net 1)
	)
	(segment
		(start 85 73.6)
		(end 84.597323 73.197323)
		(width 0.125)
		(layer "F.Cu")
		(net 1)
	)
	(segment
		(start 124.597323 73.257323)
		(end 124.6 73.26)
		(width 0.15)
		(layer "F.Cu")
		(net 1)
	)
	(segment
		(start 97.45 122.85)
		(end 96.35 122.85)
		(width 0.2)
		(layer "F.Cu")
		(net 1)
	)
	(segment
		(start 104.35 101.6)
		(end 105.05 101.6)
		(width 0.15)
		(layer "F.Cu")
		(net 1)
	)
	(segment
		(start 123.097323 70.687323)
		(end 123.06 70.65)
		(width 0.125)
		(layer "F.Cu")
		(net 1)
	)
	(segment
		(start 80.08 114.37)
		(end 80.08 114.89)
		(width 0.2)
		(layer "F.Cu")
		(net 1)
	)
	(segment
		(start 84.85 81.36)
		(end 84.847323 81.357323)
		(width 0.125)
		(layer "F.Cu")
		(net 1)
	)
	(segment
		(start 141.5 87.95)
		(end 140.45 87.95)
		(width 0.125)
		(layer "F.Cu")
		(net 1)
	)
	(segment
		(start 115.597323 70.787323)
		(end 115.597323 72.005136)
		(width 0.125)
		(layer "F.Cu")
		(net 1)
	)
	(segment
		(start 125.25 104.4)
		(end 124.5 104.4)
		(width 0.3)
		(layer "F.Cu")
		(net 1)
	)
	(segment
		(start 102.05 119.25)
		(end 102.354 119.554)
		(width 0.3)
		(layer "F.Cu")
		(net 1)
	)
	(segment
		(start 122.890585 78.890585)
		(end 122.847323 78.933847)
		(width 0.125)
		(layer "F.Cu")
		(net 1)
	)
	(segment
		(start 61.1 107.7)
		(end 61.1 106.65)
		(width 0.3)
		(layer "F.Cu")
		(net 1)
	)
	(segment
		(start 147.45 89.15)
		(end 147.25 89.15)
		(width 0.125)
		(layer "F.Cu")
		(net 1)
	)
	(segment
		(start 69.55 109.435)
		(end 69.55 108.835)
		(width 0.2)
		(layer "F.Cu")
		(net 1)
	)
	(segment
		(start 112.225536 81.461316)
		(end 112.347323 81.339529)
		(width 0.125)
		(layer "F.Cu")
		(net 1)
	)
	(segment
		(start 119.847323 78.68212)
		(end 119.868506 78.660937)
		(width 0.125)
		(layer "F.Cu")
		(net 1)
	)
	(segment
		(start 87.05 122.5)
		(end 87.55 123)
		(width 0.2)
		(layer "F.Cu")
		(net 1)
	)
	(segment
		(start 147.38 85.95)
		(end 147.055 86.275)
		(width 0.125)
		(layer "F.Cu")
		(net 1)
	)
	(segment
		(start 104.6 126.2)
		(end 104.4 126.2)
		(width 0.155)
		(layer "F.Cu")
		(net 1)
	)
	(segment
		(start 98.097323 70.827677)
		(end 98.1 70.825)
		(width 0.15)
		(layer "F.Cu")
		(net 1)
	)
	(segment
		(start 102.354 119.554)
		(end 102.354 120.551)
		(width 0.3)
		(layer "F.Cu")
		(net 1)
	)
	(segment
		(start 71.915 102.65)
		(end 71.7 102.865)
		(width 0.3)
		(layer "F.Cu")
		(net 1)
	)
	(segment
		(start 103.45 108)
		(end 103.25 108.2)
		(width 0.15)
		(layer "F.Cu")
		(net 1)
	)
	(segment
		(start 105.08 70.77)
		(end 105.097323 70.787323)
		(width 0.15)
		(layer "F.Cu")
		(net 1)
	)
	(segment
		(start 94.2 70.395)
		(end 94.097323 70.497677)
		(width 0.15)
		(layer "F.Cu")
		(net 1)
	)
	(segment
		(start 90.347323 79.202677)
		(end 90.347323 80.205136)
		(width 0.2)
		(layer "F.Cu")
		(net 1)
	)
	(segment
		(start 61.3 110.2)
		(end 62.7 110.2)
		(width 0.3)
		(layer "F.Cu")
		(net 1)
	)
	(segment
		(start 124.597323 72.005136)
		(end 124.597323 73.257323)
		(width 0.15)
		(layer "F.Cu")
		(net 1)
	)
	(segment
		(start 84.54 115.8)
		(end 84.915 115.8)
		(width 0.15)
		(layer "F.Cu")
		(net 1)
	)
	(segment
		(start 141.5 107.15)
		(end 140.4 107.15)
		(width 0.3)
		(layer "F.Cu")
		(net 1)
	)
	(segment
		(start 136.915 113.1)
		(end 136.915 113.365)
		(width 0.5)
		(layer "F.Cu")
		(net 1)
	)
	(segment
		(start 65.43 93.35)
		(end 65.43 93.83)
		(width 0.125)
		(layer "F.Cu")
		(net 1)
	)
	(segment
		(start 57.9 106.515)
		(end 57.315 107.1)
		(width 0.2)
		(layer "F.Cu")
		(net 1)
	)
	(segment
		(start 80.1 70.75)
		(end 80.1 71.2)
		(width 0.125)
		(layer "F.Cu")
		(net 1)
	)
	(segment
		(start 125.85 81.35)
		(end 125.85 80.207813)
		(width 0.125)
		(layer "F.Cu")
		(net 1)
	)
	(segment
		(start 114.7 102.15)
		(end 113.765584 103.084416)
		(width 0.15)
		(layer "F.Cu")
		(net 1)
	)
	(segment
		(start 108.5875 110.8875)
		(end 108.365 111.11)
		(width 0.15)
		(layer "F.Cu")
		(net 1)
	)
	(segment
		(start 142.45 91)
		(end 142.45 90.63)
		(width 0.15)
		(layer "F.Cu")
		(net 1)
	)
	(segment
		(start 125.4 105.5)
		(end 125.65 105.25)
		(width 0.2)
		(layer "F.Cu")
		(net 1)
	)
	(segment
		(start 70.25 127.85)
		(end 70.47992 127.62008)
		(width 0.2)
		(layer "F.Cu")
		(net 1)
	)
	(segment
		(start 142.7 111.1)
		(end 142.65 111.15)
		(width 0.3)
		(layer "F.Cu")
		(net 1)
	)
	(segment
		(start 80.323 114.127)
		(end 81.272 114.127)
		(width 0.2)
		(layer "F.Cu")
		(net 1)
	)
	(segment
		(start 140.55 93.25)
		(end 140.72 93.08)
		(width 0.125)
		(layer "F.Cu")
		(net 1)
	)
	(segment
		(start 83.35 78.95)
		(end 83.35 80.202459)
		(width 0.125)
		(layer "F.Cu")
		(net 1)
	)
	(segment
		(start 112.8 86.675)
		(end 113.225 86.675)
		(width 0.15)
		(layer "F.Cu")
		(net 1)
	)
	(segment
		(start 110.65 116.663749)
		(end 110.55 116.563749)
		(width 0.2)
		(layer "F.Cu")
		(net 1)
	)
	(segment
		(start 86.34 78.94)
		(end 86.34 80.197813)
		(width 0.125)
		(layer "F.Cu")
		(net 1)
	)
	(segment
		(start 146.8 86.35)
		(end 146.875 86.275)
		(width 0.125)
		(layer "F.Cu")
		(net 1)
	)
	(segment
		(start 55.605356 103.735356)
		(end 55.54 103.800712)
		(width 0.125)
		(layer "F.Cu")
		(net 1)
	)
	(segment
		(start 146.876533 84.113467)
		(end 146.876533 84.275506)
		(width 0.125)
		(layer "F.Cu")
		(net 1)
	)
	(segment
		(start 128.05 125.6)
		(end 130.45 125.6)
		(width 0.155)
		(layer "F.Cu")
		(net 1)
	)
	(segment
		(start 77.49992 117.35008)
		(end 77.75 117.1)
		(width 0.3)
		(layer "F.Cu")
		(net 1)
	)
	(segment
		(start 125.42 98.4)
		(end 125.81 98.01)
		(width 0.3)
		(layer "F.Cu")
		(net 1)
	)
	(segment
		(start 91.847323 79.197323)
		(end 91.65 79)
		(width 0.2)
		(layer "F.Cu")
		(net 1)
	)
	(segment
		(start 63 110.5)
		(end 63 111.35)
		(width 0.3)
		(layer "F.Cu")
		(net 1)
	)
	(segment
		(start 146 86.35)
		(end 146.8 86.35)
		(width 0.125)
		(layer "F.Cu")
		(net 1)
	)
	(segment
		(start 78 114.625)
		(end 78 115.115)
		(width 0.15)
		(layer "F.Cu")
		(net 1)
	)
	(segment
		(start 123.75 105.5)
		(end 125.4 105.5)
		(width 0.2)
		(layer "F.Cu")
		(net 1)
	)
	(segment
		(start 137.8 87.75)
		(end 137.95 87.9)
		(width 0.15)
		(layer "F.Cu")
		(net 1)
	)
	(segment
		(start 106.347323 79.285228)
		(end 106.347323 81.702677)
		(width 0.125)
		(layer "F.Cu")
		(net 1)
	)
	(segment
		(start 118.347323 81.396282)
		(end 118.347323 80.205136)
		(width 0.3)
		(layer "F.Cu")
		(net 1)
	)
	(segment
		(start 89.3 115.565)
		(end 89.3 115.1)
		(width 0.2)
		(layer "F.Cu")
		(net 1)
	)
	(segment
		(start 101.75 122.85)
		(end 102.25 122.85)
		(width 0.2)
		(layer "F.Cu")
		(net 1)
	)
	(segment
		(start 108.889938 106.545)
		(end 108.889938 104.345)
		(width 0.13)
		(layer "F.Cu")
		(net 1)
	)
	(segment
		(start 116.85 81.35)
		(end 116.85 80.207813)
		(width 0.125)
		(layer "F.Cu")
		(net 1)
	)
	(segment
		(start 146.825 91.15)
		(end 146.85 91.175)
		(width 0.125)
		(layer "F.Cu")
		(net 1)
	)
	(segment
		(start 108.676468 110.8875)
		(end 108.5875 110.8875)
		(width 0.15)
		(layer "F.Cu")
		(net 1)
	)
	(segment
		(start 142.65 111.15)
		(end 141.5 111.15)
		(width 0.3)
		(layer "F.Cu")
		(net 1)
	)
	(segment
		(start 66.303 126.755)
		(end 66.25 126.702)
		(width 0.15)
		(layer "F.Cu")
		(net 1)
	)
	(segment
		(start 107.6 127.9)
		(end 106.84 127.9)
		(width 0.2)
		(layer "F.Cu")
		(net 1)
	)
	(segment
		(start 104.67 78.77)
		(end 104.847323 78.947323)
		(width 0.125)
		(layer "F.Cu")
		(net 1)
	)
	(segment
		(start 80.372 106.263)
		(end 80.385 106.25)
		(width 0.155)
		(layer "F.Cu")
		(net 1)
	)
	(segment
		(start 109.347323 80.205136)
		(end 109.347323 79.024382)
		(width 0.125)
		(layer "F.Cu")
		(net 1)
	)
	(segment
		(start 131.315 108.65)
		(end 132.085 108.65)
		(width 0.15)
		(layer "F.Cu")
		(net 1)
	)
	(segment
		(start 130.3 123.75)
		(end 131.25 123.75)
		(width 0.15)
		(layer "F.Cu")
		(net 1)
	)
	(segment
		(start 77.49992 118.115)
		(end 77.49992 117.35008)
		(width 0.3)
		(layer "F.Cu")
		(net 1)
	)
	(segment
		(start 80.065 106.263)
		(end 80.372 106.263)
		(width 0.155)
		(layer "F.Cu")
		(net 1)
	)
	(segment
		(start 123.097323 73.247323)
		(end 123.097323 70.687323)
		(width 0.125)
		(layer "F.Cu")
		(net 1)
	)
	(segment
		(start 147.055 86.275)
		(end 146.875 86.275)
		(width 0.125)
		(layer "F.Cu")
		(net 1)
	)
	(segment
		(start 147.095 86.275)
		(end 147.37 86.55)
		(width 0.125)
		(layer "F.Cu")
		(net 1)
	)
	(segment
		(start 119.84 80.212459)
		(end 119.847323 80.205136)
		(width 0.3)
		(layer "F.Cu")
		(net 1)
	)
	(segment
		(start 115.597323 73.397323)
		(end 115.61 73.41)
		(width 0.15)
		(layer "F.Cu")
		(net 1)
	)
	(segment
		(start 110.65 118.2)
		(end 110.65 116.663749)
		(width 0.2)
		(layer "F.Cu")
		(net 1)
	)
	(segment
		(start 104.847323 78.947323)
		(end 104.847323 80.205136)
		(width 0.125)
		(layer "F.Cu")
		(net 1)
	)
	(segment
		(start 135.815 119.7)
		(end 134.8 119.7)
		(width 0.2)
		(layer "F.Cu")
		(net 1)
	)
	(segment
		(start 136.9245 108.0255)
		(end 136.63 108.32)
		(width 0.3)
		(layer "F.Cu")
		(net 1)
	)
	(segment
		(start 125.44 87.4)
		(end 124.5 87.4)
		(width 0.3)
		(layer "F.Cu")
		(net 1)
	)
	(segment
		(start 118.347323 78.922677)
		(end 118.35 78.92)
		(width 0.125)
		(layer "F.Cu")
		(net 1)
	)
	(segment
		(start 122.7 125.6)
		(end 122.9 125.6)
		(width 0.155)
		(layer "F.Cu")
		(net 1)
	)
	(segment
		(start 145.35 93.55)
		(end 145.05 93.85)
		(width 0.125)
		(layer "F.Cu")
		(net 1)
	)
	(segment
		(start 124.45 125.6)
		(end 124.95 125.1)
		(width 0.155)
		(layer "F.Cu")
		(net 1)
	)
	(segment
		(start 135.05 88.2)
		(end 134.15 88.2)
		(width 0.15)
		(layer "F.Cu")
		(net 1)
	)
	(segment
		(start 62.6 126.2)
		(end 62.15 126.65)
		(width 0.155)
		(layer "F.Cu")
		(net 1)
	)
	(segment
		(start 92.226064 70.3)
		(end 92.226064 70.626064)
		(width 0.15)
		(layer "F.Cu")
		(net 1)
	)
	(segment
		(start 55.54 103.800712)
		(end 55.54 104.39)
		(width 0.125)
		(layer "F.Cu")
		(net 1)
	)
	(segment
		(start 132.49 108.65)
		(end 132.085 108.65)
		(width 0.15)
		(layer "F.Cu")
		(net 1)
	)
	(segment
		(start 106.347323 81.702677)
		(end 106.23 81.82)
		(width 0.125)
		(layer "F.Cu")
		(net 1)
	)
	(segment
		(start 97.55 122)
		(end 97.55 122.75)
		(width 0.2)
		(layer "F.Cu")
		(net 1)
	)
	(segment
		(start 77.49992 118.115)
		(end 77.49992 119.315)
		(width 0.3)
		(layer "F.Cu")
		(net 1)
	)
	(segment
		(start 96.675 120.825)
		(end 96.675 120.285)
		(width 0.2)
		(layer "F.Cu")
		(net 1)
	)
	(segment
		(start 141.5 97.55)
		(end 142.13 97.55)
		(width 0.15)
		(layer "F.Cu")
		(net 1)
	)
	(segment
		(start 66.25 126.65)
		(end 66.25 126.7)
		(width 0.155)
		(layer "F.Cu")
		(net 1)
	)
	(segment
		(start 110.847323 81.457323)
		(end 110.847323 80.205136)
		(width 0.125)
		(layer "F.Cu")
		(net 1)
	)
	(segment
		(start 112.2 78.99)
		(end 112.35 79.14)
		(width 0.125)
		(layer "F.Cu")
		(net 1)
	)
	(segment
		(start 137.15 91.083)
		(end 137.017 90.95)
		(width 0.3)
		(layer "F.Cu")
		(net 1)
	)
	(segment
		(start 145.15 111.15)
		(end 146 111.15)
		(width 0.3)
		(layer "F.Cu")
		(net 1)
	)
	(segment
		(start 113.86 81.46)
		(end 113.847323 81.447323)
		(width 0.125)
		(layer "F.Cu")
		(net 1)
	)
	(segment
		(start 122.7 125.6)
		(end 122.9 125.4)
		(width 0.155)
		(layer "F.Cu")
		(net 1)
	)
	(segment
		(start 122.9 125.6)
		(end 123.1 125.6)
		(width 0.155)
		(layer "F.Cu")
		(net 1)
	)
	(segment
		(start 67.9 114.2)
		(end 67.9 113.35)
		(width 0.3)
		(layer "F.Cu")
		(net 1)
	)
	(segment
		(start 121.41 78.75)
		(end 121.41 80.142459)
		(width 0.125)
		(layer "F.Cu")
		(net 1)
	)
	(via
		(at 123.24 85)
		(size 0.45)
		(drill 0.1)
		(layers "F.Cu" "B.Cu")
		(net 1)
	)
	(via
		(at 93.12 76.59)
		(size 0.45)
		(drill 0.1)
		(layers "F.Cu" "B.Cu")
		(free yes)
		(net 1)
	)
	(via
		(at 122.9 125.05)
		(size 0.45)
		(drill 0.1)
		(layers "F.Cu" "B.Cu")
		(net 1)
	)
	(via
		(at 81.509753 74.539999)
		(size 0.45)
		(drill 0.1)
		(layers "F.Cu" "B.Cu")
		(net 1)
	)
	(via
		(at 119.95 127.75)
		(size 0.45)
		(drill 0.1)
		(layers "F.Cu" "B.Cu")
		(net 1)
	)
	(via
		(at 72.3 73.3)
		(size 0.45)
		(drill 0.1)
		(layers "F.Cu" "B.Cu")
		(net 1)
	)
	(via
		(at 86.325 110.775)
		(size 0.45)
		(drill 0.1)
		(layers "F.Cu" "B.Cu")
		(net 1)
	)
	(via
		(at 114.09 70.81)
		(size 0.45)
		(drill 0.1)
		(layers "F.Cu" "B.Cu")
		(net 1)
	)
	(via
		(at 140.65 112.85)
		(size 0.45)
		(drill 0.1)
		(layers "F.Cu" "B.Cu")
		(net 1)
	)
	(via
		(at 52.94 83.03)
		(size 0.45)
		(drill 0.1)
		(layers "F.Cu" "B.Cu")
		(net 1)
	)
	(via
		(at 123.1 73.25)
		(size 0.45)
		(drill 0.1)
		(layers "F.Cu" "B.Cu")
		(net 1)
	)
	(via
		(at 77.65 74.55)
		(size 0.45)
		(drill 0.1)
		(layers "F.Cu" "B.Cu")
		(net 1)
	)
	(via
		(at 75.95 90.35)
		(size 0.45)
		(drill 0.1)
		(layers "F.Cu" "B.Cu")
		(net 1)
	)
	(via
		(at 104.35 101.6)
		(size 0.45)
		(drill 0.1)
		(layers "F.Cu" "B.Cu")
		(net 1)
	)
	(via
		(at 122.98 103.46)
		(size 0.45)
		(drill 0.1)
		(layers "F.Cu" "B.Cu")
		(net 1)
	)
	(via
		(at 83.9 75)
		(size 0.45)
		(drill 0.1)
		(layers "F.Cu" "B.Cu")
		(net 1)
	)
	(via
		(at 65.43 93.83)
		(size 0.45)
		(drill 0.1)
		(layers "F.Cu" "B.Cu")
		(free yes)
		(net 1)
	)
	(via
		(at 138.65 85.6)
		(size 0.45)
		(drill 0.1)
		(layers "F.Cu" "B.Cu")
		(net 1)
	)
	(via
		(at 142.35 87.95)
		(size 0.45)
		(drill 0.1)
		(layers "F.Cu" "B.Cu")
		(free yes)
		(net 1)
	)
	(via
		(at 75.011244 99.794608)
		(size 0.45)
		(drill 0.1)
		(layers "F.Cu" "B.Cu")
		(free yes)
		(net 1)
	)
	(via
		(at 37.9 118.4)
		(size 0.45)
		(drill 0.1)
		(layers "F.Cu" "B.Cu")
		(net 1)
	)
	(via
		(at 84.5 97.49)
		(size 0.45)
		(drill 0.1)
		(layers "F.Cu" "B.Cu")
		(free yes)
		(net 1)
	)
	(via
		(at 114.4 106.35)
		(size 0.45)
		(drill 0.1)
		(layers "F.Cu" "B.Cu")
		(net 1)
	)
	(via
		(at 86.97 101.63)
		(size 0.45)
		(drill 0.1)
		(layers "F.Cu" "B.Cu")
		(net 1)
	)
	(via
		(at 123.25 89.49)
		(size 0.45)
		(drill 0.1)
		(layers "F.Cu" "B.Cu")
		(net 1)
	)
	(via
		(at 51.45 116.65)
		(size 0.45)
		(drill 0.1)
		(layers "F.Cu" "B.Cu")
		(net 1)
	)
	(via
		(at 48.3 83)
		(size 0.45)
		(drill 0.1)
		(layers "F.Cu" "B.Cu")
		(net 1)
	)
	(via
		(at 83.5 74.25)
		(size 0.45)
		(drill 0.1)
		(layers "F.Cu" "B.Cu")
		(net 1)
	)
	(via
		(at 63.46 86.06)
		(size 0.45)
		(drill 0.1)
		(layers "F.Cu" "B.Cu")
		(net 1)
	)
	(via
		(at 80.414208 81.5)
		(size 0.45)
		(drill 0.1)
		(layers "F.Cu" "B.Cu")
		(net 1)
	)
	(via
		(at 71.04 90.25)
		(size 0.45)
		(drill 0.1)
		(layers "F.Cu" "B.Cu")
		(free yes)
		(net 1)
	)
	(via
		(at 98.5 78.75)
		(size 0.45)
		(drill 0.1)
		(layers "F.Cu" "B.Cu")
		(net 1)
	)
	(via
		(at 61.68 95.97)
		(size 0.45)
		(drill 0.1)
		(layers "F.Cu" "B.Cu")
		(net 1)
	)
	(via
		(at 108.865438 103.789938)
		(size 0.45)
		(drill 0.1)
		(layers "F.Cu" "B.Cu")
		(net 1)
	)
	(via
		(at 61.9 88.74)
		(size 0.45)
		(drill 0.1)
		(layers "F.Cu" "B.Cu")
		(net 1)
	)
	(via
		(at 96.75 77.05)
		(size 0.45)
		(drill 0.1)
		(layers "F.Cu" "B.Cu")
		(net 1)
	)
	(via
		(at 142.7 111.1)
		(size 0.45)
		(drill 0.1)
		(layers "F.Cu" "B.Cu")
		(net 1)
	)
	(via
		(at 149.0245 113.3)
		(size 0.45)
		(drill 0.1)
		(layers "F.Cu" "B.Cu")
		(net 1)
	)
	(via
		(at 145.225 88.75)
		(size 0.45)
		(drill 0.1)
		(layers "F.Cu" "B.Cu")
		(free yes)
		(net 1)
	)
	(via
		(at 31.3 71.6)
		(size 0.45)
		(drill 0.1)
		(layers "F.Cu" "B.Cu")
		(net 1)
	)
	(via
		(at 88.01 81.35)
		(size 0.45)
		(drill 0.1)
		(layers "F.Cu" "B.Cu")
		(net 1)
	)
	(via
		(at 56.399282 96.033125)
		(size 0.45)
		(drill 0.1)
		(layers "F.Cu" "B.Cu")
		(net 1)
	)
	(via
		(at 107.075 101.525)
		(size 0.45)
		(drill 0.1)
		(layers "F.Cu" "B.Cu")
		(net 1)
	)
	(via
		(at 98.1 70.825)
		(size 0.45)
		(drill 0.1)
		(layers "F.Cu" "B.Cu")
		(net 1)
	)
	(via
		(at 123.01 100.86)
		(size 0.45)
		(drill 0.1)
		(layers "F.Cu" "B.Cu")
		(net 1)
	)
	(via
		(at 58.38 83.58)
		(size 0.45)
		(drill 0.1)
		(layers "F.Cu" "B.Cu")
		(free yes)
		(net 1)
	)
	(via
		(at 74.99 73.298502)
		(size 0.45)
		(drill 0.1)
		(layers "F.Cu" "B.Cu")
		(net 1)
	)
	(via
		(at 61.85 90.25)
		(size 0.45)
		(drill 0.1)
		(layers "F.Cu" "B.Cu")
		(net 1)
	)
	(via
		(at 51.7 119.4)
		(size 0.45)
		(drill 0.1)
		(layers "F.Cu" "B.Cu")
		(free yes)
		(net 1)
	)
	(via
		(at 84.3225 116.59)
		(size 0.45)
		(drill 0.1)
		(layers "F.Cu" "B.Cu")
		(net 1)
	)
	(via
		(at 63.05 73.85)
		(size 0.45)
		(drill 0.1)
		(layers "F.Cu" "B.Cu")
		(free yes)
		(net 1)
	)
	(via
		(at 146.9 83.11)
		(size 0.45)
		(drill 0.1)
		(layers "F.Cu" "B.Cu")
		(free yes)
		(net 1)
	)
	(via
		(at 115.54 70.8)
		(size 0.45)
		(drill 0.1)
		(layers "F.Cu" "B.Cu")
		(net 1)
	)
	(via
		(at 83.91 126.7275)
		(size 0.45)
		(drill 0.1)
		(layers "F.Cu" "B.Cu")
		(free yes)
		(net 1)
	)
	(via
		(at 74.2 81.7)
		(size 0.45)
		(drill 0.1)
		(layers "F.Cu" "B.Cu")
		(net 1)
	)
	(via
		(at 76.49 121.49)
		(size 0.45)
		(drill 0.1)
		(layers "F.Cu" "B.Cu")
		(free yes)
		(net 1)
	)
	(via
		(at 56.27 113.388)
		(size 0.45)
		(drill 0.1)
		(layers "F.Cu" "B.Cu")
		(net 1)
	)
	(via
		(at 70.04 90.25)
		(size 0.45)
		(drill 0.1)
		(layers "F.Cu" "B.Cu")
		(free yes)
		(net 1)
	)
	(via
		(at 125.81 98.01)
		(size 0.45)
		(drill 0.1)
		(layers "F.Cu" "B.Cu")
		(net 1)
	)
	(via
		(at 101.2 94.7)
		(size 0.45)
		(drill 0.1)
		(layers "F.Cu" "B.Cu")
		(free yes)
		(net 1)
	)
	(via
		(at 123.2 90.95)
		(size 0.45)
		(drill 0.1)
		(layers "F.Cu" "B.Cu")
		(net 1)
	)
	(via
		(at 81.61 70.72)
		(size 0.45)
		(drill 0.1)
		(layers "F.Cu" "B.Cu")
		(net 1)
	)
	(via
		(at 125.5 85.07)
		(size 0.45)
		(drill 0.1)
		(layers "F.Cu" "B.Cu")
		(net 1)
	)
	(via
		(at 125.95 78.97)
		(size 0.45)
		(drill 0.1)
		(layers "F.Cu" "B.Cu")
		(net 1)
	)
	(via
		(at 95.352278 99.757188)
		(size 0.45)
		(drill 0.1)
		(layers "F.Cu" "B.Cu")
		(net 1)
	)
	(via
		(at 144.987667 103.487333)
		(size 0.45)
		(drill 0.1)
		(layers "F.Cu" "B.Cu")
		(net 1)
	)
	(via
		(at 128.35 94.15)
		(size 0.45)
		(drill 0.1)
		(layers "F.Cu" "B.Cu")
		(net 1)
	)
	(via
		(at 72.425 77.7)
		(size 0.45)
		(drill 0.1)
		(layers "F.Cu" "B.Cu")
		(net 1)
	)
	(via
		(at 148.6 89.41)
		(size 0.45)
		(drill 0.1)
		(layers "F.Cu" "B.Cu")
		(net 1)
	)
	(via
		(at 122.75 81.55)
		(size 0.45)
		(drill 0.1)
		(layers "F.Cu" "B.Cu")
		(net 1)
	)
	(via
		(at 62.33 96.61)
		(size 0.45)
		(drill 0.1)
		(layers "F.Cu" "B.Cu")
		(net 1)
	)
	(via
		(at 148.625 85.75)
		(size 0.45)
		(drill 0.1)
		(layers "F.Cu" "B.Cu")
		(net 1)
	)
	(via
		(at 145 107.2745)
		(size 0.45)
		(drill 0.1)
		(layers "F.Cu" "B.Cu")
		(net 1)
	)
	(via
		(at 127.96 92.52)
		(size 0.45)
		(drill 0.1)
		(layers "F.Cu" "B.Cu")
		(net 1)
	)
	(via
		(at 118.478081 81.52704)
		(size 0.45)
		(drill 0.1)
		(layers "F.Cu" "B.Cu")
		(net 1)
	)
	(via
		(at 58.075167 71.774833)
		(size 0.45)
		(drill 0.1)
		(layers "F.Cu" "B.Cu")
		(net 1)
	)
	(via
		(at 89.3 118.9)
		(size 0.45)
		(drill 0.1)
		(layers "F.Cu" "B.Cu")
		(net 1)
	)
	(via
		(at 91.945769 117.822006)
		(size 0.45)
		(drill 0.1)
		(layers "F.Cu" "B.Cu")
		(free yes)
		(net 1)
	)
	(via
		(at 73.5 90.25)
		(size 0.45)
		(drill 0.1)
		(layers "F.Cu" "B.Cu")
		(free yes)
		(net 1)
	)
	(via
		(at 113.55 114.95)
		(size 0.45)
		(drill 0.1)
		(layers "F.Cu" "B.Cu")
		(net 1)
	)
	(via
		(at 137.325 104.05)
		(size 0.45)
		(drill 0.1)
		(layers "F.Cu" "B.Cu")
		(net 1)
	)
	(via
		(at 84.6 70.7)
		(size 0.45)
		(drill 0.1)
		(layers "F.Cu" "B.Cu")
		(net 1)
	)
	(via
		(at 112.225536 81.461316)
		(size 0.45)
		(drill 0.1)
		(layers "F.Cu" "B.Cu")
		(net 1)
	)
	(via
		(at 62.35 89.75)
		(size 0.45)
		(drill 0.1)
		(layers "F.Cu" "B.Cu")
		(net 1)
	)
	(via
		(at 87.05 122.5)
		(size 0.45)
		(drill 0.1)
		(layers "F.Cu" "B.Cu")
		(net 1)
	)
	(via
		(at 131.94 84.94)
		(size 0.45)
		(drill 0.1)
		(layers "F.Cu" "B.Cu")
		(free yes)
		(net 1)
	)
	(via
		(at 103.25 108.2)
		(size 0.45)
		(drill 0.1)
		(layers "F.Cu" "B.Cu")
		(net 1)
	)
	(via
		(at 107.71 81.45)
		(size 0.45)
		(drill 0.1)
		(layers "F.Cu" "B.Cu")
		(net 1)
	)
	(via
		(at 63.34 83.7)
		(size 0.45)
		(drill 0.1)
		(layers "F.Cu" "B.Cu")
		(free yes)
		(net 1)
	)
	(via
		(at 140.525 83.15)
		(size 0.45)
		(drill 0.1)
		(layers "F.Cu" "B.Cu")
		(free yes)
		(net 1)
	)
	(via
		(at 124.59 70.89)
		(size 0.45)
		(drill 0.1)
		(layers "F.Cu" "B.Cu")
		(net 1)
	)
	(via
		(at 73 90.25)
		(size 0.45)
		(drill 0.1)
		(layers "F.Cu" "B.Cu")
		(free yes)
		(net 1)
	)
	(via
		(at 121.67 92.44)
		(size 0.45)
		(drill 0.1)
		(layers "F.Cu" "B.Cu")
		(net 1)
	)
	(via
		(at 73.5 89.75)
		(size 0.45)
		(drill 0.1)
		(layers "F.Cu" "B.Cu")
		(net 1)
	)
	(via
		(at 101.7 122.9)
		(size 0.45)
		(drill 0.1)
		(layers "F.Cu" "B.Cu")
		(net 1)
	)
	(via
		(at 57.16 84.97)
		(size 0.45)
		(drill 0.1)
		(layers "F.Cu" "B.Cu")
		(free yes)
		(net 1)
	)
	(via
		(at 78.65 102.95)
		(size 0.45)
		(drill 0.1)
		(layers "F.Cu" "B.Cu")
		(free yes)
		(net 1)
	)
	(via
		(at 100.853485 78.702711)
		(size 0.45)
		(drill 0.1)
		(layers "F.Cu" "B.Cu")
		(net 1)
	)
	(via
		(at 112.1 83)
		(size 0.45)
		(drill 0.1)
		(layers "F.Cu" "B.Cu")
		(net 1)
	)
	(via
		(at 76.45 90.35)
		(size 0.45)
		(drill 0.1)
		(layers "F.Cu" "B.Cu")
		(free yes)
		(net 1)
	)
	(via
		(at 58.7 95.81)
		(size 0.45)
		(drill 0.1)
		(layers "F.Cu" "B.Cu")
		(net 1)
	)
	(via
		(at 62.35 88.25)
		(size 0.45)
		(drill 0.1)
		(layers "F.Cu" "B.Cu")
		(net 1)
	)
	(via
		(at 49.9 118.2)
		(size 0.45)
		(drill 0.1)
		(layers "F.Cu" "B.Cu")
		(free yes)
		(net 1)
	)
	(via
		(at 126.08 73.34)
		(size 0.45)
		(drill 0.1)
		(layers "F.Cu" "B.Cu")
		(net 1)
	)
	(via
		(at 123.28 88)
		(size 0.45)
		(drill 0.1)
		(layers "F.Cu" "B.Cu")
		(net 1)
	)
	(via
		(at 91.72 75.31)
		(size 0.45)
		(drill 0.1)
		(layers "F.Cu" "B.Cu")
		(net 1)
	)
	(via
		(at 140.5 90.45)
		(size 0.45)
		(drill 0.1)
		(layers "F.Cu" "B.Cu")
		(free yes)
		(net 1)
	)
	(via
		(at 94.75 86.65)
		(size 0.45)
		(drill 0.1)
		(layers "F.Cu" "B.Cu")
		(net 1)
	)
	(via
		(at 62.27 81.8)
		(size 0.45)
		(drill 0.1)
		(layers "F.Cu" "B.Cu")
		(free yes)
		(net 1)
	)
	(via
		(at 82.625 85.5)
		(size 0.45)
		(drill 0.1)
		(layers "F.Cu" "B.Cu")
		(free yes)
		(net 1)
	)
	(via
		(at 85 74.25)
		(size 0.45)
		(drill 0.1)
		(layers "F.Cu" "B.Cu")
		(net 1)
	)
	(via
		(at 67.85 113.3)
		(size 0.45)
		(drill 0.1)
		(layers "F.Cu" "B.Cu")
		(net 1)
	)
	(via
		(at 61.86 89.77)
		(size 0.45)
		(drill 0.1)
		(layers "F.Cu" "B.Cu")
		(net 1)
	)
	(via
		(at 142.41 97.01)
		(size 0.45)
		(drill 0.1)
		(layers "F.Cu" "B.Cu")
		(net 1)
	)
	(via
		(at 88.6 76.28)
		(size 0.45)
		(drill 0.1)
		(layers "F.Cu" "B.Cu")
		(free yes)
		(net 1)
	)
	(via
		(at 80.805 125.325)
		(size 0.45)
		(drill 0.1)
		(layers "F.Cu" "B.Cu")
		(net 1)
	)
	(via
		(at 73.49 121.66)
		(size 0.45)
		(drill 0.1)
		(layers "F.Cu" "B.Cu")
		(free yes)
		(net 1)
	)
	(via
		(at 52.9 76.2)
		(size 0.45)
		(drill 0.1)
		(layers "F.Cu" "B.Cu")
		(net 1)
	)
	(via
		(at 80.1 70.75)
		(size 0.45)
		(drill 0.1)
		(layers "F.Cu" "B.Cu")
		(net 1)
	)
	(via
		(at 148.51 90.99)
		(size 0.45)
		(drill 0.1)
		(layers "F.Cu" "B.Cu")
		(net 1)
	)
	(via
		(at 139.36 96.87)
		(size 0.45)
		(drill 0.1)
		(layers "F.Cu" "B.Cu")
		(free yes)
		(net 1)
	)
	(via
		(at 144.375 80.2)
		(size 0.45)
		(drill 0.1)
		(layers "F.Cu" "B.Cu")
		(net 1)
	)
	(via
		(at 56.19 96.45)
		(size 0.45)
		(drill 0.1)
		(layers "F.Cu" "B.Cu")
		(net 1)
	)
	(via
		(at 70.54 89.75)
		(size 0.45)
		(drill 0.1)
		(layers "F.Cu" "B.Cu")
		(net 1)
	)
	(via
		(at 125.74 100.66)
		(size 0.45)
		(drill 0.1)
		(layers "F.Cu" "B.Cu")
		(net 1)
	)
	(via
		(at 62.25 81.3125)
		(size 0.45)
		(drill 0.1)
		(layers "F.Cu" "B.Cu")
		(free yes)
		(net 1)
	)
	(via
		(at 109.483979 73.6229)
		(size 0.45)
		(drill 0.1)
		(layers "F.Cu" "B.Cu")
		(net 1)
	)
	(via
		(at 51.7 119.95)
		(size 0.45)
		(drill 0.1)
		(layers "F.Cu" "B.Cu")
		(free yes)
		(net 1)
	)
	(via
		(at 83.125 77.075)
		(size 0.45)
		(drill 0.1)
		(layers "F.Cu" "B.Cu")
		(free yes)
		(net 1)
	)
	(via
		(at 51.1 119.95)
		(size 0.45)
		(drill 0.1)
		(layers "F.Cu" "B.Cu")
		(free yes)
		(net 1)
	)
	(via
		(at 123.06 70.65)
		(size 0.45)
		(drill 0.1)
		(layers "F.Cu" "B.Cu")
		(net 1)
	)
	(via
		(at 62.38 89.26)
		(size 0.45)
		(drill 0.1)
		(layers "F.Cu" "B.Cu")
		(net 1)
	)
	(via
		(at 140.525 85.55)
		(size 0.45)
		(drill 0.1)
		(layers "F.Cu" "B.Cu")
		(free yes)
		(net 1)
	)
	(via
		(at 124.35 81.35)
		(size 0.45)
		(drill 0.1)
		(layers "F.Cu" "B.Cu")
		(net 1)
	)
	(via
		(at 115.696953 89.549538)
		(size 0.45)
		(drill 0.1)
		(layers "F.Cu" "B.Cu")
		(net 1)
	)
	(via
		(at 77.6 101.8)
		(size 0.45)
		(drill 0.1)
		(layers "F.Cu" "B.Cu")
		(free yes)
		(net 1)
	)
	(via
		(at 105.72 85.89)
		(size 0.45)
		(drill 0.1)
		(layers "F.Cu" "B.Cu")
		(net 1)
	)
	(via
		(at 107.6 85.32)
		(size 0.45)
		(drill 0.1)
		(layers "F.Cu" "B.Cu")
		(net 1)
	)
	(via
		(at 61.3 110.2)
		(size 0.45)
		(drill 0.1)
		(layers "F.Cu" "B.Cu")
		(net 1)
	)
	(via
		(at 76.45 89.85)
		(size 0.45)
		(drill 0.1)
		(layers "F.Cu" "B.Cu")
		(net 1)
	)
	(via
		(at 103.5 92.45)
		(size 0.45)
		(drill 0.1)
		(layers "F.Cu" "B.Cu")
		(free yes)
		(net 1)
	)
	(via
		(at 70.54 90.25)
		(size 0.45)
		(drill 0.1)
		(layers "F.Cu" "B.Cu")
		(net 1)
	)
	(via
		(at 54.9 90.1)
		(size 0.45)
		(drill 0.1)
		(layers "F.Cu" "B.Cu")
		(free yes)
		(net 1)
	)
	(via
		(at 123.15 93.95)
		(size 0.45)
		(drill 0.1)
		(layers "F.Cu" "B.Cu")
		(net 1)
	)
	(via
		(at 56.76 83.06)
		(size 0.45)
		(drill 0.1)
		(layers "F.Cu" "B.Cu")
		(free yes)
		(net 1)
	)
	(via
		(at 123.15 92.6)
		(size 0.45)
		(drill 0.1)
		(layers "F.Cu" "B.Cu")
		(net 1)
	)
	(via
		(at 140.55 97.55)
		(size 0.45)
		(drill 0.1)
		(layers "F.Cu" "B.Cu")
		(free yes)
		(net 1)
	)
	(via
		(at 89.2 115)
		(size 0.45)
		(drill 0.1)
		(layers "F.Cu" "B.Cu")
		(net 1)
	)
	(via
		(at 129.5 123.75)
		(size 0.45)
		(drill 0.1)
		(layers "F.Cu" "B.Cu")
		(net 1)
	)
	(via
		(at 57.45 82.8)
		(size 0.45)
		(drill 0.1)
		(layers "F.Cu" "B.Cu")
		(free yes)
		(net 1)
	)
	(via
		(at 140.55 93.25)
		(size 0.45)
		(drill 0.1)
		(layers "F.Cu" "B.Cu")
		(free yes)
		(net 1)
	)
	(via
		(at 84.85 81.36)
		(size 0.45)
		(drill 0.1)
		(layers "F.Cu" "B.Cu")
		(net 1)
	)
	(via
		(at 70.04 89.75)
		(size 0.45)
		(drill 0.1)
		(layers "F.Cu" "B.Cu")
		(net 1)
	)
	(via
		(at 125.57 86)
		(size 0.45)
		(drill 0.1)
		(layers "F.Cu" "B.Cu")
		(net 1)
	)
	(via
		(at 105.08 70.77)
		(size 0.45)
		(drill 0.1)
		(layers "F.Cu" "B.Cu")
		(net 1)
	)
	(via
		(at 113.2 90.990938)
		(size 0.45)
		(drill 0.1)
		(layers "F.Cu" "B.Cu")
		(net 1)
	)
	(via
		(at 119.84 81.46)
		(size 0.45)
		(drill 0.1)
		(layers "F.Cu" "B.Cu")
		(net 1)
	)
	(via
		(at 137.25 113.7)
		(size 0.45)
		(drill 0.1)
		(layers "F.Cu" "B.Cu")
		(net 1)
	)
	(via
		(at 80.323 114.127)
		(size 0.45)
		(drill 0.1)
		(layers "F.Cu" "B.Cu")
		(net 1)
	)
	(via
		(at 76.181746 76.48341)
		(size 0.45)
		(drill 0.1)
		(layers "F.Cu" "B.Cu")
		(free yes)
		(net 1)
	)
	(via
		(at 90.7 89.825)
		(size 0.45)
		(drill 0.1)
		(layers "F.Cu" "B.Cu")
		(net 1)
	)
	(via
		(at 116.85 81.24)
		(size 0.45)
		(drill 0.1)
		(layers "F.Cu" "B.Cu")
		(net 1)
	)
	(via
		(at 56.173952 76.827286)
		(size 0.45)
		(drill 0.1)
		(layers "F.Cu" "B.Cu")
		(net 1)
	)
	(via
		(at 87.6 70.8)
		(size 0.45)
		(drill 0.1)
		(layers "F.Cu" "B.Cu")
		(net 1)
	)
	(via
		(at 92.344303 78.011463)
		(size 0.45)
		(drill 0.1)
		(layers "F.Cu" "B.Cu")
		(net 1)
	)
	(via
		(at 101.15 84)
		(size 0.45)
		(drill 0.1)
		(layers "F.Cu" "B.Cu")
		(net 1)
	)
	(via
		(at 132.75 86.15)
		(size 0.45)
		(drill 0.1)
		(layers "F.Cu" "B.Cu")
		(free yes)
		(net 1)
	)
	(via
		(at 61.88 89.28)
		(size 0.45)
		(drill 0.1)
		(layers "F.Cu" "B.Cu")
		(net 1)
	)
	(via
		(at 77.45 89.85)
		(size 0.45)
		(drill 0.1)
		(layers "F.Cu" "B.Cu")
		(net 1)
	)
	(via
		(at 48.375 123.945)
		(size 0.45)
		(drill 0.1)
		(layers "F.Cu" "B.Cu")
		(net 1)
	)
	(via
		(at 61.1 107.7)
		(size 0.45)
		(drill 0.1)
		(layers "F.Cu" "B.Cu")
		(net 1)
	)
	(via
		(at 91.75 108.8)
		(size 0.45)
		(drill 0.1)
		(layers "F.Cu" "B.Cu")
		(net 1)
	)
	(via
		(at 148.65 86.775)
		(size 0.45)
		(drill 0.1)
		(layers "F.Cu" "B.Cu")
		(net 1)
	)
	(via
		(at 123.1 95.441)
		(size 0.45)
		(drill 0.1)
		(layers "F.Cu" "B.Cu")
		(net 1)
	)
	(via
		(at 88.65 72.241)
		(size 0.45)
		(drill 0.1)
		(layers "F.Cu" "B.Cu")
		(net 1)
	)
	(via
		(at 50.4 73.15)
		(size 0.45)
		(drill 0.1)
		(layers "F.Cu" "B.Cu")
		(net 1)
	)
	(via
		(at 145.05 93.85)
		(size 0.45)
		(drill 0.1)
		(layers "F.Cu" "B.Cu")
		(free yes)
		(net 1)
	)
	(via
		(at 50.5 119.4)
		(size 0.45)
		(drill 0.1)
		(layers "F.Cu" "B.Cu")
		(free yes)
		(net 1)
	)
	(via
		(at 104.35 128.05)
		(size 0.45)
		(drill 0.1)
		(layers "F.Cu" "B.Cu")
		(net 1)
	)
	(via
		(at 125.51 92.55)
		(size 0.45)
		(drill 0.1)
		(layers "F.Cu" "B.Cu")
		(net 1)
	)
	(via
		(at 57.69 96.01)
		(size 0.45)
		(drill 0.1)
		(layers "F.Cu" "B.Cu")
		(net 1)
	)
	(via
		(at 82.74 70.75)
		(size 0.45)
		(drill 0.1)
		(layers "F.Cu" "B.Cu")
		(net 1)
	)
	(via
		(at 133.9 114.1245)
		(size 0.45)
		(drill 0.1)
		(layers "F.Cu" "B.Cu")
		(net 1)
	)
	(via
		(at 121.69 94.05)
		(size 0.45)
		(drill 0.1)
		(layers "F.Cu" "B.Cu")
		(free yes)
		(net 1)
	)
	(via
		(at 108.676468 110.8875)
		(size 0.45)
		(drill 0.1)
		(layers "F.Cu" "B.Cu")
		(net 1)
	)
	(via
		(at 95.15 122.85)
		(size 0.45)
		(drill 0.1)
		(layers "F.Cu" "B.Cu")
		(net 1)
	)
	(via
		(at 137.85 82)
		(size 0.45)
		(drill 0.1)
		(layers "F.Cu" "B.Cu")
		(net 1)
	)
	(via
		(at 125.808002 81.391998)
		(size 0.45)
		(drill 0.1)
		(layers "F.Cu" "B.Cu")
		(net 1)
	)
	(via
		(at 125.85 77.6)
		(size 0.45)
		(drill 0.1)
		(layers "F.Cu" "B.Cu")
		(net 1)
	)
	(via
		(at 61.17 95.22)
		(size 0.45)
		(drill 0.1)
		(layers "F.Cu" "B.Cu")
		(net 1)
	)
	(via
		(at 65.2 74.3)
		(size 0.45)
		(drill 0.1)
		(layers "F.Cu" "B.Cu")
		(net 1)
	)
	(via
		(at 100 75.95)
		(size 0.45)
		(drill 0.1)
		(layers "F.Cu" "B.Cu")
		(net 1)
	)
	(via
		(at 84.375 99.99)
		(size 0.45)
		(drill 0.1)
		(layers "F.Cu" "B.Cu")
		(free yes)
		(net 1)
	)
	(via
		(at 93.650167 78.750167)
		(size 0.45)
		(drill 0.1)
		(layers "F.Cu" "B.Cu")
		(net 1)
	)
	(via
		(at 124.6 73.26)
		(size 0.45)
		(drill 0.1)
		(layers "F.Cu" "B.Cu")
		(net 1)
	)
	(via
		(at 119.868506 78.660937)
		(size 0.45)
		(drill 0.1)
		(layers "F.Cu" "B.Cu")
		(net 1)
	)
	(via
		(at 51.1 118.8)
		(size 0.45)
		(drill 0.1)
		(layers "F.Cu" "B.Cu")
		(free yes)
		(net 1)
	)
	(via
		(at 49.5125 112.974001)
		(size 0.45)
		(drill 0.1)
		(layers "F.Cu" "B.Cu")
		(net 1)
	)
	(via
		(at 122.890585 78.890585)
		(size 0.45)
		(drill 0.1)
		(layers "F.Cu" "B.Cu")
		(net 1)
	)
	(via
		(at 76.33 113.25)
		(size 0.45)
		(drill 0.1)
		(layers "F.Cu" "B.Cu")
		(free yes)
		(net 1)
	)
	(via
		(at 57.9 106.4)
		(size 0.45)
		(drill 0.1)
		(layers "F.Cu" "B.Cu")
		(net 1)
	)
	(via
		(at 57.53 96.45)
		(size 0.45)
		(drill 0.1)
		(layers "F.Cu" "B.Cu")
		(net 1)
	)
	(via
		(at 137.2 108.0255)
		(size 0.45)
		(drill 0.1)
		(layers "F.Cu" "B.Cu")
		(net 1)
	)
	(via
		(at 125.67 91.35)
		(size 0.45)
		(drill 0.1)
		(layers "F.Cu" "B.Cu")
		(net 1)
	)
	(via
		(at 108.11 73.379)
		(size 0.45)
		(drill 0.1)
		(layers "F.Cu" "B.Cu")
		(net 1)
	)
	(via
		(at 125.58 96.83)
		(size 0.45)
		(drill 0.1)
		(layers "F.Cu" "B.Cu")
		(net 1)
	)
	(via
		(at 134.07 85.27)
		(size 0.45)
		(drill 0.1)
		(layers "F.Cu" "B.Cu")
		(free yes)
		(net 1)
	)
	(via
		(at 75.95 89.85)
		(size 0.45)
		(drill 0.1)
		(layers "F.Cu" "B.Cu")
		(net 1)
	)
	(via
		(at 148.625 88.325)
		(size 0.45)
		(drill 0.1)
		(layers "F.Cu" "B.Cu")
		(net 1)
	)
	(via
		(at 94.962501 117.706675)
		(size 0.45)
		(drill 0.1)
		(layers "F.Cu" "B.Cu")
		(free yes)
		(net 1)
	)
	(via
		(at 134.45 119.35)
		(size 0.45)
		(drill 0.1)
		(layers "F.Cu" "B.Cu")
		(net 1)
	)
	(via
		(at 76.738028 78.150119)
		(size 0.45)
		(drill 0.1)
		(layers "F.Cu" "B.Cu")
		(net 1)
	)
	(via
		(at 133.69 70.89)
		(size 0.45)
		(drill 0.1)
		(layers "F.Cu" "B.Cu")
		(net 1)
	)
	(via
		(at 113.86 81.46)
		(size 0.45)
		(drill 0.1)
		(layers "F.Cu" "B.Cu")
		(net 1)
	)
	(via
		(at 105.05 88.24)
		(size 0.45)
		(drill 0.1)
		(layers "F.Cu" "B.Cu")
		(net 1)
	)
	(via
		(at 112.52 86.3)
		(size 0.45)
		(drill 0.1)
		(layers "F.Cu" "B.Cu")
		(net 1)
	)
	(via
		(at 102.78 100.5625)
		(size 0.45)
		(drill 0.1)
		(layers "F.Cu" "B.Cu")
		(free yes)
		(net 1)
	)
	(via
		(at 97.1255 85.4285)
		(size 0.45)
		(drill 0.1)
		(layers "F.Cu" "B.Cu")
		(net 1)
	)
	(via
		(at 121.59 70.65)
		(size 0.45)
		(drill 0.1)
		(layers "F.Cu" "B.Cu")
		(net 1)
	)
	(via
		(at 83.45 84.55)
		(size 0.45)
		(drill 0.1)
		(layers "F.Cu" "B.Cu")
		(free yes)
		(net 1)
	)
	(via
		(at 103.94383 89.225)
		(size 0.45)
		(drill 0.1)
		(layers "F.Cu" "B.Cu")
		(net 1)
	)
	(via
		(at 128.3 85)
		(size 0.45)
		(drill 0.1)
		(layers "F.Cu" "B.Cu")
		(free yes)
		(net 1)
	)
	(via
		(at 62.55 73.35)
		(size 0.45)
		(drill 0.1)
		(layers "F.Cu" "B.Cu")
		(free yes)
		(net 1)
	)
	(via
		(at 133.5285 91.08)
		(size 0.45)
		(drill 0.1)
		(layers "F.Cu" "B.Cu")
		(free yes)
		(net 1)
	)
	(via
		(at 145.2 86.375)
		(size 0.45)
		(drill 0.1)
		(layers "F.Cu" "B.Cu")
		(free yes)
		(net 1)
	)
	(via
		(at 63.55 73.35)
		(size 0.45)
		(drill 0.1)
		(layers "F.Cu" "B.Cu")
		(free yes)
		(net 1)
	)
	(via
		(at 83.45 86.7)
		(size 0.45)
		(drill 0.1)
		(layers "F.Cu" "B.Cu")
		(free yes)
		(net 1)
	)
	(via
		(at 142.42 86.49)
		(size 0.45)
		(drill 0.1)
		(layers "F.Cu" "B.Cu")
		(free yes)
		(net 1)
	)
	(via
		(at 93.95 122.85)
		(size 0.45)
		(drill 0.1)
		(layers "F.Cu" "B.Cu")
		(net 1)
	)
	(via
		(at 146.87 84.34)
		(size 0.45)
		(drill 0.1)
		(layers "F.Cu" "B.Cu")
		(free yes)
		(net 1)
	)
	(via
		(at 87.34 85.88)
		(size 0.45)
		(drill 0.1)
		(layers "F.Cu" "B.Cu")
		(free yes)
		(net 1)
	)
	(via
		(at 146.9 93.8)
		(size 0.45)
		(drill 0.1)
		(layers "F.Cu" "B.Cu")
		(free yes)
		(net 1)
	)
	(via
		(at 62.34 95.97)
		(size 0.45)
		(drill 0.1)
		(layers "F.Cu" "B.Cu")
		(net 1)
	)
	(via
		(at 128.22 90.84)
		(size 0.45)
		(drill 0.1)
		(layers "F.Cu" "B.Cu")
		(free yes)
		(net 1)
	)
	(via
		(at 63.46 85.56)
		(size 0.45)
		(drill 0.1)
		(layers "F.Cu" "B.Cu")
		(net 1)
	)
	(via
		(at 123.2 83.5)
		(size 0.45)
		(drill 0.1)
		(layers "F.Cu" "B.Cu")
		(net 1)
	)
	(via
		(at 91.1755 77.9)
		(size 0.45)
		(drill 0.1)
		(layers "F.Cu" "B.Cu")
		(free yes)
		(net 1)
	)
	(via
		(at 105.65 118.725)
		(size 0.45)
		(drill 0.1)
		(layers "F.Cu" "B.Cu")
		(net 1)
	)
	(via
		(at 49.9 119.4)
		(size 0.45)
		(drill 0.1)
		(layers "F.Cu" "B.Cu")
		(free yes)
		(net 1)
	)
	(via
		(at 131.45 95.2)
		(size 0.45)
		(drill 0.1)
		(layers "F.Cu" "B.Cu")
		(net 1)
	)
	(via
		(at 92.226064 70.3)
		(size 0.45)
		(drill 0.1)
		(layers "F.Cu" "B.Cu")
		(net 1)
	)
	(via
		(at 142.45 91)
		(size 0.45)
		(drill 0.1)
		(layers "F.Cu" "B.Cu")
		(net 1)
	)
	(via
		(at 132.55 90.15)
		(size 0.45)
		(drill 0.1)
		(layers "F.Cu" "B.Cu")
		(free yes)
		(net 1)
	)
	(via
		(at 76.32 74.58)
		(size 0.45)
		(drill 0.1)
		(layers "F.Cu" "B.Cu")
		(net 1)
	)
	(via
		(at 129 95.15)
		(size 0.45)
		(drill 0.1)
		(layers "F.Cu" "B.Cu")
		(net 1)
	)
	(via
		(at 81.33 75)
		(size 0.45)
		(drill 0.1)
		(layers "F.Cu" "B.Cu")
		(net 1)
	)
	(via
		(at 70.7 83.3875)
		(size 0.45)
		(drill 0.1)
		(layers "F.Cu" "B.Cu")
		(free yes)
		(net 1)
	)
	(via
		(at 58.4 79)
		(size 0.45)
		(drill 0.1)
		(layers "F.Cu" "B.Cu")
		(net 1)
	)
	(via
		(at 146.875 86.275)
		(size 0.45)
		(drill 0.1)
		(layers "F.Cu" "B.Cu")
		(free yes)
		(net 1)
	)
	(via
		(at 76.15 101.15)
		(size 0.45)
		(drill 0.1)
		(layers "F.Cu" "B.Cu")
		(free yes)
		(net 1)
	)
	(via
		(at 63.46 85.06)
		(size 0.45)
		(drill 0.1)
		(layers "F.Cu" "B.Cu")
		(net 1)
	)
	(via
		(at 122.09 89.5)
		(size 0.45)
		(drill 0.1)
		(layers "F.Cu" "B.Cu")
		(net 1)
	)
	(via
		(at 63.05 73.35)
		(size 0.45)
		(drill 0.1)
		(layers "F.Cu" "B.Cu")
		(free yes)
		(net 1)
	)
	(via
		(at 125.63 89.16)
		(size 0.45)
		(drill 0.1)
		(layers "F.Cu" "B.Cu")
		(net 1)
	)
	(via
		(at 73.9 107.9)
		(size 0.45)
		(drill 0.1)
		(layers "F.Cu" "B.Cu")
		(free yes)
		(net 1)
	)
	(via
		(at 75.074048 106.266885)
		(size 0.45)
		(drill 0.1)
		(layers "F.Cu" "B.Cu")
		(free yes)
		(net 1)
	)
	(via
		(at 113.765584 103.684416)
		(size 0.45)
		(drill 0.1)
		(layers "F.Cu" "B.Cu")
		(net 1)
	)
	(via
		(at 86.08 70.77)
		(size 0.45)
		(drill 0.1)
		(layers "F.Cu" "B.Cu")
		(net 1)
	)
	(via
		(at 127.8 125.05)
		(size 0.45)
		(drill 0.1)
		(layers "F.Cu" "B.Cu")
		(net 1)
	)
	(via
		(at 109.04 87.02)
		(size 0.45)
		(drill 0.1)
		(layers "F.Cu" "B.Cu")
		(net 1)
	)
	(via
		(at 122.47 86.34)
		(size 0.45)
		(drill 0.1)
		(layers "F.Cu" "B.Cu")
		(net 1)
	)
	(via
		(at 83.315 99.08)
		(size 0.45)
		(drill 0.1)
		(layers "F.Cu" "B.Cu")
		(free yes)
		(net 1)
	)
	(via
		(at 116.6 75.941)
		(size 0.45)
		(drill 0.1)
		(layers "F.Cu" "B.Cu")
		(free yes)
		(net 1)
	)
	(via
		(at 113.92 82.97)
		(size 0.45)
		(drill 0.1)
		(layers "F.Cu" "B.Cu")
		(net 1)
	)
	(via
		(at 66.960356 97.660356)
		(size 0.45)
		(drill 0.1)
		(layers "F.Cu" "B.Cu")
		(net 1)
	)
	(via
		(at 72.14 116.55)
		(size 0.45)
		(drill 0.1)
		(layers "F.Cu" "B.Cu")
		(net 1)
	)
	(via
		(at 125.56 83.56)
		(size 0.45)
		(drill 0.1)
		(layers "F.Cu" "B.Cu")
		(net 1)
	)
	(via
		(at 146.85 91.175)
		(size 0.45)
		(drill 0.1)
		(layers "F.Cu" "B.Cu")
		(free yes)
		(net 1)
	)
	(via
		(at 85.72 75.83)
		(size 0.45)
		(drill 0.1)
		(layers "F.Cu" "B.Cu")
		(free yes)
		(net 1)
	)
	(via
		(at 106.6 70.73)
		(size 0.45)
		(drill 0.1)
		(layers "F.Cu" "B.Cu")
		(net 1)
	)
	(via
		(at 57.16 84.43)
		(size 0.45)
		(drill 0.1)
		(layers "F.Cu" "B.Cu")
		(free yes)
		(net 1)
	)
	(via
		(at 70.875 76.925)
		(size 0.45)
		(drill 0.1)
		(layers "F.Cu" "B.Cu")
		(net 1)
	)
	(via
		(at 140.425 87.975)
		(size 0.45)
		(drill 0.1)
		(layers "F.Cu" "B.Cu")
		(free yes)
		(net 1)
	)
	(via
		(at 53.45 120.1)
		(size 0.45)
		(drill 0.1)
		(layers "F.Cu" "B.Cu")
		(net 1)
	)
	(via
		(at 140.4 107.15)
		(size 0.45)
		(drill 0.1)
		(layers "F.Cu" "B.Cu")
		(net 1)
	)
	(via
		(at 77.9 109.45)
		(size 0.45)
		(drill 0.1)
		(layers "F.Cu" "B.Cu")
		(free yes)
		(net 1)
	)
	(via
		(at 106.72 128.02)
		(size 0.45)
		(drill 0.1)
		(layers "F.Cu" "B.Cu")
		(net 1)
	)
	(via
		(at 86.8 93.72)
		(size 0.45)
		(drill 0.1)
		(layers "F.Cu" "B.Cu")
		(free yes)
		(net 1)
	)
	(via
		(at 63.55 74.35)
		(size 0.45)
		(drill 0.1)
		(layers "F.Cu" "B.Cu")
		(free yes)
		(net 1)
	)
	(via
		(at 81.941624 81.371)
		(size 0.45)
		(drill 0.1)
		(layers "F.Cu" "B.Cu")
		(net 1)
	)
	(via
		(at 123.13 87.39)
		(size 0.45)
		(drill 0.1)
		(layers "F.Cu" "B.Cu")
		(net 1)
	)
	(via
		(at 125.85 77.03)
		(size 0.45)
		(drill 0.1)
		(layers "F.Cu" "B.Cu")
		(net 1)
	)
	(via
		(at 127.95 96.5)
		(size 0.45)
		(drill 0.1)
		(layers "F.Cu" "B.Cu")
		(net 1)
	)
	(via
		(at 141.5 124.96)
		(size 0.45)
		(drill 0.1)
		(layers "F.Cu" "B.Cu")
		(net 1)
	)
	(via
		(at 138.539 84.975)
		(size 0.45)
		(drill 0.1)
		(layers "F.Cu" "B.Cu")
		(net 1)
	)
	(via
		(at 74.1 69.8)
		(size 0.45)
		(drill 0.1)
		(layers "F.Cu" "B.Cu")
		(net 1)
	)
	(via
		(at 92.75 122.85)
		(size 0.45)
		(drill 0.1)
		(layers "F.Cu" "B.Cu")
		(net 1)
	)
	(via
		(at 66.8625 81.75)
		(size 0.45)
		(drill 0.1)
		(layers "F.Cu" "B.Cu")
		(free yes)
		(net 1)
	)
	(via
		(at 49.9 118.8)
		(size 0.45)
		(drill 0.1)
		(layers "F.Cu" "B.Cu")
		(free yes)
		(net 1)
	)
	(via
		(at 109.46 81.44)
		(size 0.45)
		(drill 0.1)
		(layers "F.Cu" "B.Cu")
		(net 1)
	)
	(via
		(at 90.15 70.7)
		(size 0.45)
		(drill 0.1)
		(layers "F.Cu" "B.Cu")
		(net 1)
	)
	(via
		(at 90.7 85.675)
		(size 0.45)
		(drill 0.1)
		(layers "F.Cu" "B.Cu")
		(free yes)
		(net 1)
	)
	(via
		(at 128.25 83.5375)
		(size 0.45)
		(drill 0.1)
		(layers "F.Cu" "B.Cu")
		(free yes)
		(net 1)
	)
	(via
		(at 58.2598 90.107733)
		(size 0.45)
		(drill 0.1)
		(layers "F.Cu" "B.Cu")
		(net 1)
	)
	(via
		(at 127.85 81.023)
		(size 0.45)
		(drill 0.1)
		(layers "F.Cu" "B.Cu")
		(free yes)
		(net 1)
	)
	(via
		(at 80.77 74.52)
		(size 0.45)
		(drill 0.1)
		(layers "F.Cu" "B.Cu")
		(net 1)
	)
	(via
		(at 145.175 91.125)
		(size 0.45)
		(drill 0.1)
		(layers "F.Cu" "B.Cu")
		(free yes)
		(net 1)
	)
	(via
		(at 65.9255 109.1455)
		(size 0.45)
		(drill 0.1)
		(layers "F.Cu" "B.Cu")
		(net 1)
	)
	(via
		(at 87.85 78.9)
		(size 0.45)
		(drill 0.1)
		(layers "F.Cu" "B.Cu")
		(net 1)
	)
	(via
		(at 90.6 118.6)
		(size 0.45)
		(drill 0.1)
		(layers "F.Cu" "B.Cu")
		(net 1)
	)
	(via
		(at 70.7 76.25)
		(size 0.45)
		(drill 0.1)
		(layers "F.Cu" "B.Cu")
		(net 1)
	)
	(via
		(at 78.34 111.65)
		(size 0.45)
		(drill 0.1)
		(layers "F.Cu" "B.Cu")
		(net 1)
	)
	(via
		(at 122.199484 99.377784)
		(size 0.45)
		(drill 0.1)
		(layers "F.Cu" "B.Cu")
		(free yes)
		(net 1)
	)
	(via
		(at 50.5 118.8)
		(size 0.45)
		(drill 0.1)
		(layers "F.Cu" "B.Cu")
		(free yes)
		(net 1)
	)
	(via
		(at 115.52 78.9)
		(size 0.45)
		(drill 0.1)
		(layers "F.Cu" "B.Cu")
		(net 1)
	)
	(via
		(at 137.15 91.083)
		(size 0.45)
		(drill 0.1)
		(layers "F.Cu" "B.Cu")
		(net 1)
	)
	(via
		(at 137.2 92.906098)
		(size 0.45)
		(drill 0.1)
		(layers "F.Cu" "B.Cu")
		(net 1)
	)
	(via
		(at 85.21 88.69)
		(size 0.45)
		(drill 0.1)
		(layers "F.Cu" "B.Cu")
		(free yes)
		(net 1)
	)
	(via
		(at 87.6 108.2345)
		(size 0.45)
		(drill 0.1)
		(layers "F.Cu" "B.Cu")
		(net 1)
	)
	(via
		(at 40.7 82.2)
		(size 0.45)
		(drill 0.1)
		(layers "F.Cu" "B.Cu")
		(free yes)
		(net 1)
	)
	(via
		(at 117.14 70.74)
		(size 0.45)
		(drill 0.1)
		(layers "F.Cu" "B.Cu")
		(net 1)
	)
	(via
		(at 120.65 98.47)
		(size 0.45)
		(drill 0.1)
		(layers "F.Cu" "B.Cu")
		(net 1)
	)
	(via
		(at 125.65 104.8)
		(size 0.45)
		(drill 0.1)
		(layers "F.Cu" "B.Cu")
		(net 1)
	)
	(via
		(at 69.95 106.83)
		(size 0.45)
		(drill 0.1)
		(layers "F.Cu" "B.Cu")
		(free yes)
		(net 1)
	)
	(via
		(at 67.065 126.755)
		(size 0.45)
		(drill 0.1)
		(layers "F.Cu" "B.Cu")
		(net 1)
	)
	(via
		(at 134.19 90.31)
		(size 0.45)
		(drill 0.1)
		(layers "F.Cu" "B.Cu")
		(net 1)
	)
	(via
		(at 123.32 98.43)
		(size 0.45)
		(drill 0.1)
		(layers "F.Cu" "B.Cu")
		(net 1)
	)
	(via
		(at 66.6 111.3)
		(size 0.45)
		(drill 0.1)
		(layers "F.Cu" "B.Cu")
		(net 1)
	)
	(via
		(at 61.68 96.61)
		(size 0.45)
		(drill 0.1)
		(layers "F.Cu" "B.Cu")
		(net 1)
	)
	(via
		(at 77.75 117.1)
		(size 0.45)
		(drill 0.1)
		(layers "F.Cu" "B.Cu")
		(net 1)
	)
	(via
		(at 62.55 74.35)
		(size 0.45)
		(drill 0.1)
		(layers "F.Cu" "B.Cu")
		(free yes)
		(net 1)
	)
	(via
		(at 44.65 120.6)
		(size 0.45)
		(drill 0.1)
		(layers "F.Cu" "B.Cu")
		(net 1)
	)
	(via
		(at 85.331979 123.983021)
		(size 0.45)
		(drill 0.1)
		(layers "F.Cu" "B.Cu")
		(net 1)
	)
	(via
		(at 110.59 78.82)
		(size 0.45)
		(drill 0.1)
		(layers "F.Cu" "B.Cu")
		(net 1)
	)
	(via
		(at 106.735891 78.89666)
		(size 0.45)
		(drill 0.1)
		(layers "F.Cu" "B.Cu")
		(net 1)
	)
	(via
		(at 125.6 93.99)
		(size 0.45)
		(drill 0.1)
		(layers "F.Cu" "B.Cu")
		(net 1)
	)
	(via
		(at 120.14 70.41)
		(size 0.45)
		(drill 0.1)
		(layers "F.Cu" "B.Cu")
		(net 1)
	)
	(via
		(at 125.63 88.1)
		(size 0.45)
		(drill 0.1)
		(layers "F.Cu" "B.Cu")
		(net 1)
	)
	(via
		(at 132.35 85.75)
		(size 0.45)
		(drill 0.1)
		(layers "F.Cu" "B.Cu")
		(free yes)
		(net 1)
	)
	(via
		(at 105.72 90.95)
		(size 0.45)
		(drill 0.1)
		(layers "F.Cu" "B.Cu")
		(net 1)
	)
	(via
		(at 121.22 78.56)
		(size 0.45)
		(drill 0.1)
		(layers "F.Cu" "B.Cu")
		(net 1)
	)
	(via
		(at 144.7 113.2)
		(size 0.45)
		(drill 0.1)
		(layers "F.Cu" "B.Cu")
		(net 1)
	)
	(via
		(at 121.92 84.84)
		(size 0.45)
		(drill 0.1)
		(layers "F.Cu" "B.Cu")
		(net 1)
	)
	(via
		(at 76.275 75.075)
		(size 0.45)
		(drill 0.1)
		(layers "F.Cu" "B.Cu")
		(net 1)
	)
	(via
		(at 55.605356 103.735356)
		(size 0.45)
		(drill 0.1)
		(layers "F.Cu" "B.Cu")
		(net 1)
	)
	(via
		(at 121.114209 81.393058)
		(size 0.45)
		(drill 0.1)
		(layers "F.Cu" "B.Cu")
		(net 1)
	)
	(via
		(at 69.55 109.435)
		(size 0.45)
		(drill 0.1)
		(layers "F.Cu" "B.Cu")
		(net 1)
	)
	(via
		(at 123.24 86.48)
		(size 0.45)
		(drill 0.1)
		(layers "F.Cu" "B.Cu")
		(net 1)
	)
	(via
		(at 112.5 93.1)
		(size 0.45)
		(drill 0.1)
		(layers "F.Cu" "B.Cu")
		(net 1)
	)
	(via
		(at 96.65 70.85)
		(size 0.45)
		(drill 0.1)
		(layers "F.Cu" "B.Cu")
		(net 1)
	)
	(via
		(at 51.6 70.9)
		(size 0.45)
		(drill 0.1)
		(layers "F.Cu" "B.Cu")
		(net 1)
	)
	(via
		(at 63.25 81.3125)
		(size 0.45)
		(drill 0.1)
		(layers "F.Cu" "B.Cu")
		(free yes)
		(net 1)
	)
	(via
		(at 114.34 75.23)
		(size 0.45)
		(drill 0.1)
		(layers "F.Cu" "B.Cu")
		(net 1)
	)
	(via
		(at 84.14 76.84)
		(size 0.45)
		(drill 0.1)
		(layers "F.Cu" "B.Cu")
		(free yes)
		(net 1)
	)
	(via
		(at 146.875 88.775)
		(size 0.45)
		(drill 0.1)
		(layers "F.Cu" "B.Cu")
		(free yes)
		(net 1)
	)
	(via
		(at 113.76 78.6)
		(size 0.45)
		(drill 0.1)
		(layers "F.Cu" "B.Cu")
		(net 1)
	)
	(via
		(at 98.499833 102.649833)
		(size 0.45)
		(drill 0.1)
		(layers "F.Cu" "B.Cu")
		(net 1)
	)
	(via
		(at 47.725 74.95)
		(size 0.45)
		(drill 0.1)
		(layers "F.Cu" "B.Cu")
		(net 1)
	)
	(via
		(at 62.75 81.3125)
		(size 0.45)
		(drill 0.1)
		(layers "F.Cu" "B.Cu")
		(free yes)
		(net 1)
	)
	(via
		(at 75.44 112.2)
		(size 0.45)
		(drill 0.1)
		(layers "F.Cu" "B.Cu")
		(net 1)
	)
	(via
		(at 78 114.625)
		(size 0.45)
		(drill 0.1)
		(layers "F.Cu" "B.Cu")
		(net 1)
	)
	(via
		(at 121.14 88.76)
		(size 0.45)
		(drill 0.1)
		(layers "F.Cu" "B.Cu")
		(net 1)
	)
	(via
		(at 145.14 83.35)
		(size 0.45)
		(drill 0.1)
		(layers "F.Cu" "B.Cu")
		(free yes)
		(net 1)
	)
	(via
		(at 84.125 88.4)
		(size 0.45)
		(drill 0.1)
		(layers "F.Cu" "B.Cu")
		(free yes)
		(net 1)
	)
	(via
		(at 109.107954 78.785013)
		(size 0.45)
		(drill 0.1)
		(layers "F.Cu" "B.Cu")
		(net 1)
	)
	(via
		(at 128.45 86.45)
		(size 0.45)
		(drill 0.1)
		(layers "F.Cu" "B.Cu")
		(free yes)
		(net 1)
	)
	(via
		(at 138.75 87.9)
		(size 0.45)
		(drill 0.1)
		(layers "F.Cu" "B.Cu")
		(net 1)
	)
	(via
		(at 111.52 73.56)
		(size 0.45)
		(drill 0.1)
		(layers "F.Cu" "B.Cu")
		(net 1)
	)
	(via
		(at 50.5 118.2)
		(size 0.45)
		(drill 0.1)
		(layers "F.Cu" "B.Cu")
		(free yes)
		(net 1)
	)
	(via
		(at 121.25 82.75)
		(size 0.45)
		(drill 0.1)
		(layers "F.Cu" "B.Cu")
		(net 1)
	)
	(via
		(at 65.4 126.2)
		(size 0.45)
		(drill 0.1)
		(layers "F.Cu" "B.Cu")
		(net 1)
	)
	(via
		(at 57.83 85.02)
		(size 0.45)
		(drill 0.1)
		(layers "F.Cu" "B.Cu")
		(free yes)
		(net 1)
	)
	(via
		(at 51.1 119.4)
		(size 0.45)
		(drill 0.1)
		(layers "F.Cu" "B.Cu")
		(free yes)
		(net 1)
	)
	(via
		(at 86.275 85.025)
		(size 0.45)
		(drill 0.1)
		(layers "F.Cu" "B.Cu")
		(free yes)
		(net 1)
	)
	(via
		(at 129.8 127)
		(size 0.45)
		(drill 0.1)
		(layers "F.Cu" "B.Cu")
		(net 1)
	)
	(via
		(at 67.375 77.45)
		(size 0.45)
		(drill 0.1)
		(layers "F.Cu" "B.Cu")
		(net 1)
	)
	(via
		(at 112.85 78.35)
		(size 0.45)
		(drill 0.1)
		(layers "F.Cu" "B.Cu")
		(net 1)
	)
	(via
		(at 69.5 90.25)
		(size 0.45)
		(drill 0.1)
		(layers "F.Cu" "B.Cu")
		(net 1)
	)
	(via
		(at 72.45 84.9)
		(size 0.45)
		(drill 0.1)
		(layers "F.Cu" "B.Cu")
		(net 1)
	)
	(via
		(at 52.475 79.125)
		(size 0.45)
		(drill 0.1)
		(layers "F.Cu" "B.Cu")
		(net 1)
	)
	(via
		(at 147.7 120)
		(size 0.45)
		(drill 0.1)
		(layers "F.Cu" "B.Cu")
		(net 1)
	)
	(via
		(at 87.029 74.539999)
		(size 0.45)
		(drill 0.1)
		(layers "F.Cu" "B.Cu")
		(net 1)
	)
	(via
		(at 33.3 79.6)
		(size 0.45)
		(drill 0.1)
		(layers "F.Cu" "B.Cu")
		(net 1)
	)
	(via
		(at 118.55 70.7)
		(size 0.45)
		(drill 0.1)
		(layers "F.Cu" "B.Cu")
		(net 1)
	)
	(via
		(at 83.352866 81.347134)
		(size 0.45)
		(drill 0.1)
		(layers "F.Cu" "B.Cu")
		(net 1)
	)
	(via
		(at 55.800167 108.700167)
		(size 0.45)
		(drill 0.1)
		(layers "F.Cu" "B.Cu")
		(net 1)
	)
	(via
		(at 86.289091 89.916411)
		(size 0.45)
		(drill 0.1)
		(layers "F.Cu" "B.Cu")
		(free yes)
		(net 1)
	)
	(via
		(at 64.48 95.32)
		(size 0.45)
		(drill 0.1)
		(layers "F.Cu" "B.Cu")
		(net 1)
	)
	(via
		(at 112.6 70.79)
		(size 0.45)
		(drill 0.1)
		(layers "F.Cu" "B.Cu")
		(net 1)
	)
	(via
		(at 48.1 122.3)
		(size 0.45)
		(drill 0.1)
		(layers "F.Cu" "B.Cu")
		(net 1)
	)
	(via
		(at 60.32 95.22)
		(size 0.45)
		(drill 0.1)
		(layers "F.Cu" "B.Cu")
		(net 1)
	)
	(via
		(at 139.775 100.425)
		(size 0.45)
		(drill 0.1)
		(layers "F.Cu" "B.Cu")
		(net 1)
	)
	(via
		(at 137.7 122)
		(size 0.45)
		(drill 0.1)
		(layers "F.Cu" "B.Cu")
		(net 1)
	)
	(via
		(at 88.05 91.85)
		(size 0.45)
		(drill 0.1)
		(layers "F.Cu" "B.Cu")
		(free yes)
		(net 1)
	)
	(via
		(at 113.15 73.5)
		(size 0.45)
		(drill 0.1)
		(layers "F.Cu" "B.Cu")
		(net 1)
	)
	(via
		(at 101.2 114.725)
		(size 0.45)
		(drill 0.1)
		(layers "F.Cu" "B.Cu")
		(net 1)
	)
	(via
		(at 88.67 85.16)
		(size 0.45)
		(drill 0.1)
		(layers "F.Cu" "B.Cu")
		(free yes)
		(net 1)
	)
	(via
		(at 74.75 120.1)
		(size 0.45)
		(drill 0.1)
		(layers "F.Cu" "B.Cu")
		(net 1)
	)
	(via
		(at 49.5625 110.35375)
		(size 0.45)
		(drill 0.1)
		(layers "F.Cu" "B.Cu")
		(net 1)
	)
	(via
		(at 121.7 91.1)
		(size 0.45)
		(drill 0.1)
		(layers "F.Cu" "B.Cu")
		(net 1)
	)
	(via
		(at 102.05 119.25)
		(size 0.45)
		(drill 0.1)
		(layers "F.Cu" "B.Cu")
		(net 1)
	)
	(via
		(at 137.7 118)
		(size 0.45)
		(drill 0.1)
		(layers "F.Cu" "B.Cu")
		(free yes)
		(net 1)
	)
	(via
		(at 80.065 106.263)
		(size 0.45)
		(drill 0.1)
		(layers "F.Cu" "B.Cu")
		(net 1)
	)
	(via
		(at 86.34 78.94)
		(size 0.45)
		(drill 0.1)
		(layers "F.Cu" "B.Cu")
		(net 1)
	)
	(via
		(at 72.212 102.65)
		(size 0.45)
		(drill 0.1)
		(layers "F.Cu" "B.Cu")
		(net 1)
	)
	(via
		(at 145.1 97.65)
		(size 0.45)
		(drill 0.1)
		(layers "F.Cu" "B.Cu")
		(free yes)
		(net 1)
	)
	(via
		(at 54.9 115.85)
		(size 0.45)
		(drill 0.1)
		(layers "F.Cu" "B.Cu")
		(net 1)
	)
	(via
		(at 89.85 84.625)
		(size 0.45)
		(drill 0.1)
		(layers "F.Cu" "B.Cu")
		(free yes)
		(net 1)
	)
	(via
		(at 99.6 70.775)
		(size 0.45)
		(drill 0.1)
		(layers "F.Cu" "B.Cu")
		(net 1)
	)
	(via
		(at 139.69 94.27)
		(size 0.45)
		(drill 0.1)
		(layers "F.Cu" "B.Cu")
		(free yes)
		(net 1)
	)
	(via
		(at 38.3 114.5)
		(size 0.45)
		(drill 0.1)
		(layers "F.Cu" "B.Cu")
		(net 1)
	)
	(via
		(at 119.777 97.559)
		(size 0.45)
		(drill 0.1)
		(layers "F.Cu" "B.Cu")
		(free yes)
		(net 1)
	)
	(via
		(at 135.65 122.8)
		(size 0.45)
		(drill 0.1)
		(layers "F.Cu" "B.Cu")
		(net 1)
	)
	(via
		(at 74.499514 106.279969)
		(size 0.45)
		(drill 0.1)
		(layers "F.Cu" "B.Cu")
		(free yes)
		(net 1)
	)
	(via
		(at 128.5 89.5)
		(size 0.45)
		(drill 0.1)
		(layers "F.Cu" "B.Cu")
		(free yes)
		(net 1)
	)
	(via
		(at 62.55 73.85)
		(size 0.45)
		(drill 0.1)
		(layers "F.Cu" "B.Cu")
		(free yes)
		(net 1)
	)
	(via
		(at 62.77 81.8)
		(size 0.45)
		(drill 0.1)
		(layers "F.Cu" "B.Cu")
		(free yes)
		(net 1)
	)
	(via
		(at 63.05 74.35)
		(size 0.45)
		(drill 0.1)
		(layers "F.Cu" "B.Cu")
		(free yes)
		(net 1)
	)
	(via
		(at 75 114.6)
		(size 0.45)
		(drill 0.1)
		(layers "F.Cu" "B.Cu")
		(net 1)
	)
	(via
		(at 67.75 109.2)
		(size 0.45)
		(drill 0.1)
		(layers "F.Cu" "B.Cu")
		(net 1)
	)
	(via
		(at 89.75 81.3)
		(size 0.45)
		(drill 0.1)
		(layers "F.Cu" "B.Cu")
		(net 1)
	)
	(via
		(at 123.32 75.46)
		(size 0.45)
		(drill 0.1)
		(layers "F.Cu" "B.Cu")
		(net 1)
	)
	(via
		(at 126.1 70.65)
		(size 0.45)
		(drill 0.1)
		(layers "F.Cu" "B.Cu")
		(net 1)
	)
	(via
		(at 81.95 86.6)
		(size 0.45)
		(drill 0.1)
		(layers "F.Cu" "B.Cu")
		(free yes)
		(net 1)
	)
	(via
		(at 128.45 88.05)
		(size 0.45)
		(drill 0.1)
		(layers "F.Cu" "B.Cu")
		(free yes)
		(net 1)
	)
	(via
		(at 62.35 90.25)
		(size 0.45)
		(drill 0.1)
		(layers "F.Cu" "B.Cu")
		(net 1)
	)
	(via
		(at 106.640585 86.259415)
		(size 0.45)
		(drill 0.1)
		(layers "F.Cu" "B.Cu")
		(net 1)
	)
	(via
		(at 85.44 86.12)
		(size 0.45)
		(drill 0.1)
		(layers "F.Cu" "B.Cu")
		(free yes)
		(net 1)
	)
	(via
		(at 54.9 107.7)
		(size 0.45)
		(drill 0.1)
		(layers "F.Cu" "B.Cu")
		(net 1)
	)
	(via
		(at 93.435323 81.35)
		(size 0.45)
		(drill 0.1)
		(layers "F.Cu" "B.Cu")
		(net 1)
	)
	(via
		(at 112.25 73.599)
		(size 0.45)
		(drill 0.1)
		(layers "F.Cu" "B.Cu")
		(net 1)
	)
	(via
		(at 146.95 97.64)
		(size 0.45)
		(drill 0.1)
		(layers "F.Cu" "B.Cu")
		(free yes)
		(net 1)
	)
	(via
		(at 90.9 94.9)
		(size 0.45)
		(drill 0.1)
		(layers "F.Cu" "B.Cu")
		(net 1)
	)
	(via
		(at 115.195585 81.664415)
		(size 0.45)
		(drill 0.1)
		(layers "F.Cu" "B.Cu")
		(net 1)
	)
	(via
		(at 46.994565 112.929409)
		(size 0.45)
		(drill 0.1)
		(layers "F.Cu" "B.Cu")
		(net 1)
	)
	(via
		(at 144.142909 103.849481)
		(size 0.45)
		(drill 0.1)
		(layers "F.Cu" "B.Cu")
		(net 1)
	)
	(via
		(at 125.85 76.475)
		(size 0.45)
		(drill 0.1)
		(layers "F.Cu" "B.Cu")
		(net 1)
	)
	(via
		(at 112.5 92.6)
		(size 0.45)
		(drill 0.1)
		(layers "F.Cu" "B.Cu")
		(net 1)
	)
	(via
		(at 110.85 81.46)
		(size 0.45)
		(drill 0.1)
		(layers "F.Cu" "B.Cu")
		(net 1)
	)
	(via
		(at 145.1 111.1)
		(size 0.45)
		(drill 0.1)
		(layers "F.Cu" "B.Cu")
		(net 1)
	)
	(via
		(at 125.59 95.31)
		(size 0.45)
		(drill 0.1)
		(layers "F.Cu" "B.Cu")
		(net 1)
	)
	(via
		(at 76.95 89.85)
		(size 0.45)
		(drill 0.1)
		(layers "F.Cu" "B.Cu")
		(net 1)
	)
	(via
		(at 83.35 78.95)
		(size 0.45)
		(drill 0.1)
		(layers "F.Cu" "B.Cu")
		(net 1)
	)
	(via
		(at 63.55 73.85)
		(size 0.45)
		(drill 0.1)
		(layers "F.Cu" "B.Cu")
		(free yes)
		(net 1)
	)
	(via
		(at 84.83 78.94)
		(size 0.45)
		(drill 0.1)
		(layers "F.Cu" "B.Cu")
		(net 1)
	)
	(via
		(at 98.2 75.9)
		(size 0.45)
		(drill 0.1)
		(layers "F.Cu" "B.Cu")
		(net 1)
	)
	(via
		(at 76.65 76.75)
		(size 0.45)
		(drill 0.1)
		(layers "F.Cu" "B.Cu")
		(free yes)
		(net 1)
	)
	(via
		(at 62.39 88.75)
		(size 0.45)
		(drill 0.1)
		(layers "F.Cu" "B.Cu")
		(net 1)
	)
	(via
		(at 133.65 128.125)
		(size 0.45)
		(drill 0.1)
		(layers "F.Cu" "B.Cu")
		(net 1)
	)
	(via
		(at 132.6 87.55)
		(size 0.45)
		(drill 0.1)
		(layers "F.Cu" "B.Cu")
		(free yes)
		(net 1)
	)
	(via
		(at 121.73 95.51)
		(size 0.45)
		(drill 0.1)
		(layers "F.Cu" "B.Cu")
		(net 1)
	)
	(via
		(at 108.85 91.44)
		(size 0.45)
		(drill 0.1)
		(layers "F.Cu" "B.Cu")
		(net 1)
	)
	(via
		(at 144.95 89.5)
		(size 0.45)
		(drill 0.1)
		(layers "F.Cu" "B.Cu")
		(net 1)
	)
	(via
		(at 134.15 88.2)
		(size 0.45)
		(drill 0.1)
		(layers "F.Cu" "B.Cu")
		(net 1)
	)
	(via
		(at 66.59 73.27)
		(size 0.45)
		(drill 0.1)
		(layers "F.Cu" "B.Cu")
		(net 1)
	)
	(via
		(at 76.95 90.35)
		(size 0.45)
		(drill 0.1)
		(layers "F.Cu" "B.Cu")
		(net 1)
	)
	(via
		(at 88.44 96.87)
		(size 0.45)
		(drill 0.1)
		(layers "F.Cu" "B.Cu")
		(free yes)
		(net 1)
	)
	(via
		(at 83.300167 97.500167)
		(size 0.45)
		(drill 0.1)
		(layers "F.Cu" "B.Cu")
		(free yes)
		(net 1)
	)
	(via
		(at 74.4 107.9)
		(size 0.45)
		(drill 0.1)
		(layers "F.Cu" "B.Cu")
		(free yes)
		(net 1)
	)
	(via
		(at 118.35 78.92)
		(size 0.45)
		(drill 0.1)
		(layers "F.Cu" "B.Cu")
		(net 1)
	)
	(via
		(at 91.180619 92.3)
		(size 0.45)
		(drill 0.1)
		(layers "F.Cu" "B.Cu")
		(net 1)
	)
	(via
		(at 113.35 95.72)
		(size 0.45)
		(drill 0.1)
		(layers "F.Cu" "B.Cu")
		(net 1)
	)
	(via
		(at 90.6 76.35)
		(size 0.45)
		(drill 0.1)
		(layers "F.Cu" "B.Cu")
		(free yes)
		(net 1)
	)
	(via
		(at 73 89.75)
		(size 0.45)
		(drill 0.1)
		(layers "F.Cu" "B.Cu")
		(net 1)
	)
	(via
		(at 104.67 78.77)
		(size 0.45)
		(drill 0.1)
		(layers "F.Cu" "B.Cu")
		(net 1)
	)
	(via
		(at 121.232792 98.286915)
		(size 0.45)
		(drill 0.1)
		(layers "F.Cu" "B.Cu")
		(free yes)
		(net 1)
	)
	(via
		(at 95.1 70.37)
		(size 0.45)
		(drill 0.1)
		(layers "F.Cu" "B.Cu")
		(net 1)
	)
	(via
		(at 115.61 73.41)
		(size 0.45)
		(drill 0.1)
		(layers "F.Cu" "B.Cu")
		(net 1)
	)
	(via
		(at 142.38 95.52)
		(size 0.45)
		(drill 0.1)
		(layers "F.Cu" "B.Cu")
		(free yes)
		(net 1)
	)
	(via
		(at 63.27 81.8)
		(size 0.45)
		(drill 0.1)
		(layers "F.Cu" "B.Cu")
		(free yes)
		(net 1)
	)
	(via
		(at 66.2 76.2)
		(size 0.45)
		(drill 0.1)
		(layers "F.Cu" "B.Cu")
		(net 1)
	)
	(via
		(at 131.75 91.25)
		(size 0.45)
		(drill 0.1)
		(layers "F.Cu" "B.Cu")
		(free yes)
		(net 1)
	)
	(via
		(at 125.9 127.7)
		(size 0.45)
		(drill 0.1)
		(layers "F.Cu" "B.Cu")
		(net 1)
	)
	(via
		(at 132.55 108.71)
		(size 0.45)
		(drill 0.1)
		(layers "F.Cu" "B.Cu")
		(net 1)
	)
	(via
		(at 34.8 69.4)
		(size 0.45)
		(drill 0.1)
		(layers "F.Cu" "B.Cu")
		(net 1)
	)
	(via
		(at 106.23 81.82)
		(size 0.45)
		(drill 0.1)
		(layers "F.Cu" "B.Cu")
		(net 1)
	)
	(via
		(at 58.25 73.55)
		(size 0.45)
		(drill 0.1)
		(layers "F.Cu" "B.Cu")
		(net 1)
	)
	(via
		(at 112.2 78.9)
		(size 0.45)
		(drill 0.1)
		(layers "F.Cu" "B.Cu")
		(net 1)
	)
	(via
		(at 81.87 78.9)
		(size 0.45)
		(drill 0.1)
		(layers "F.Cu" "B.Cu")
		(net 1)
	)
	(via
		(at 40.3 118.4)
		(size 0.45)
		(drill 0.1)
		(layers "F.Cu" "B.Cu")
		(net 1)
	)
	(via
		(at 51.7 118.8)
		(size 0.45)
		(drill 0.1)
		(layers "F.Cu" "B.Cu")
		(free yes)
		(net 1)
	)
	(via
		(at 148.65 84.175)
		(size 0.45)
		(drill 0.1)
		(layers "F.Cu" "B.Cu")
		(net 1)
	)
	(via
		(at 96.35 122.85)
		(size 0.45)
		(drill 0.1)
		(layers "F.Cu" "B.Cu")
		(net 1)
	)
	(via
		(at 109.3 83.2)
		(size 0.45)
		(drill 0.1)
		(layers "F.Cu" "B.Cu")
		(net 1)
	)
	(via
		(at 71.04 89.75)
		(size 0.45)
		(drill 0.1)
		(layers "F.Cu" "B.Cu")
		(net 1)
	)
	(via
		(at 94.2 70.395)
		(size 0.45)
		(drill 0.1)
		(layers "F.Cu" "B.Cu")
		(net 1)
	)
	(via
		(at 134.45 118.05)
		(size 0.45)
		(drill 0.1)
		(layers "F.Cu" "B.Cu")
		(free yes)
		(net 1)
	)
	(via
		(at 77.45 90.35)
		(size 0.45)
		(drill 0.1)
		(layers "F.Cu" "B.Cu")
		(free yes)
		(net 1)
	)
	(via
		(at 78.137131 113.328606)
		(size 0.45)
		(drill 0.1)
		(layers "F.Cu" "B.Cu")
		(free yes)
		(net 1)
	)
	(via
		(at 58.4 111.45)
		(size 0.45)
		(drill 0.1)
		(layers "F.Cu" "B.Cu")
		(net 1)
	)
	(segment
		(start 69.936 81.3)
		(end 69.8 81.436)
		(width 0.2)
		(layer "B.Cu")
		(net 1)
	)
	(segment
		(start 56.8 121.36)
		(end 57.345 121.36)
		(width 0.5)
		(layer "B.Cu")
		(net 1)
	)
	(segment
		(start 123.15 93.95)
		(end 124.275 93.95)
		(width 0.3)
		(layer "B.Cu")
		(net 1)
	)
	(segment
		(start 137.25 117.55)
		(end 137.7 118)
		(width 0.3)
		(layer "B.Cu")
		(net 1)
	)
	(segment
		(start 60.35 72.1)
		(end 60.035 71.785)
		(width 0.15)
		(layer "B.Cu")
		(net 1)
	)
	(segment
		(start 123.82 96.83)
		(end 123.55 97.1)
		(width 0.3)
		(layer "B.Cu")
		(net 1)
	)
	(segment
		(start 58.889833 71.774833)
		(end 58.9 71.785)
		(width 0.15)
		(layer "B.Cu")
		(net 1)
	)
	(segment
		(start 109.1 71.75)
		(end 108.4 71.05)
		(width 0.15)
		(layer "B.Cu")
		(net 1)
	)
	(segment
		(start 50.4 121.36)
		(end 49.855 121.36)
		(width 0.5)
		(layer "B.Cu")
		(net 1)
	)
	(segment
		(start 95.352278 99.757188)
		(end 95.352278 99.647722)
		(width 0.13)
		(layer "B.Cu")
		(net 1)
	)
	(segment
		(start 61.6 76.6)
		(end 61.9 76.3)
		(width 0.3)
		(layer "B.Cu")
		(net 1)
	)
	(segment
		(start 31.5 71.4)
		(end 31.3 71.6)
		(width 0.5)
		(layer "B.Cu")
		(net 1)
	)
	(segment
		(start 123.34 96)
		(end 125.47 96)
		(width 0.3)
		(layer "B.Cu")
		(net 1)
	)
	(segment
		(start 40.75 82.25)
		(end 40.75 86.75)
		(width 0.15)
		(layer "B.Cu")
		(net 1)
	)
	(segment
		(start 125.4 95.5)
		(end 125.59 95.31)
		(width 0.3)
		(layer "B.Cu")
		(net 1)
	)
	(segment
		(start 66.36 88.25)
		(end 62.35 88.25)
		(width 0.15)
		(layer "B.Cu")
		(net 1)
	)
	(segment
		(start 98.64999 102.499676)
		(end 98.64999 102.14999)
		(width 0.15)
		(layer "B.Cu")
		(net 1)
	)
	(segment
		(start 57.9 106.885)
		(end 58.065 107.05)
		(width 0.2)
		(layer "B.Cu")
		(net 1)
	)
	(segment
		(start 87.5655 108.2)
		(end 87.085 108.2)
		(width 0.155)
		(layer "B.Cu")
		(net 1)
	)
	(segment
		(start 102.25 100)
		(end 101.79999 100)
		(width 0.15)
		(layer "B.Cu")
		(net 1)
	)
	(segment
		(start 73.8 79.7)
		(end 73.55 79.45)
		(width 0.3)
		(layer "B.Cu")
		(net 1)
	)
	(segment
		(start 68.165 127.57)
		(end 67.425 127.57)
		(width 0.15)
		(layer "B.Cu")
		(net 1)
	)
	(segment
		(start 72.3 76.185)
		(end 71.3 76.185)
		(width 0.15)
		(layer "B.Cu")
		(net 1)
	)
	(segment
		(start 134.45 118.05)
		(end 134.435 118.05)
		(width 0.3)
		(layer "B.Cu")
		(net 1)
	)
	(segment
		(start 142.4 88)
		(end 142.35 87.95)
		(width 0.125)
		(layer "B.Cu")
		(net 1)
	)
	(segment
		(start 53.1 82.37)
		(end 53.1 81.975)
		(width 0.15)
		(layer "B.Cu")
		(net 1)
	)
	(segment
		(start 116.2 118.83)
		(end 115.8535 118.4835)
		(width 0.2)
		(layer "B.Cu")
		(net 1)
	)
	(segment
		(start 57.92 127.52)
		(end 57.92 126.115)
		(width 0.2)
		(layer "B.Cu")
		(net 1)
	)
	(segment
		(start 125.47 96)
		(end 125.59 95.88)
		(width 0.3)
		(layer "B.Cu")
		(net 1)
	)
	(segment
		(start 67.735 108.685)
		(end 68.2 108.685)
		(width 0.15)
		(layer "B.Cu")
		(net 1)
	)
	(segment
		(start 35.5 69.5)
		(end 34.9 69.5)
		(width 0.5)
		(layer "B.Cu")
		(net 1)
	)
	(segment
		(start 49.855 121.36)
		(end 49.28 121.935)
		(width 0.5)
		(layer "B.Cu")
		(net 1)
	)
	(segment
		(start 136.7 126.7)
		(end 138.14 126.7)
		(width 0.15)
		(layer "B.Cu")
		(net 1)
	)
	(segment
		(start 60.9 76.6)
		(end 61.6 76.6)
		(width 0.3)
		(layer "B.Cu")
		(net 1)
	)
	(segment
		(start 106.92 71.05)
		(end 106.6 70.73)
		(width 0.15)
		(layer "B.Cu")
		(net 1)
	)
	(segment
		(start 69.65 103.7)
		(end 69.01 103.7)
		(width 0.15)
		(layer "B.Cu")
		(net 1)
	)
	(segment
		(start 125.9 127.15)
		(end 125.9 127.7)
		(width 0.125)
		(layer "B.Cu")
		(net 1)
	)
	(segment
		(start 73.8 80.1)
		(end 73.8 79.7)
		(width 0.3)
		(layer "B.Cu")
		(net 1)
	)
	(segment
		(start 52.425 111.45)
		(end 52.425 112.275)
		(width 0.3)
		(layer "B.Cu")
		(net 1)
	)
	(segment
		(start 58.075167 71.774833)
		(end 58.889833 71.774833)
		(width 0.15)
		(layer "B.Cu")
		(net 1)
	)
	(segment
		(start 128.85 95.15)
		(end 129 95.15)
		(width 0.15)
		(layer "B.Cu")
		(net 1)
	)
	(segment
		(start 145.05 113.25)
		(end 145.2 113.4)
		(width 0.15)
		(layer "B.Cu")
		(net 1)
	)
	(segment
		(start 70.5 75.3)
		(end 70.8 75.6)
		(width 0.15)
		(layer "B.Cu")
		(net 1)
	)
	(segment
		(start 67.2 108.685)
		(end 67.735 108.685)
		(width 0.15)
		(layer "B.Cu")
		(net 1)
	)
	(segment
		(start 71.685 81.735)
		(end 71.95 82)
		(width 0.2)
		(layer "B.Cu")
		(net 1)
	)
	(segment
		(start 66.6 111.3)
		(end 67.7 111.3)
		(width 0.2)
		(layer "B.Cu")
		(net 1)
	)
	(segment
		(start 91.68 75.17)
		(end 91.005 74.495)
		(width 0.15)
		(layer "B.Cu")
		(net 1)
	)
	(segment
		(start 142.42 97)
		(end 142.41 97.01)
		(width 0.15)
		(layer "B.Cu")
		(net 1)
	)
	(segment
		(start 53.4 120.05)
		(end 53.45 120.1)
		(width 0.3)
		(layer "B.Cu")
		(net 1)
	)
	(segment
		(start 139.285 122.97)
		(end 138.315 122)
		(width 0.15)
		(layer "B.Cu")
		(net 1)
	)
	(segment
		(start 76.22 78.668147)
		(end 76.22 78.85)
		(width 0.3)
		(layer "B.Cu")
		(net 1)
	)
	(segment
		(start 100 75.25)
		(end 100 75.95)
		(width 0.3)
		(layer "B.Cu")
		(net 1)
	)
	(segment
		(start 54.9 116.315)
		(end 54.9 115.85)
		(width 0.15)
		(layer "B.Cu")
		(net 1)
	)
	(segment
		(start 57.01 121.15)
		(end 56.8 121.36)
		(width 0.3)
		(layer "B.Cu")
		(net 1)
	)
	(segment
		(start 87.265894 101.63)
		(end 86.97 101.63)
		(width 0.13)
		(layer "B.Cu")
		(net 1)
	)
	(segment
		(start 133.515 117.13)
		(end 133.935 117.55)
		(width 0.125)
		(layer "B.Cu")
		(net 1)
	)
	(segment
		(start 144.75 113.25)
		(end 144.7 113.2)
		(width 0.15)
		(layer "B.Cu")
		(net 1)
	)
	(segment
		(start 71.898 70.55)
		(end 71.898 72.898)
		(width 0.15)
		(layer "B.Cu")
		(net 1)
	)
	(segment
		(start 75.235 121.1)
		(end 75.235 120.585)
		(width 0.15)
		(layer "B.Cu")
		(net 1)
	)
	(segment
		(start 44.65 120.6)
		(end 44.65 119.945)
		(width 0.15)
		(layer "B.Cu")
		(net 1)
	)
	(segment
		(start 80.065 106.263)
		(end 79.213 106.263)
		(width 0.155)
		(layer "B.Cu")
		(net 1)
	)
	(segment
		(start 97.5 80.4)
		(end 97.5 79.55)
		(width 0.3)
		(layer "B.Cu")
		(net 1)
	)
	(segment
		(start 97.115 85.418)
		(end 97.1255 85.4285)
		(width 0.125)
		(layer "B.Cu")
		(net 1)
	)
	(segment
		(start 115.56 70.75)
		(end 115.35 70.96)
		(width 0.125)
		(layer "B.Cu")
		(net 1)
	)
	(segment
		(start 47.243974 112.68)
		(end 46.994565 112.929409)
		(width 0.15)
		(layer "B.Cu")
		(net 1)
	)
	(segment
		(start 48.03 122.23)
		(end 48.03 121.64)
		(width 0.15)
		(layer "B.Cu")
		(net 1)
	)
	(segment
		(start 95.352278 99.647722)
		(end 95.525 99.475)
		(width 0.13)
		(layer "B.Cu")
		(net 1)
	)
	(segment
		(start 67.1475 86.7375)
		(end 66.8 87.085)
		(width 0.155)
		(layer "B.Cu")
		(net 1)
	)
	(segment
		(start 47.3 112.66)
		(end 47.32 112.68)
		(width 0.15)
		(layer "B.Cu")
		(net 1)
	)
	(segment
		(start 125.59 95.88)
		(end 125.59 95.31)
		(width 0.3)
		(layer "B.Cu")
		(net 1)
	)
	(segment
		(start 61.9 75)
		(end 62.55 74.35)
		(width 0.3)
		(layer "B.Cu")
		(net 1)
	)
	(segment
		(start 91.68 75.27)
		(end 91.68 75.17)
		(width 0.15)
		(layer "B.Cu")
		(net 1)
	)
	(segment
		(start 119.95 127.15)
		(end 119.9 127.1)
		(width 0.125)
		(layer "B.Cu")
		(net 1)
	)
	(segment
		(start 145 107.2745)
		(end 145 108.95)
		(width 0.15)
		(layer "B.Cu")
		(net 1)
	)
	(segment
		(start 66.6 88.01)
		(end 66.36 88.25)
		(width 0.15)
		(layer "B.Cu")
		(net 1)
	)
	(segment
		(start 102.78 100.5625)
		(end 102.78 100.53)
		(width 0.15)
		(layer "B.Cu")
		(net 1)
	)
	(segment
		(start 66.960356 97.660356)
		(end 66.865 97.565)
		(width 0.15)
		(layer "B.Cu")
		(net 1)
	)
	(segment
		(start 55.825 77.2)
		(end 55.815 77.2)
		(width 0.15)
		(layer "B.Cu")
		(net 1)
	)
	(segment
		(start 51.9 116.315)
		(end 51.785 116.315)
		(width 0.15)
		(layer "B.Cu")
		(net 1)
	)
	(segment
		(start 87 110.785)
		(end 86.335 110.785)
		(width 0.155)
		(layer "B.Cu")
		(net 1)
	)
	(segment
		(start 71.685 80.6)
		(end 71.685 81.085)
		(width 0.2)
		(layer "B.Cu")
		(net 1)
	)
	(segment
		(start 82.005 74.172054)
		(end 82.005 73.55)
		(width 0.3)
		(layer "B.Cu")
		(net 1)
	)
	(segment
		(start 50.4 73.82)
		(end 50.4 73.15)
		(width 0.15)
		(layer "B.Cu")
		(net 1)
	)
	(segment
		(start 125.46 92.5)
		(end 125.51 92.55)
		(width 0.3)
		(layer "B.Cu")
		(net 1)
	)
	(segment
		(start 66.2 76.2)
		(end 65.9 76.5)
		(width 0.15)
		(layer "B.Cu")
		(net 1)
	)
	(segment
		(start 47.175 123.945)
		(end 48.375 123.945)
		(width 0.3)
		(layer "B.Cu")
		(net 1)
	)
	(segment
		(start 86.335 110.785)
		(end 86.325 110.775)
		(width 0.155)
		(layer "B.Cu")
		(net 1)
	)
	(segment
		(start 138 104.015)
		(end 137.36 104.015)
		(width 0.15)
		(layer "B.Cu")
		(net 1)
	)
	(segment
		(start 97.5 79.55)
		(end 97.75 79.3)
		(width 0.3)
		(layer "B.Cu")
		(net 1)
	)
	(segment
		(start 145 111)
		(end 145.1 111.1)
		(width 0.3)
		(layer "B.Cu")
		(net 1)
	)
	(segment
		(start 59.858 87.408)
		(end 59.59 87.14)
		(width 0.15)
		(layer "B.Cu")
		(net 1)
	)
	(segment
		(start 70.8 75.8)
		(end 71.185 76.185)
		(width 0.15)
		(layer "B.Cu")
		(net 1)
	)
	(segment
		(start 52.99 76.29)
		(end 52.9 76.2)
		(width 0.15)
		(layer "B.Cu")
		(net 1)
	)
	(segment
		(start 56.173952 76.827286)
		(end 56.173952 76.851048)
		(width 0.15)
		(layer "B.Cu")
		(net 1)
	)
	(segment
		(start 59.365 79)
		(end 59.415 78.95)
		(width 0.15)
		(layer "B.Cu")
		(net 1)
	)
	(segment
		(start 129.725 127.475)
		(end 129 127.475)
		(width 0.3)
		(layer "B.Cu")
		(net 1)
	)
	(segment
		(start 44.65 119.945)
		(end 44.67 119.925)
		(width 0.15)
		(layer "B.Cu")
		(net 1)
	)
	(segment
		(start 137.7905 108.0255)
		(end 138 108.235)
		(width 0.3)
		(layer "B.Cu")
		(net 1)
	)
	(segment
		(start 139.25 99.0975)
		(end 139.25 99.55)
		(width 0.3)
		(layer "B.Cu")
		(net 1)
	)
	(segment
		(start 55.2 113.575)
		(end 54.025 113.575)
		(width 0.15)
		(layer "B.Cu")
		(net 1)
	)
	(segment
		(start 101.4 122.9)
		(end 101.7 122.9)
		(width 0.2)
		(layer "B.Cu")
		(net 1)
	)
	(segment
		(start 67.735 108.685)
		(end 67.735 109.185)
		(width 0.15)
		(layer "B.Cu")
		(net 1)
	)
	(segment
		(start 37.959 118.341)
		(end 37.9 118.4)
		(width 0.3)
		(layer "B.Cu")
		(net 1)
	)
	(segment
		(start 71.685 81.085)
		(end 71.685 81.265)
		(width 0.2)
		(layer "B.Cu")
		(net 1)
	)
	(segment
		(start 132.3035 73.519)
		(end 132.1285 73.519)
		(width 0.15)
		(layer "B.Cu")
		(net 1)
	)
	(segment
		(start 113.65 107.1)
		(end 114.4 106.35)
		(width 0.15)
		(layer "B.Cu")
		(net 1)
	)
	(segment
		(start 91.75 108.8)
		(end 91.3 109.25)
		(width 0.15)
		(layer "B.Cu")
		(net 1)
	)
	(segment
		(start 66.6 111.3)
		(end 65.465 111.3)
		(width 0.2)
		(layer "B.Cu")
		(net 1)
	)
	(segment
		(start 79.213 106.263)
		(end 79.1 106.15)
		(width 0.155)
		(layer "B.Cu")
		(net 1)
	)
	(segment
		(start 63.55 74.35)
		(end 62.55 74.35)
		(width 0.3)
		(layer "B.Cu")
		(net 1)
	)
	(segment
		(start 45.3 123.595)
		(end 46.825 123.595)
		(width 0.3)
		(layer "B.Cu")
		(net 1)
	)
	(segment
		(start 54.925 83.6)
		(end 54.925 83.92)
		(width 0.15)
		(layer "B.Cu")
		(net 1)
	)
	(segment
		(start 93.8 78.9)
		(end 93.8 80.4)
		(width 0.3)
		(layer "B.Cu")
		(net 1)
	)
	(segment
		(start 145.2 113.4)
		(end 145.2 114)
		(width 0.15)
		(layer "B.Cu")
		(net 1)
	)
	(segment
		(start 98.499833 102.649833)
		(end 98.64999 102.499676)
		(width 0.15)
		(layer "B.Cu")
		(net 1)
	)
	(segment
		(start 47.326428 82.676428)
		(end 47.326428 81.615)
		(width 0.15)
		(layer "B.Cu")
		(net 1)
	)
	(segment
		(start 91.3 109.25)
		(end 90.9 109.25)
		(width 0.15)
		(layer "B.Cu")
		(net 1)
	)
	(segment
		(start 85.179 123.921)
		(end 85.18 123.92)
		(width 0.15)
		(layer "B.Cu")
		(net 1)
	)
	(segment
		(start 67.05 80.285)
		(end 67.05 81.205)
		(width 0.3)
		(layer "B.Cu")
		(net 1)
	)
	(segment
		(start 47.3 111.68)
		(end 47.3 112.66)
		(width 0.15)
		(layer "B.Cu")
		(net 1)
	)
	(segment
		(start 54.925 83.92)
		(end 54.595 84.25)
		(width 0.15)
		(layer "B.Cu")
		(net 1)
	)
	(segment
		(start 109.1 70.3)
		(end 109.1 70.35)
		(width 0.15)
		(layer "B.Cu")
		(net 1)
	)
	(segment
		(start 66.6 87.28)
		(end 66.6 88.01)
		(width 0.15)
		(layer "B.Cu")
		(net 1)
	)
	(segment
		(start 73.8 81.3)
		(end 73.8 80.1)
		(width 0.3)
		(layer "B.Cu")
		(net 1)
	)
	(segment
		(start 70.7 76.25)
		(end 70.7 75.9)
		(width 0.15)
		(layer "B.Cu")
		(net 1)
	)
	(segment
		(start 63.55 74.35)
		(end 63.55 73.35)
		(width 0.3)
		(layer "B.Cu")
		(net 1)
	)
	(segment
		(start 51.75 73.6995)
		(end 51.75 71.34)
		(width 0.15)
		(layer "B.Cu")
		(net 1)
	)
	(segment
		(start 53.4 76.29)
		(end 52.99 76.29)
		(width 0.15)
		(layer "B.Cu")
		(net 1)
	)
	(segment
		(start 123.15 92.6)
		(end 123.25 92.5)
		(width 0.3)
		(layer "B.Cu")
		(net 1)
	)
	(segment
		(start 49.5625 110.35375)
		(end 49.53 110.38625)
		(width 0.15)
		(layer "B.Cu")
		(net 1)
	)
	(segment
		(start 71.685 81.265)
		(end 71.65 81.3)
		(width 0.2)
		(layer "B.Cu")
		(net 1)
	)
	(segment
		(start 94.464999 86.65)
		(end 94.149999 86.335)
		(width 0.3)
		(layer "B.Cu")
		(net 1)
	)
	(segment
		(start 141.36 124.82)
		(end 140.58 124.82)
		(width 0.3)
		(layer "B.Cu")
		(net 1)
	)
	(segment
		(start 135.65 122.8)
		(end 134.85 123.6)
		(width 0.3)
		(layer "B.Cu")
		(net 1)
	)
	(segment
		(start 75 115.285)
		(end 75.23 115.515)
		(width 0.15)
		(layer "B.Cu")
		(net 1)
	)
	(segment
		(start 133.69 72.1325)
		(end 132.3035 73.519)
		(width 0.15)
		(layer "B.Cu")
		(net 1)
	)
	(segment
		(start 101.15 123.15)
		(end 101.4 122.9)
		(width 0.2)
		(layer "B.Cu")
		(net 1)
	)
	(segment
		(start 66.545 73.225)
		(end 66.59 73.27)
		(width 0.15)
		(layer "B.Cu")
		(net 1)
	)
	(segment
		(start 48.3 83)
		(end 47.65 83)
		(width 0.15)
		(layer "B.Cu")
		(net 1)
	)
	(segment
		(start 125.57 86.33)
		(end 125.4 86.5)
		(width 0.3)
		(layer "B.Cu")
		(net 1)
	)
	(segment
		(start 88.65 72.241)
		(end 89.089 72.68)
		(width 0.15)
		(layer "B.Cu")
		(net 1)
	)
	(segment
		(start 80.805 125.325)
		(end 81.3685 125.8885)
		(width 0.15)
		(layer "B.Cu")
		(net 1)
	)
	(segment
		(start 98.45 99.5)
		(end 98.64999 99.69999)
		(width 0.15)
		(layer "B.Cu")
		(net 1)
	)
	(segment
		(start 65.2 75.115)
		(end 64.815 75.5)
		(width 0.15)
		(layer "B.Cu")
		(net 1)
	)
	(segment
		(start 143.15 88)
		(end 142.4 88)
		(width 0.125)
		(layer "B.Cu")
		(net 1)
	)
	(segment
		(start 123.2 83.5)
		(end 125.5 83.5)
		(width 0.3)
		(layer "B.Cu")
		(net 1)
	)
	(segment
		(start 49.27 115)
		(end 49.27 115.03)
		(width 0.15)
		(layer "B.Cu")
		(net 1)
	)
	(segment
		(start 33.25 79.55)
		(end 33.3 79.6)
		(width 0.5)
		(layer "B.Cu")
		(net 1)
	)
	(segment
		(start 48.1 122.3)
		(end 47.825 122.575)
		(width 0.15)
		(layer "B.Cu")
		(net 1)
	)
	(segment
		(start 72.212 101.963)
		(end 72.28 101.895)
		(width 0.3)
		(layer "B.Cu")
		(net 1)
	)
	(segment
		(start 65.55 108.77)
		(end 65.55 108.6725)
		(width 0.15)
		(layer "B.Cu")
		(net 1)
	)
	(segment
		(start 38.3 114.5)
		(end 38.3 113.85)
		(width 0.5)
		(layer "B.Cu")
		(net 1)
	)
	(segment
		(start 52.94 82.53)
		(end 53.1 82.37)
		(width 0.15)
		(layer "B.Cu")
		(net 1)
	)
	(segment
		(start 125.63 88.1)
		(end 125.53 88)
		(width 0.3)
		(layer "B.Cu")
		(net 1)
	)
	(segment
		(start 60.035 71.785)
		(end 58.9 71.785)
		(width 0.15)
		(layer "B.Cu")
		(net 1)
	)
	(segment
		(start 95.525 98.98)
		(end 96.075 98.43)
		(width 0.13)
		(layer "B.Cu")
		(net 1)
	)
	(segment
		(start 62.55 73.35)
		(end 63.55 73.35)
		(width 0.3)
		(layer "B.Cu")
		(net 1)
	)
	(segment
		(start 124.325 86.5)
		(end 123.26 86.5)
		(width 0.3)
		(layer "B.Cu")
		(net 1)
	)
	(segment
		(start 129.8 127)
		(end 129.8 127.4)
		(width 0.3)
		(layer "B.Cu")
		(net 1)
	)
	(segment
		(start 31.5 79.55)
		(end 33.25 79.55)
		(width 0.5)
		(layer "B.Cu")
		(net 1)
	)
	(segment
		(start 47.65 83)
		(end 47.326428 82.676428)
		(width 0.15)
		(layer "B.Cu")
		(net 1)
	)
	(segment
		(start 63.59 103.7)
		(end 65.11 102.18)
		(width 0.15)
		(layer "B.Cu")
		(net 1)
	)
	(segment
		(start 47.025 74.475)
		(end 47.025 74.06)
		(width 0.15)
		(layer "B.Cu")
		(net 1)
	)
	(segment
		(start 71.685 81.465)
		(end 71.665 81.465)
		(width 0.2)
		(layer "B.Cu")
		(net 1)
	)
	(segment
		(start 47.025 74.06)
		(end 47.025 73.475)
		(width 0.15)
		(layer "B.Cu")
		(net 1)
	)
	(segment
		(start 71.5 81.3)
		(end 69.936 81.3)
		(width 0.2)
		(layer "B.Cu")
		(net 1)
	)
	(segment
		(start 52.425 112.275)
		(end 53.4 113.25)
		(width 0.3)
		(layer "B.Cu")
		(net 1)
	)
	(segment
		(start 81.712054 74.465)
		(end 82.005 74.172054)
		(width 0.3)
		(layer "B.Cu")
		(net 1)
	)
	(segment
		(start 124.325 94)
		(end 125.59 94)
		(width 0.3)
		(layer "B.Cu")
		(net 1)
	)
	(segment
		(start 106.49 86.41)
		(end 106.49 87.295)
		(width 0.3)
		(layer "B.Cu")
		(net 1)
	)
	(segment
		(start 34.9 69.5)
		(end 34.8 69.4)
		(width 0.5)
		(layer "B.Cu")
		(net 1)
	)
	(segment
		(start 124.275 93.95)
		(end 124.325 94)
		(width 0.3)
		(layer "B.Cu")
		(net 1)
	)
	(segment
		(start 125.4 86.5)
		(end 124.325 86.5)
		(width 0.3)
		(layer "B.Cu")
		(net 1)
	)
	(segment
		(start 58.735 73.55)
		(end 58.9 73.715)
		(width 0.15)
		(layer "B.Cu")
		(net 1)
	)
	(segment
		(start 113.35 95.72)
		(end 113.35 95.45)
		(width 0.3)
		(layer "B.Cu")
		(net 1)
	)
	(segment
		(start 53.725 113.575)
		(end 53.825 113.575)
		(width 0.2)
		(layer "B.Cu")
		(net 1)
	)
	(segment
		(start 95.352278 99.757188)
		(end 95.352278 100.072278)
		(width 0.3)
		(layer "B.Cu")
		(net 1)
	)
	(segment
		(start 51.6 71.19)
		(end 51.6 70.9)
		(width 0.15)
		(layer "B.Cu")
		(net 1)
	)
	(segment
		(start 112.885 107.1)
		(end 113.65 107.1)
		(width 0.15)
		(layer "B.Cu")
		(net 1)
	)
	(segment
		(start 67.7 77.45)
		(end 68.165 77.915)
		(width 0.3)
		(layer "B.Cu")
		(net 1)
	)
	(segment
		(start 60.55 127.9)
		(end 58.3 127.9)
		(width 0.2)
		(layer "B.Cu")
		(net 1)
	)
	(segment
		(start 124.275 90.95)
		(end 124.325 91)
		(width 0.3)
		(layer "B.Cu")
		(net 1)
	)
	(segment
		(start 49.53 110.38625)
		(end 49.53 110.8745)
		(width 0.15)
		(layer "B.Cu")
		(net 1)
	)
	(segment
		(start 137.534 112.649)
		(end 137.534 113.416)
		(width 0.5)
		(layer "B.Cu")
		(net 1)
	)
	(segment
		(start 67.1475 86.357976)
		(end 67.1475 86.7375)
		(width 0.155)
		(layer "B.Cu")
		(net 1)
	)
	(segment
		(start 125.5 85.07)
		(end 125.37 85.07)
		(width 0.3)
		(layer "B.Cu")
		(net 1)
	)
	(segment
		(start 71.685 81.465)
		(end 71.685 81.735)
		(width 0.2)
		(layer "B.Cu")
		(net 1)
	)
	(segment
		(start 63.05 74.35)
		(end 63.05 73.35)
		(width 0.3)
		(layer "B.Cu")
		(net 1)
	)
	(segment
		(start 62.55 74.35)
		(end 62.55 73.35)
		(width 0.3)
		(layer "B.Cu")
		(net 1)
	)
	(segment
		(start 57.49 106.4)
		(end 57.035 106.855)
		(width 0.2)
		(layer "B.Cu")
		(net 1)
	)
	(segment
		(start 59.59 87.14)
		(end 59.59 86.31)
		(width 0.15)
		(layer "B.Cu")
		(net 1)
	)
	(segment
		(start 51.7385 73.711)
		(end 51.75 73.6995)
		(width 0.15)
		(layer "B.Cu")
		(net 1)
	)
	(segment
		(start 98.64999 99.69999)
		(end 98.64999 102.14999)
		(width 0.15)
		(layer "B.Cu")
		(net 1)
	)
	(segment
		(start 98 99.5)
		(end 98.45 99.5)
		(width 0.15)
		(layer "B.Cu")
		(net 1)
	)
	(segment
		(start 67.375 77.45)
		(end 67.7 77.45)
		(width 0.3)
		(layer "B.Cu")
		(net 1)
	)
	(segment
		(start 59.858 88.07)
		(end 59.858 87.408)
		(width 0.15)
		(layer "B.Cu")
		(net 1)
	)
	(segment
		(start 109.43 92.02)
		(end 108.85 91.44)
		(width 0.15)
		(layer "B.Cu")
		(net 1)
	)
	(segment
		(start 109.1 70.35)
		(end 108.4 71.05)
		(width 0.15)
		(layer "B.Cu")
		(net 1)
	)
	(segment
		(start 58.3 127.9)
		(end 57.92 127.52)
		(width 0.2)
		(layer "B.Cu")
		(net 1)
	)
	(segment
		(start 145.2 113.15)
		(end 145.2 113.25)
		(width 0.15)
		(layer "B.Cu")
		(net 1)
	)
	(segment
		(start 38.608 118.341)
		(end 37.959 118.341)
		(width 0.3)
		(layer "B.Cu")
		(net 1)
	)
	(segment
		(start 67.735 109.185)
		(end 67.75 109.2)
		(width 0.15)
		(layer "B.Cu")
		(net 1)
	)
	(segment
		(start 98.885 84.25)
		(end 98.885 84.915)
		(width 0.155)
		(layer "B.Cu")
		(net 1)
	)
	(segment
		(start 123.1 95.76)
		(end 123.34 96)
		(width 0.3)
		(layer "B.Cu")
		(net 1)
	)
	(segment
		(start 58.15 111.45)
		(end 58.4 111.45)
		(width 0.15)
		(layer "B.Cu")
		(net 1)
	)
	(segment
		(start 108.676468 110.8875)
		(end 108.4875 110.8875)
		(width 0.15)
		(layer "B.Cu")
		(net 1)
	)
	(segment
		(start 123.1 95.441)
		(end 123.1 95.76)
		(width 0.3)
		(layer "B.Cu")
		(net 1)
	)
	(segment
		(start 93.15 86.335)
		(end 94.149999 86.335)
		(width 0.3)
		(layer "B.Cu")
		(net 1)
	)
	(segment
		(start 129.8 127.4)
		(end 129.725 127.475)
		(width 0.3)
		(layer "B.Cu")
		(net 1)
	)
	(segment
		(start 89.089 72.68)
		(end 89.21 72.68)
		(width 0.15)
		(layer "B.Cu")
		(net 1)
	)
	(segment
		(start 46.825 123.595)
		(end 47.175 123.945)
		(width 0.3)
		(layer "B.Cu")
		(net 1)
	)
	(segment
		(start 65.465 111.3)
		(end 64.925 110.76)
		(width 0.2)
		(layer "B.Cu")
		(net 1)
	)
	(segment
		(start 134.451 127.406)
		(end 134.451 127.949)
		(width 0.15)
		(layer "B.Cu")
		(net 1)
	)
	(segment
		(start 62.95 103.7)
		(end 63.59 103.7)
		(width 0.15)
		(layer "B.Cu")
		(net 1)
	)
	(segment
		(start 74.2 81.7)
		(end 73.8 81.3)
		(width 0.3)
		(layer "B.Cu")
		(net 1)
	)
	(segment
		(start 134.275 128.125)
		(end 133.65 128.125)
		(width 0.15)
		(layer "B.Cu")
		(net 1)
	)
	(segment
		(start 145.1 113.25)
		(end 145.2 113.15)
		(width 0.15)
		(layer "B.Cu")
		(net 1)
	)
	(segment
		(start 143.15 86.5)
		(end 142.43 86.5)
		(width 0.15)
		(layer "B.Cu")
		(net 1)
	)
	(segment
		(start 133.69 70.89)
		(end 133.69 72.1325)
		(width 0.15)
		(layer "B.Cu")
		(net 1)
	)
	(segment
		(start 61.3 110.2)
		(end 61.55 109.95)
		(width 0.3)
		(layer "B.Cu")
		(net 1)
	)
	(segment
		(start 113.35 95.45)
		(end 113.8 95)
		(width 0.3)
		(layer "B.Cu")
		(net 1)
	)
	(segment
		(start 142.4 95.5)
		(end 143.15 95.5)
		(width 0.3)
		(layer "B.Cu")
		(net 1)
	)
	(segment
		(start 93.650167 78.750167)
		(end 93.8 78.9)
		(width 0.3)
		(layer "B.Cu")
		(net 1)
	)
	(segment
		(start 137.36 104.015)
		(end 137.325 104.05)
		(width 0.15)
		(layer "B.Cu")
		(net 1)
	)
	(segment
		(start 124.325 81.375)
		(end 124.325 82)
		(width 0.3)
		(layer "B.Cu")
		(net 1)
	)
	(segment
		(start 56.083 113.575)
		(end 55.2 113.575)
		(width 0.3)
		(layer "B.Cu")
		(net 1)
	)
	(segment
		(start 48.1 122.3)
		(end 48.085 122.285)
		(width 0.2)
		(layer "B.Cu")
		(net 1)
	)
	(segment
		(start 125.29 89.5)
		(end 125.63 89.16)
		(width 0.3)
		(layer "B.Cu")
		(net 1)
	)
	(segment
		(start 105.515 91.155)
		(end 105.72 90.95)
		(width 0.3)
		(layer "B.Cu")
		(net 1)
	)
	(segment
		(start 89.75 81.3)
		(end 90.415 81.3)
		(width 0.125)
		(layer "B.Cu")
		(net 1)
	)
	(segment
		(start 45.478 71.551145)
		(end 47.02 73.093145)
		(width 0.15)
		(layer "B.Cu")
		(net 1)
	)
	(segment
		(start 124.325 89.5)
		(end 125.29 89.5)
		(width 0.3)
		(layer "B.Cu")
		(net 1)
	)
	(segment
		(start 140.58 124.82)
		(end 139.53 124.82)
		(width 0.3)
		(layer "B.Cu")
		(net 1)
	)
	(segment
		(start 57.9 106.4)
		(end 57.9 106.885)
		(width 0.2)
		(layer "B.Cu")
		(net 1)
	)
	(segment
		(start 137.534 113.416)
		(end 137.25 113.7)
		(width 0.5)
		(layer "B.Cu")
		(net 1)
	)
	(segment
		(start 95.525 99.475)
		(end 95.525 98.98)
		(width 0.13)
		(layer "B.Cu")
		(net 1)
	)
	(segment
		(start 65.2 74.3)
		(end 65.2 75.115)
		(width 0.15)
		(layer "B.Cu")
		(net 1)
	)
	(segment
		(start 90.415 81.3)
		(end 90.515 81.4)
		(width 0.125)
		(layer "B.Cu")
		(net 1)
	)
	(segment
		(start 110.2 92.02)
		(end 109.43 92.02)
		(width 0.15)
		(layer "B.Cu")
		(net 1)
	)
	(segment
		(start 134.451 127.949)
		(end 134.275 128.125)
		(width 0.15)
		(layer "B.Cu")
		(net 1)
	)
	(segment
		(start 66.8625 81.75)
		(end 66.92 81.6925)
		(width 0.15)
		(layer "B.Cu")
		(net 1)
	)
	(segment
		(start 83.91 125.8895)
		(end 83.909 125.8885)
		(width 0.15)
		(layer "B.Cu")
		(net 1)
	)
	(segment
		(start 89.21 72.68)
		(end 89.505 72.975)
		(width 0.15)
		(layer "B.Cu")
		(net 1)
	)
	(segment
		(start 55.25 83.23)
		(end 55.25 83.275)
		(width 0.15)
		(layer "B.Cu")
		(net 1)
	)
	(segment
		(start 80.505 74.255)
		(end 80.505 73.55)
		(width 0.3)
		(layer "B.Cu")
		(net 1)
	)
	(segment
		(start 72.212 102.65)
		(end 72.212 101.963)
		(width 0.3)
		(layer "B.Cu")
		(net 1)
	)
	(segment
		(start 115.21 81.65)
		(end 115.21 80.525)
		(width 0.3)
		(layer "B.Cu")
		(net 1)
	)
	(segment
		(start 73.55 79.45)
		(end 72.825 79.45)
		(width 0.3)
		(layer "B.Cu")
		(net 1)
	)
	(segment
		(start 98.115 75.25)
		(end 98.115 75.815)
		(width 0.3)
		(layer "B.Cu")
		(net 1)
	)
	(segment
		(start 52.475 79.125)
		(end 52.475 79.575)
		(width 0.15)
		(layer "B.Cu")
		(net 1)
	)
	(segment
		(start 57.01 119.9)
		(end 57.01 121.15)
		(width 0.3)
		(layer "B.Cu")
		(net 1)
	)
	(segment
		(start 47.02 73.093145)
		(end 47.02 73.475)
		(width 0.15)
		(layer "B.Cu")
		(net 1)
	)
	(segment
		(start 67.7 111.3)
		(end 68.2 110.8)
		(width 0.2)
		(layer "B.Cu")
		(net 1)
	)
	(segment
		(start 71.65 81.3)
		(end 71.5 81.3)
		(width 0.2)
		(layer "B.Cu")
		(net 1)
	)
	(segment
		(start 67.455476 86.05)
		(end 67.1475 86.357976)
		(width 0.155)
		(layer "B.Cu")
		(net 1)
	)
	(segment
		(start 145.2 113.25)
		(end 145.05 113.25)
		(width 0.15)
		(layer "B.Cu")
		(net 1)
	)
	(segment
		(start 119.95 127.75)
		(end 119.95 127.15)
		(width 0.125)
		(layer "B.Cu")
		(net 1)
	)
	(segment
		(start 76.738028 78.150119)
		(end 76.22 78.668147)
		(width 0.3)
		(layer "B.Cu")
		(net 1)
	)
	(segment
		(start 40.241 118.341)
		(end 40.3 118.4)
		(width 0.3)
		(layer "B.Cu")
		(net 1)
	)
	(segment
		(start 94.75 86.65)
		(end 94.464999 86.65)
		(width 0.3)
		(layer "B.Cu")
		(net 1)
	)
	(segment
		(start 109.1 71.8)
		(end 109.1 71.75)
		(width 0.15)
		(layer "B.Cu")
		(net 1)
	)
	(segment
		(start 76.365 106.15)
		(end 76 105.785)
		(width 0.15)
		(layer "B.Cu")
		(net 1)
	)
	(segment
		(start 75.44 112.2)
		(end 75.19 112.45)
		(width 0.15)
		(layer "B.Cu")
		(net 1)
	)
	(segment
		(start 95.805 100.525)
		(end 96.115 100.525)
		(width 0.3)
		(layer "B.Cu")
		(net 1)
	)
	(segment
		(start 55.25 83.23)
		(end 55.192764 83.23)
		(width 0.15)
		(layer "B.Cu")
		(net 1)
	)
	(segment
		(start 72.285 102.28)
		(end 71.7 102.865)
		(width 0.2)
		(layer "B.Cu")
		(net 1)
	)
	(segment
		(start 74.775 80.1)
		(end 73.8 80.1)
		(width 0.3)
		(layer "B.Cu")
		(net 1)
	)
	(segment
		(start 72.825 79.45)
		(end 73.25 79.45)
		(width 0.3)
		(layer "B.Cu")
		(net 1)
	)
	(segment
		(start 77.25 106.15)
		(end 76.365 106.15)
		(width 0.15)
		(layer "B.Cu")
		(net 1)
	)
	(segment
		(start 70.8 75.6)
		(end 70.8 75.8)
		(width 0.15)
		(layer "B.Cu")
		(net 1)
	)
	(segment
		(start 139.4 99.7)
		(end 139.4 100.075)
		(width 0.3)
		(layer "B.Cu")
		(net 1)
	)
	(segment
		(start 54.025 113.575)
		(end 53.825 113.575)
		(width 0.15)
		(layer "B.Cu")
		(net 1)
	)
	(segment
		(start 145.2 112.5)
		(end 145.2 113.15)
		(width 0.15)
		(layer "B.Cu")
		(net 1)
	)
	(segment
		(start 47.825 122.575)
		(end 47.825 122.97)
		(width 0.15)
		(layer "B.Cu")
		(net 1)
	)
	(segment
		(start 74.99 73.298502)
		(end 74.555 72.863502)
		(width 0.15)
		(layer "B.Cu")
		(net 1)
	)
	(segment
		(start 145.05 113.25)
		(end 144.75 113.25)
		(width 0.15)
		(layer "B.Cu")
		(net 1)
	)
	(segment
		(start 53.4 118.615)
		(end 53.4 119.385)
		(width 0.3)
		(layer "B.Cu")
		(net 1)
	)
	(segment
		(start 38.608 118.341)
		(end 39.608 118.341)
		(width 0.3)
		(layer "B.Cu")
		(net 1)
	)
	(segment
		(start 139.285 123)
		(end 139.285 122.97)
		(width 0.15)
		(layer "B.Cu")
		(net 1)
	)
	(segment
		(start 123.25 92.5)
		(end 124.325 92.5)
		(width 0.3)
		(layer "B.Cu")
		(net 1)
	)
	(segment
		(start 138.15 117.55)
		(end 137.7 118)
		(width 0.125)
		(layer "B.Cu")
		(net 1)
	)
	(segment
		(start 85.179 124.6195)
		(end 85.179 123.921)
		(width 0.15)
		(layer "B.Cu")
		(net 1)
	)
	(segment
		(start 133.9 114.1245)
		(end 133.9 112.7)
		(width 0.5)
		(layer "B.Cu")
		(net 1)
	)
	(segment
		(start 113.76 78.6)
		(end 113.76 77.96)
		(width 0.3)
		(layer "B.Cu")
		(net 1)
	)
	(segment
		(start 64.56 73.35)
		(end 64.685 73.225)
		(width 0.15)
		(layer "B.Cu")
		(net 1)
	)
	(segment
		(start 123.24 85)
		(end 124.325 85)
		(width 0.3)
		(layer "B.Cu")
		(net 1)
	)
	(segment
		(start 65.9 76.5)
		(end 65.785 76.5)
		(width 0.15)
		(layer "B.Cu")
		(net 1)
	)
	(segment
		(start 95.352278 100.072278)
		(end 95.805 100.525)
		(width 0.3)
		(layer "B.Cu")
		(net 1)
	)
	(segment
		(start 138.165 117.55)
		(end 138.15 117.55)
		(width 0.125)
		(layer "B.Cu")
		(net 1)
	)
	(segment
		(start 83.91 126.7275)
		(end 83.91 125.8895)
		(width 0.15)
		(layer "B.Cu")
		(net 1)
	)
	(segment
		(start 134.85 123.6)
		(end 133.3 123.6)
		(width 0.3)
		(layer "B.Cu")
		(net 1)
	)
	(segment
		(start 61.55 109.95)
		(end 61.55 109.685)
		(width 0.3)
		(layer "B.Cu")
		(net 1)
	)
	(segment
		(start 123.28 88)
		(end 124.325 88)
		(width 0.3)
		(layer "B.Cu")
		(net 1)
	)
	(segment
		(start 69.01 103.7)
		(end 68.56 103.25)
		(width 0.15)
		(layer "B.Cu")
		(net 1)
	)
	(segment
		(start 71.665 81.465)
		(end 71.5 81.3)
		(width 0.2)
		(layer "B.Cu")
		(net 1)
	)
	(segment
		(start 128.6 94.9)
		(end 128.85 95.15)
		(width 0.15)
		(layer "B.Cu")
		(net 1)
	)
	(segment
		(start 75 114.6)
		(end 75 115.285)
		(width 0.15)
		(layer "B.Cu")
		(net 1)
	)
	(segment
		(start 101.15 123.8)
		(end 101.15 123.15)
		(width 0.2)
		(layer "B.Cu")
		(net 1)
	)
	(segment
		(start 89.505 72.975)
		(end 89.505 73.55)
		(width 0.15)
		(layer "B.Cu")
		(net 1)
	)
	(segment
		(start 62.55 74.35)
		(end 63.55 73.35)
		(width 0.3)
		(layer "B.Cu")
		(net 1)
	)
	(segment
		(start 123.25 89.49)
		(end 123.26 89.5)
		(width 0.3)
		(layer "B.Cu")
		(net 1)
	)
	(segment
		(start 68.165 77.915)
		(end 68.165 78.71)
		(width 0.3)
		(layer "B.Cu")
		(net 1)
	)
	(segment
		(start 98.115 75.815)
		(end 98.2 75.9)
		(width 0.3)
		(layer "B.Cu")
		(net 1)
	)
	(segment
		(start 45.1 69.8)
		(end 44.275 69.8)
		(width 0.15)
		(layer "B.Cu")
		(net 1)
	)
	(segment
		(start 47.175 123.945)
		(end 47.175 124.92)
		(width 0.155)
		(layer "B.Cu")
		(net 1)
	)
	(segment
		(start 106.640585 86.259415)
		(end 106.49 86.41)
		(width 0.3)
		(layer "B.Cu")
		(net 1)
	)
	(segment
		(start 56.173952 76.851048)
		(end 55.825 77.2)
		(width 0.15)
		(layer "B.Cu")
		(net 1)
	)
	(segment
		(start 57.345 121.36)
		(end 57.92 121.935)
		(width 0.5)
		(layer "B.Cu")
		(net 1)
	)
	(segment
		(start 49.27 115.03)
		(end 48.323 115.977)
		(width 0.15)
		(layer "B.Cu")
		(net 1)
	)
	(segment
		(start 97.75 79.3)
		(end 98.25 79.3)
		(width 0.3)
		(layer "B.Cu")
		(net 1)
	)
	(segment
		(start 133.515 116.55)
		(end 133.515 117.13)
		(width 0.125)
		(layer "B.Cu")
		(net 1)
	)
	(segment
		(start 81.509753 74.539999)
		(end 81.584752 74.465)
		(width 0.3)
		(layer "B.Cu")
		(net 1)
	)
	(segment
		(start 49.5125 112.974001)
		(end 49.265 113.221501)
		(width 0.3)
		(layer "B.Cu")
		(net 1)
	)
	(segment
		(start 49.15 119.548)
		(end 49.752 119.548)
		(width 0.15)
		(layer "B.Cu")
		(net 1)
	)
	(segment
		(start 63.55 74.35)
		(end 62.55 73.35)
		(width 0.3)
		(layer "B.Cu")
		(net 1)
	)
	(segment
		(start 55.25 83.275)
		(end 54.925 83.6)
		(width 0.15)
		(layer "B.Cu")
		(net 1)
	)
	(segment
		(start 111.872 83)
		(end 111.089 83.783)
		(width 0.3)
		(layer "B.Cu")
		(net 1)
	)
	(segment
		(start 48.085 122.285)
		(end 48.085 121.7)
		(width 0.2)
		(layer "B.Cu")
		(net 1)
	)
	(segment
		(start 137.185 117.55)
		(end 137.25 117.55)
		(width 0.3)
		(layer "B.Cu")
		(net 1)
	)
	(segment
		(start 138.315 122)
		(end 137.7 122)
		(width 0.15)
		(layer "B.Cu")
		(net 1)
	)
	(segment
		(start 91.005 74.495)
		(end 91.005 73.55)
		(width 0.15)
		(layer "B.Cu")
		(net 1)
	)
	(segment
		(start 143.15 91)
		(end 142.45 91)
		(width 0.15)
		(layer "B.Cu")
		(net 1)
	)
	(segment
		(start 65.11 102.18)
		(end 65.11 102.05)
		(width 0.15)
		(layer "B.Cu")
		(net 1)
	)
	(segment
		(start 51.75 71.34)
		(end 51.6 71.19)
		(width 0.15)
		(layer "B.Cu")
		(net 1)
	)
	(segment
		(start 141.5 124.96)
		(end 141.36 124.82)
		(width 0.3)
		(layer "B.Cu")
		(net 1)
	)
	(segment
		(start 49.265 113.221501)
		(end 49.265 115)
		(width 0.3)
		(layer "B.Cu")
		(net 1)
	)
	(segment
		(start 69.9 75.3)
		(end 70.5 75.3)
		(width 0.15)
		(layer "B.Cu")
		(net 1)
	)
	(segment
		(start 67.425 127.57)
		(end 67.065 127.21)
		(width 0.15)
		(layer "B.Cu")
		(net 1)
	)
	(segment
		(start 81.584752 74.465)
		(end 81.712054 74.465)
		(width 0.3)
		(layer "B.Cu")
		(net 1)
	)
	(segment
		(start 123.1 95.441)
		(end 123.159 95.5)
		(width 0.3)
		(layer "B.Cu")
		(net 1)
	)
	(segment
		(start 98.885 84.915)
		(end 98.3715 85.4285)
		(width 0.155)
		(layer "B.Cu")
		(net 1)
	)
	(segment
		(start 123.2 90.95)
		(end 124.275 90.95)
		(width 0.3)
		(layer "B.Cu")
		(net 1)
	)
	(segment
		(start 52.475 79.575)
		(end 52.65 79.75)
		(width 0.15)
		(layer "B.Cu")
		(net 1)
	)
	(segment
		(start 71.685 81.265)
		(end 71.685 81.465)
		(width 0.2)
		(layer "B.Cu")
		(net 1)
	)
	(segment
		(start 117.14 70.74)
		(end 117.35 70.95)
		(width 0.125)
		(layer "B.Cu")
		(net 1)
	)
	(segment
		(start 139.53 126.6)
		(end 139.53 124.82)
		(width 0.3)
		(layer "B.Cu")
		(net 1)
	)
	(segment
		(start 68.56 103.25)
		(end 67.621 103.25)
		(width 0.15)
		(layer "B.Cu")
		(net 1)
	)
	(segment
		(start 125.5 83.5)
		(end 125.56 83.56)
		(width 0.3)
		(layer "B.Cu")
		(net 1)
	)
	(segment
		(start 124.35 81.35)
		(end 124.325 81.375)
		(width 0.3)
		(layer "B.Cu")
		(net 1)
	)
	(segment
		(start 134.435 118.05)
		(end 133.935 117.55)
		(width 0.3)
		(layer "B.Cu")
		(net 1)
	)
	(segment
		(start 57.035 106.855)
		(end 57.035 107.26)
		(width 0.2)
		(layer "B.Cu")
		(net 1)
	)
	(segment
		(start 98.5 79.05)
		(end 98.5 78.75)
		(width 0.3)
		(layer "B.Cu")
		(net 1)
	)
	(segment
		(start 66.865 97.565)
		(end 66.075 97.565)
		(width 0.15)
		(layer "B.Cu")
		(net 1)
	)
	(segment
		(start 58.4 79)
		(end 59.365 79)
		(width 0.15)
		(layer "B.Cu")
		(net 1)
	)
	(segment
		(start 123.26 86.5)
		(end 123.24 86.48)
		(width 0.3)
		(layer "B.Cu")
		(net 1)
	)
	(segment
		(start 65.9255 109.1455)
		(end 65.55 108.77)
		(width 0.15)
		(layer "B.Cu")
		(net 1)
	)
	(segment
		(start 84.375 100.84)
		(end 84.375 99.99)
		(width 0.15)
		(layer "B.Cu")
		(net 1)
	)
	(segment
		(start 108.215 110.3)
		(end 108.2 110.285)
		(width 0.15)
		(layer "B.Cu")
		(net 1)
	)
	(segment
		(start 123.26 89.5)
		(end 124.325 89.5)
		(width 0.3)
		(layer "B.Cu")
		(net 1)
	)
	(segment
		(start 105.08 70.77)
		(end 103.885 70.77)
		(width 0.15)
		(layer "B.Cu")
		(net 1)
	)
	(segment
		(start 115.8535 118.4835)
		(end 115.8535 117.825)
		(width 0.2)
		(layer "B.Cu")
		(net 1)
	)
	(segment
		(start 87.6 108.2345)
		(end 87.5655 108.2)
		(width 0.155)
		(layer "B.Cu")
		(net 1)
	)
	(segment
		(start 75.235 120.585)
		(end 74.75 120.1)
		(width 0.15)
		(layer "B.Cu")
		(net 1)
	)
	(segment
		(start 108.4875 110.8875)
		(end 108.215 110.615)
		(width 0.15)
		(layer "B.Cu")
		(net 1)
	)
	(segment
		(start 53.9 82.6)
		(end 53.3 83.2)
		(width 0.15)
		(layer "B.Cu")
		(net 1)
	)
	(segment
		(start 124.325 91)
		(end 125.32 91)
		(width 0.3)
		(layer "B.Cu")
		(net 1)
	)
	(segment
		(start 96.985 85.288)
		(end 96.985 84.75)
		(width 0.3)
		(layer "B.Cu")
		(net 1)
	)
	(segment
		(start 80.77 74.52)
		(end 80.505 74.255)
		(width 0.3)
		(layer "B.Cu")
		(net 1)
	)
	(segment
		(start 61.115 107.685)
		(end 61.5 107.685)
		(width 0.3)
		(layer "B.Cu")
		(net 1)
	)
	(segment
		(start 58.9 74.715)
		(end 58.9 73.715)
		(width 0.125)
		(layer "B.Cu")
		(net 1)
	)
	(segment
		(start 54.562764 82.6)
		(end 53.9 82.6)
		(width 0.15)
		(layer "B.Cu")
		(net 1)
	)
	(segment
		(start 142.43 86.5)
		(end 142.42 86.49)
		(width 0.15)
		(layer "B.Cu")
		(net 1)
	)
	(segment
		(start 45.51 70.21)
		(end 45.1 69.8)
		(width 0.15)
		(layer "B.Cu")
		(net 1)
	)
	(segment
		(start 128.6 94.5)
		(end 128.6 94.9)
		(width 0.15)
		(layer "B.Cu")
		(net 1)
	)
	(segment
		(start 143.15 97)
		(end 142.42 97)
		(width 0.15)
		(layer "B.Cu")
		(net 1)
	)
	(segment
		(start 123.159 95.5)
		(end 125.4 95.5)
		(width 0.3)
		(layer "B.Cu")
		(net 1)
	)
	(segment
		(start 71.685 81.115)
		(end 71.5 81.3)
		(width 0.2)
		(layer "B.Cu")
		(net 1)
	)
	(segment
		(start 125.58 96.83)
		(end 123.82 96.83)
		(width 0.3)
		(layer "B.Cu")
		(net 1)
	)
	(segment
		(start 71.898 72.898)
		(end 72.3 73.3)
		(width 0.15)
		(layer "B.Cu")
		(net 1)
	)
	(segment
		(start 137.2 108.0255)
		(end 137.7905 108.0255)
		(width 0.3)
		(layer "B.Cu")
		(net 1)
	)
	(segment
		(start 125.53 88)
		(end 124.325 88)
		(width 0.3)
		(layer "B.Cu")
		(net 1)
	)
	(segment
		(start 53.4 113.25)
		(end 53.7 113.25)
		(width 0.3)
		(layer "B.Cu")
		(net 1)
	)
	(segment
		(start 139.25 99.55)
		(end 139.4 99.7)
		(width 0.3)
		(layer "B.Cu")
		(net 1)
	)
	(segment
		(start 67.805 86.05)
		(end 67.455476 86.05)
		(width 0.155)
		(layer "B.Cu")
		(net 1)
	)
	(segment
		(start 105.515 92.02)
		(end 105.515 91.155)
		(width 0.3)
		(layer "B.Cu")
		(net 1)
	)
	(segment
		(start 131.15 95.2)
		(end 130.6 94.65)
		(width 0.15)
		(layer "B.Cu")
		(net 1)
	)
	(segment
		(start 145.05 113.25)
		(end 145.1 113.25)
		(width 0.15)
		(layer "B.Cu")
		(net 1)
	)
	(segment
		(start 108.4 71.05)
		(end 106.92 71.05)
		(width 0.15)
		(layer "B.Cu")
		(net 1)
	)
	(segment
		(start 115.195585 81.664415)
		(end 115.21 81.65)
		(width 0.3)
		(layer "B.Cu")
		(net 1)
	)
	(segment
		(start 39.608 118.341)
		(end 40.241 118.341)
		(width 0.3)
		(layer "B.Cu")
		(net 1)
	)
	(segment
		(start 70.7 75.9)
		(end 70.8 75.8)
		(width 0.15)
		(layer "B.Cu")
		(net 1)
	)
	(segment
		(start 63.55 73.85)
		(end 62.55 73.85)
		(width 0.3)
		(layer "B.Cu")
		(net 1)
	)
	(segment
		(start 64.685 73.225)
		(end 66.545 73.225)
		(width 0.15)
		(layer "B.Cu")
		(net 1)
	)
	(segment
		(start 55.2 113.575)
		(end 53.825 113.575)
		(width 0.3)
		(layer "B.Cu")
		(net 1)
	)
	(segment
		(start 53.4 113.25)
		(end 53.725 113.575)
		(width 0.2)
		(layer "B.Cu")
		(net 1)
	)
	(segment
		(start 57.9 106.4)
		(end 57.49 106.4)
		(width 0.2)
		(layer "B.Cu")
		(net 1)
	)
	(segment
		(start 142.38 95.52)
		(end 142.4 95.5)
		(width 0.3)
		(layer "B.Cu")
		(net 1)
	)
	(segment
		(start 125.32 91)
		(end 125.67 91.35)
		(width 0.3)
		(layer "B.Cu")
		(net 1)
	)
	(segment
		(start 68.2 110.8)
		(end 68.2 110.735)
		(width 0.2)
		(layer "B.Cu")
		(net 1)
	)
	(segment
		(start 125.57 86)
		(end 125.57 86.33)
		(width 0.3)
		(layer "B.Cu")
		(net 1)
	)
	(segment
		(start 63.46 86.06)
		(end 63.46 85.06)
		(width 0.3)
		(layer "B.Cu")
		(net 1)
	)
	(segment
		(start 98.3715 85.4285)
		(end 97.1255 85.4285)
		(width 0.155)
		(layer "B.Cu")
		(net 1)
	)
	(segment
		(start 58.25 73.55)
		(end 58.735 73.55)
		(width 0.15)
		(layer "B.Cu")
		(net 1)
	)
	(segment
		(start 131.45 95.2)
		(end 131.15 95.2)
		(width 0.15)
		(layer "B.Cu")
		(net 1)
	)
	(segment
		(start 49.752 119.548)
		(end 49.9 119.4)
		(width 0.15)
		(layer "B.Cu")
		(net 1)
	)
	(segment
		(start 40.7 82.2)
		(end 40.75 82.25)
		(width 0.15)
		(layer "B.Cu")
		(net 1)
	)
	(segment
		(start 139.775 100.425)
		(end 139.75 100.425)
		(width 0.3)
		(layer "B.Cu")
		(net 1)
	)
	(segment
		(start 47.32 112.68)
		(end 47.243974 112.68)
		(width 0.15)
		(layer "B.Cu")
		(net 1)
	)
	(segment
		(start 102.78 100.53)
		(end 102.25 100)
		(width 0.15)
		(layer "B.Cu")
		(net 1)
	)
	(segment
		(start 112.1 83)
		(end 111.872 83)
		(width 0.3)
		(layer "B.Cu")
		(net 1)
	)
	(segment
		(start 143.15 89.5)
		(end 144.95 89.5)
		(width 0.15)
		(layer "B.Cu")
		(net 1)
	)
	(segment
		(start 75.19 112.45)
		(end 75.01 112.45)
		(width 0.15)
		(layer "B.Cu")
		(net 1)
	)
	(segment
		(start 138.24 126.6)
		(end 139.53 126.6)
		(width 0.15)
		(layer "B.Cu")
		(net 1)
	)
	(segment
		(start 125.37 85.07)
		(end 125.3 85)
		(width 0.3)
		(layer "B.Cu")
		(net 1)
	)
	(segment
		(start 72.285 101.9)
		(end 72.285 102.28)
		(width 0.2)
		(layer "B.Cu")
		(net 1)
	)
	(segment
		(start 48.1 122.3)
		(end 48.03 122.23)
		(width 0.15)
		(layer "B.Cu")
		(net 1)
	)
	(segment
		(start 145 108.95)
		(end 145 111)
		(width 0.3)
		(layer "B.Cu")
		(net 1)
	)
	(segment
		(start 38.3 113.85)
		(end 38.29 113.84)
		(width 0.5)
		(layer "B.Cu")
		(net 1)
	)
	(segment
		(start 98.25 79.3)
		(end 98.5 79.05)
		(width 0.3)
		(layer "B.Cu")
		(net 1)
	)
	(segment
		(start 53.7 113.25)
		(end 54.025 113.575)
		(width 0.3)
		(layer "B.Cu")
		(net 1)
	)
	(segment
		(start 66.92 81.6925)
		(end 66.92 81.43)
		(width 0.15)
		(layer "B.Cu")
		(net 1)
	)
	(segment
		(start 81.3685 125.8885)
		(end 81.37 125.8885)
		(width 0.15)
		(layer "B.Cu")
		(net 1)
	)
	(segment
		(start 108.215 110.615)
		(end 108.215 110.3)
		(width 0.15)
		(layer "B.Cu")
		(net 1)
	)
	(segment
		(start 51.785 116.315)
		(end 51.45 116.65)
		(width 0.15)
		(layer "B.Cu")
		(net 1)
	)
	(segment
		(start 60.35 72.6)
		(end 60.35 72.1)
		(width 0.15)
		(layer "B.Cu")
		(net 1)
	)
	(segment
		(start 137.215 117.52)
		(end 137.185 117.55)
		(width 0.125)
		(layer "B.Cu")
		(net 1)
	)
	(segment
		(start 140.115 97.55)
		(end 140.55 97.55)
		(width 0.3)
		(layer "B.Cu")
		(net 1)
	)
	(segment
		(start 110.04 88.02)
		(end 109.04 87.02)
		(width 0.15)
		(layer "B.Cu")
		(net 1)
	)
	(segment
		(start 91.72 75.31)
		(end 91.68 75.27)
		(width 0.15)
		(layer "B.Cu")
		(net 1)
	)
	(segment
		(start 145.2 113.25)
		(end 145.2 113.4)
		(width 0.15)
		(layer "B.Cu")
		(net 1)
	)
	(segment
		(start 52.94 83.03)
		(end 52.94 82.53)
		(width 0.15)
		(layer "B.Cu")
		(net 1)
	)
	(segment
		(start 116.2 119.45)
		(end 116.2 118.83)
		(width 0.2)
		(layer "B.Cu")
		(net 1)
	)
	(segment
		(start 55.192764 83.23)
		(end 54.562764 82.6)
		(width 0.15)
		(layer "B.Cu")
		(net 1)
	)
	(segment
		(start 125.3 85)
		(end 124.325 85)
		(width 0.3)
		(layer "B.Cu")
		(net 1)
	)
	(segment
		(start 88.392947 102.757053)
		(end 87.265894 101.63)
		(width 0.13)
		(layer "B.Cu")
		(net 1)
	)
	(segment
		(start 125.59 94)
		(end 125.6 93.99)
		(width 0.3)
		(layer "B.Cu")
		(net 1)
	)
	(segment
		(start 97.1255 85.4285)
		(end 96.985 85.288)
		(width 0.3)
		(layer "B.Cu")
		(net 1)
	)
	(segment
		(start 52.65 79.75)
		(end 52.65 80.175)
		(width 0.15)
		(layer "B.Cu")
		(net 1)
	)
	(segment
		(start 137.215 116.55)
		(end 137.215 117.52)
		(width 0.125)
		(layer "B.Cu")
		(net 1)
	)
	(segment
		(start 124.325 92.5)
		(end 125.46 92.5)
		(width 0.3)
		(layer "B.Cu")
		(net 1)
	)
	(segment
		(start 31.5 70.2)
		(end 31.5 71.4)
		(width 0.5)
		(layer "B.Cu")
		(net 1)
	)
	(segment
		(start 67.065 127.21)
		(end 67.065 126.755)
		(width 0.15)
		(layer "B.Cu")
		(net 1)
	)
	(segment
		(start 48.202 74.95)
		(end 47.725 74.95)
		(width 0.15)
		(layer "B.Cu")
		(net 1)
	)
	(segment
		(start 61.9 76.3)
		(end 61.9 75)
		(width 0.3)
		(layer "B.Cu")
		(net 1)
	)
	(segment
		(start 108.2 110.285)
		(end 108.2 109.25)
		(width 0.15)
		(layer "B.Cu")
		(net 1)
	)
	(segment
		(start 72.285 100.95)
		(end 72.285 101.9)
		(width 0.3)
		(layer "B.Cu")
		(net 1)
	)
	(segment
		(start 61.1 107.7)
		(end 61.115 107.685)
		(width 0.3)
		(layer "B.Cu")
		(net 1)
	)
	(segment
		(start 53.4 119.385)
		(end 53.4 120.05)
		(width 0.3)
		(layer "B.Cu")
		(net 1)
	)
	(segment
		(start 56.27 113.388)
		(end 56.083 113.575)
		(width 0.3)
		(layer "B.Cu")
		(net 1)
	)
	(segment
		(start 139.75 100.425)
		(end 139.4 100.075)
		(width 0.3)
		(layer "B.Cu")
		(net 1)
	)
	(segment
		(start 138.14 126.7)
		(end 138.24 126.6)
		(width 0.15)
		(layer "B.Cu")
		(net 1)
	)
	(segment
		(start 48.323 115.977)
		(end 48.323 116.1)
		(width 0.15)
		(layer "B.Cu")
		(net 1)
	)
	(segment
		(start 45.51 71.51)
		(end 45.51 70.21)
		(width 0.15)
		(layer "B.Cu")
		(net 1)
	)
	(segment
		(start 74.555 72.863502)
		(end 74.555 71.45)
		(width 0.15)
		(layer "B.Cu")
		(net 1)
	)
	(segment
		(start 71.685 81.085)
		(end 71.685 81.115)
		(width 0.2)
		(layer "B.Cu")
		(net 1)
	)
	(segment
		(start 125.496823 75.014603)
		(end 125.496823 73.418137)
		(width 0.155)
		(layer "F.Cu")
		(net 2)
	)
	(segment
		(start 121.89 74.76)
		(end 121.2005 75.4495)
		(width 0.155)
		(layer "F.Cu")
		(net 2)
	)
	(segment
		(start 125.496823 73.418137)
		(end 125.597323 73.317637)
		(width 0.155)
		(layer "F.Cu")
		(net 2)
	)
	(segment
		(start 121.2005 76.161926)
		(end 121.588074 76.5495)
		(width 0.155)
		(layer "F.Cu")
		(net 2)
	)
	(segment
		(start 121.2005 75.4495)
		(end 121.2005 76.161926)
		(width 0.155)
		(layer "F.Cu")
		(net 2)
	)
	(segment
		(start 125.597323 73.317637)
		(end 125.597323 72.005136)
		(width 0.155)
		(layer "F.Cu")
		(net 2)
	)
	(segment
		(start 123.961926 76.5495)
		(end 125.496823 75.014603)
		(width 0.155)
		(layer "F.Cu")
		(net 2)
	)
	(segment
		(start 121.588074 76.5495)
		(end 123.961926 76.5495)
		(width 0.155)
		(layer "F.Cu")
		(net 2)
	)
	(via
		(at 121.89 74.76)
		(size 0.45)
		(drill 0.1)
		(layers "F.Cu" "B.Cu")
		(net 2)
	)
	(segment
		(start 120.65 74.71)
		(end 121.53 74.71)
		(width 0.155)
		(layer "B.Cu")
		(net 2)
	)
	(segment
		(start 121.53 74.71)
		(end 121.58 74.76)
		(width 0.155)
		(layer "B.Cu")
		(net 2)
	)
	(segment
		(start 120.0507 74.5532)
		(end 120.4932 74.5532)
		(width 0.155)
		(layer "B.Cu")
		(net 2)
	)
	(segment
		(start 120.4932 74.5532)
		(end 120.65 74.71)
		(width 0.155)
		(layer "B.Cu")
		(net 2)
	)
	(segment
		(start 122.0868 74.5632)
		(end 122.7768 74.5632)
		(width 0.155)
		(layer "B.Cu")
		(net 2)
	)
	(segment
		(start 121.89 74.76)
		(end 122.0868 74.5632)
		(width 0.155)
		(layer "B.Cu")
		(net 2)
	)
	(segment
		(start 121.58 74.76)
		(end 121.89 74.76)
		(width 0.155)
		(layer "B.Cu")
		(net 2)
	)
	(segment
		(start 122.7768 74.5632)
		(end 122.78 74.56)
		(width 0.155)
		(layer "B.Cu")
		(net 2)
	)
	(segment
		(start 127.432006 81.706569)
		(end 127.218575 81.92)
		(width 0.155)
		(layer "F.Cu")
		(net 3)
	)
	(segment
		(start 125.246823 81.435397)
		(end 125.246823 80.305636)
		(width 0.155)
		(layer "F.Cu")
		(net 3)
	)
	(segment
		(start 125.731426 81.92)
		(end 125.246823 81.435397)
		(width 0.155)
		(layer "F.Cu")
		(net 3)
	)
	(segment
		(start 127.432006 81.531259)
		(end 127.432006 81.706569)
		(width 0.155)
		(layer "F.Cu")
		(net 3)
	)
	(segment
		(start 127.218575 81.92)
		(end 125.731426 81.92)
		(width 0.155)
		(layer "F.Cu")
		(net 3)
	)
	(segment
		(start 125.246823 80.305636)
		(end 125.347323 80.205136)
		(width 0.155)
		(layer "F.Cu")
		(net 3)
	)
	(via
		(at 127.432006 81.531259)
		(size 0.45)
		(drill 0.1)
		(layers "F.Cu" "B.Cu")
		(net 3)
	)
	(segment
		(start 134.029 81.590499)
		(end 134.029 81.93)
		(width 0.155)
		(layer "B.Cu")
		(net 3)
	)
	(segment
		(start 127.432006 81.531259)
		(end 127.607316 81.531259)
		(width 0.155)
		(layer "B.Cu")
		(net 3)
	)
	(segment
		(start 135.844565 82.723961)
		(end 135.844566 82.72396)
		(width 0.155)
		(layer "B.Cu")
		(net 3)
	)
	(segment
		(start 143.0495 85.6005)
		(end 143.15 85.5)
		(width 0.155)
		(layer "B.Cu")
		(net 3)
	)
	(segment
		(start 129.041926 82.1805)
		(end 129.4795 82.1805)
		(width 0.155)
		(layer "B.Cu")
		(net 3)
	)
	(segment
		(start 142.138074 85.6005)
		(end 143.0495 85.6005)
		(width 0.155)
		(layer "B.Cu")
		(net 3)
	)
	(segment
		(start 132.93 83.069501)
		(end 132.93 81.590499)
		(width 0.155)
		(layer "B.Cu")
		(net 3)
	)
	(segment
		(start 128.311926 81.4505)
		(end 129.041926 82.1805)
		(width 0.155)
		(layer "B.Cu")
		(net 3)
	)
	(segment
		(start 127.607316 81.531259)
		(end 127.688075 81.4505)
		(width 0.155)
		(layer "B.Cu")
		(net 3)
	)
	(segment
		(start 135.543556 82.459286)
		(end 135.543555 82.459287)
		(width 0.155)
		(layer "B.Cu")
		(net 3)
	)
	(segment
		(start 136.9295 85.168074)
		(end 137.886926 86.1255)
		(width 0.155)
		(layer "B.Cu")
		(net 3)
	)
	(segment
		(start 131.33 83.069501)
		(end 131.33 81.590499)
		(width 0.155)
		(layer "B.Cu")
		(net 3)
	)
	(segment
		(start 127.688075 81.4505)
		(end 128.311926 81.4505)
		(width 0.155)
		(layer "B.Cu")
		(net 3)
	)
	(segment
		(start 134.2795 82.1805)
		(end 134.981926 82.1805)
		(width 0.155)
		(layer "B.Cu")
		(net 3)
	)
	(segment
		(start 135.826398 83.024971)
		(end 135.826397 83.024971)
		(width 0.155)
		(layer "B.Cu")
		(net 3)
	)
	(segment
		(start 137.886926 86.1255)
		(end 141.613074 86.1255)
		(width 0.155)
		(layer "B.Cu")
		(net 3)
	)
	(segment
		(start 136.9295 84.128074)
		(end 136.9295 85.168074)
		(width 0.155)
		(layer "B.Cu")
		(net 3)
	)
	(segment
		(start 135.826397 83.024971)
		(end 136.9295 84.128074)
		(width 0.155)
		(layer "B.Cu")
		(net 3)
	)
	(segment
		(start 132.429 81.590499)
		(end 132.429 83.069501)
		(width 0.155)
		(layer "B.Cu")
		(net 3)
	)
	(segment
		(start 135.543555 82.459287)
		(end 135.561724 82.441119)
		(width 0.155)
		(layer "B.Cu")
		(net 3)
	)
	(segment
		(start 130.829 81.590499)
		(end 130.829 83.069501)
		(width 0.155)
		(layer "B.Cu")
		(net 3)
	)
	(segment
		(start 135.844566 82.72396)
		(end 135.826398 82.742129)
		(width 0.155)
		(layer "B.Cu")
		(net 3)
	)
	(segment
		(start 129.73 81.93)
		(end 129.73 81.590499)
		(width 0.155)
		(layer "B.Cu")
		(net 3)
	)
	(segment
		(start 135.844566 82.441119)
		(end 135.844566 82.441118)
		(width 0.155)
		(layer "B.Cu")
		(net 3)
	)
	(segment
		(start 134.981926 82.1805)
		(end 135.260713 82.459287)
		(width 0.155)
		(layer "B.Cu")
		(net 3)
	)
	(segment
		(start 141.613074 86.1255)
		(end 142.138074 85.6005)
		(width 0.155)
		(layer "B.Cu")
		(net 3)
	)
	(arc
		(start 133.4795 81.040999)
		(mid 133.868055 81.201944)
		(end 134.029 81.590499)
		(width 0.155)
		(layer "B.Cu")
		(net 3)
	)
	(arc
		(start 130.829 83.069501)
		(mid 130.90237 83.246631)
		(end 131.0795 83.320001)
		(width 0.155)
		(layer "B.Cu")
		(net 3)
	)
	(arc
		(start 131.8795 81.040999)
		(mid 132.268055 81.201944)
		(end 132.429 81.590499)
		(width 0.155)
		(layer "B.Cu")
		(net 3)
	)
	(arc
		(start 129.4795 82.1805)
		(mid 129.65663 82.10713)
		(end 129.73 81.93)
		(width 0.155)
		(layer "B.Cu")
		(net 3)
	)
	(arc
		(start 135.561724 82.441119)
		(mid 135.703144 82.38254)
		(end 135.844566 82.441119)
		(width 0.155)
		(layer "B.Cu")
		(net 3)
	)
	(arc
		(start 134.029 81.93)
		(mid 134.10237 82.10713)
		(end 134.2795 82.1805)
		(width 0.155)
		(layer "B.Cu")
		(net 3)
	)
	(arc
		(start 135.260713 82.459287)
		(mid 135.402135 82.517865)
		(end 135.543556 82.459286)
		(width 0.155)
		(layer "B.Cu")
		(net 3)
	)
	(arc
		(start 129.73 81.590499)
		(mid 129.890945 81.201944)
		(end 130.2795 81.040999)
		(width 0.155)
		(layer "B.Cu")
		(net 3)
	)
	(arc
		(start 132.429 83.069501)
		(mid 132.50237 83.246631)
		(end 132.6795 83.320001)
		(width 0.155)
		(layer "B.Cu")
		(net 3)
	)
	(arc
		(start 135.826398 82.742129)
		(mid 135.767819 82.883549)
		(end 135.826398 83.024971)
		(width 0.155)
		(layer "B.Cu")
		(net 3)
	)
	(arc
		(start 131.0795 83.320001)
		(mid 131.25663 83.246631)
		(end 131.33 83.069501)
		(width 0.155)
		(layer "B.Cu")
		(net 3)
	)
	(arc
		(start 132.6795 83.320001)
		(mid 132.85663 83.246631)
		(end 132.93 83.069501)
		(width 0.155)
		(layer "B.Cu")
		(net 3)
	)
	(arc
		(start 130.2795 81.040999)
		(mid 130.668055 81.201944)
		(end 130.829 81.590499)
		(width 0.155)
		(layer "B.Cu")
		(net 3)
	)
	(arc
		(start 132.93 81.590499)
		(mid 133.090945 81.201944)
		(end 133.4795 81.040999)
		(width 0.155)
		(layer "B.Cu")
		(net 3)
	)
	(arc
		(start 135.844566 82.441118)
		(mid 135.903144 82.58254)
		(end 135.844565 82.723961)
		(width 0.155)
		(layer "B.Cu")
		(net 3)
	)
	(arc
		(start 131.33 81.590499)
		(mid 131.490945 81.201944)
		(end 131.8795 81.040999)
		(width 0.155)
		(layer "B.Cu")
		(net 3)
	)
	(segment
		(start 123.838074 76.2505)
		(end 121.711926 76.2505)
		(width 0.155)
		(layer "F.Cu")
		(net 4)
	)
	(segment
		(start 124.045819 75.044347)
		(end 124.4036 75.402128)
		(width 0.155)
		(layer "F.Cu")
		(net 4)
	)
	(segment
		(start 121.4995 75.57335)
		(end 121.74285 75.33)
		(width 0.155)
		(layer "F.Cu")
		(net 4)
	)
	(segment
		(start 125.197823 74.890751)
		(end 124.969287 75.119287)
		(width 0.155)
		(layer "F.Cu")
		(net 4)
	)
	(segment
		(start 124.686444 75.119287)
		(end 124.328662 74.761505)
		(width 0.155)
		(layer "F.Cu")
		(net 4)
	)
	(segment
		(start 125.097323 73.317637)
		(end 125.197823 73.418137)
		(width 0.155)
		(layer "F.Cu")
		(net 4)
	)
	(segment
		(start 121.711926 76.2505)
		(end 121.4995 76.038074)
		(width 0.155)
		(layer "F.Cu")
		(net 4)
	)
	(segment
		(start 121.4995 76.038074)
		(end 121.4995 75.57335)
		(width 0.155)
		(layer "F.Cu")
		(net 4)
	)
	(segment
		(start 125.197823 73.418137)
		(end 125.197823 74.890751)
		(width 0.155)
		(layer "F.Cu")
		(net 4)
	)
	(segment
		(start 124.403601 75.684971)
		(end 124.4036 75.684971)
		(width 0.155)
		(layer "F.Cu")
		(net 4)
	)
	(segment
		(start 124.686443 75.119287)
		(end 124.686444 75.119287)
		(width 0.155)
		(layer "F.Cu")
		(net 4)
	)
	(segment
		(start 124.045819 74.761504)
		(end 124.045819 74.761505)
		(width 0.155)
		(layer "F.Cu")
		(net 4)
	)
	(segment
		(start 125.097323 72.005136)
		(end 125.097323 73.317637)
		(width 0.155)
		(layer "F.Cu")
		(net 4)
	)
	(segment
		(start 121.74285 75.33)
		(end 122.02 75.33)
		(width 0.155)
		(layer "F.Cu")
		(net 4)
	)
	(segment
		(start 124.4036 75.684971)
		(end 123.838074 76.2505)
		(width 0.155)
		(layer "F.Cu")
		(net 4)
	)
	(via
		(at 122.02 75.33)
		(size 0.45)
		(drill 0.1)
		(layers "F.Cu" "B.Cu")
		(net 4)
	)
	(arc
		(start 124.969287 75.119287)
		(mid 124.827865 75.177866)
		(end 124.686443 75.119287)
		(width 0.155)
		(layer "F.Cu")
		(net 4)
	)
	(arc
		(start 124.328662 74.761505)
		(mid 124.187241 74.702926)
		(end 124.045819 74.761504)
		(width 0.155)
		(layer "F.Cu")
		(net 4)
	)
	(arc
		(start 124.045819 74.761505)
		(mid 123.987241 74.902926)
		(end 124.045819 75.044347)
		(width 0.155)
		(layer "F.Cu")
		(net 4)
	)
	(arc
		(start 124.4036 75.402128)
		(mid 124.462179 75.543549)
		(end 124.403601 75.684971)
		(width 0.155)
		(layer "F.Cu")
		(net 4)
	)
	(segment
		(start 122.3804 74.9696)
		(end 122.7704 74.9696)
		(width 0.155)
		(layer "B.Cu")
		(net 4)
	)
	(segment
		(start 122.02 75.33)
		(end 122.3804 74.9696)
		(width 0.155)
		(layer "B.Cu")
		(net 4)
	)
	(segment
		(start 121.6 75.33)
		(end 121.32 75.05)
		(width 0.155)
		(layer "B.Cu")
		(net 4)
	)
	(segment
		(start 122.7704 74.9696)
		(end 122.78 74.96)
		(width 0.155)
		(layer "B.Cu")
		(net 4)
	)
	(segment
		(start 121.32 75.05)
		(end 120.1411 75.05)
		(width 0.155)
		(layer "B.Cu")
		(net 4)
	)
	(segment
		(start 122.02 75.33)
		(end 121.6 75.33)
		(width 0.155)
		(layer "B.Cu")
		(net 4)
	)
	(segment
		(start 120.1411 75.05)
		(end 120.0507 74.9596)
		(width 0.155)
		(layer "B.Cu")
		(net 4)
	)
	(segment
		(start 124.847323 80.205136)
		(end 124.947823 80.305636)
		(width 0.155)
		(layer "F.Cu")
		(net 5)
	)
	(segment
		(start 124.947823 81.559249)
		(end 125.608574 82.22)
		(width 0.155)
		(layer "F.Cu")
		(net 5)
	)
	(segment
		(start 125.608574 82.22)
		(end 127.341425 82.22)
		(width 0.155)
		(layer "F.Cu")
		(net 5)
	)
	(segment
		(start 127.566414 81.995011)
		(end 127.775011 81.995011)
		(width 0.155)
		(layer "F.Cu")
		(net 5)
	)
	(segment
		(start 124.947823 80.305636)
		(end 124.947823 81.559249)
		(width 0.155)
		(layer "F.Cu")
		(net 5)
	)
	(segment
		(start 127.341425 82.22)
		(end 127.566414 81.995011)
		(width 0.155)
		(layer "F.Cu")
		(net 5)
	)
	(via
		(at 127.775011 81.995011)
		(size 0.45)
		(drill 0.1)
		(layers "F.Cu" "B.Cu")
		(net 5)
	)
	(segment
		(start 131.629 83.069501)
		(end 131.629 81.590499)
		(width 0.155)
		(layer "B.Cu")
		(net 5)
	)
	(segment
		(start 130.53 81.590499)
		(end 130.53 83.069501)
		(width 0.155)
		(layer "B.Cu")
		(net 5)
	)
	(segment
		(start 133.229 83.069501)
		(end 133.229 81.590499)
		(width 0.155)
		(layer "B.Cu")
		(net 5)
	)
	(segment
		(start 142.261926 85.8995)
		(end 143.0495 85.8995)
		(width 0.155)
		(layer "B.Cu")
		(net 5)
	)
	(segment
		(start 134.858074 82.4795)
		(end 136.6305 84.251926)
		(width 0.155)
		(layer "B.Cu")
		(net 5)
	)
	(segment
		(start 137.763074 86.4245)
		(end 141.736926 86.4245)
		(width 0.155)
		(layer "B.Cu")
		(net 5)
	)
	(segment
		(start 143.0495 85.8995)
		(end 143.15 86)
		(width 0.155)
		(layer "B.Cu")
		(net 5)
	)
	(segment
		(start 136.6305 84.251926)
		(end 136.6305 85.291926)
		(width 0.155)
		(layer "B.Cu")
		(net 5)
	)
	(segment
		(start 132.13 81.590499)
		(end 132.13 83.069501)
		(width 0.155)
		(layer "B.Cu")
		(net 5)
	)
	(segment
		(start 127.775011 81.995011)
		(end 127.775011 81.786414)
		(width 0.155)
		(layer "B.Cu")
		(net 5)
	)
	(segment
		(start 128.918074 82.4795)
		(end 129.4795 82.4795)
		(width 0.155)
		(layer "B.Cu")
		(net 5)
	)
	(segment
		(start 127.775011 81.786414)
		(end 127.811925 81.7495)
		(width 0.155)
		(layer "B.Cu")
		(net 5)
	)
	(segment
		(start 133.73 81.590499)
		(end 133.73 81.93)
		(width 0.155)
		(layer "B.Cu")
		(net 5)
	)
	(segment
		(start 134.2795 82.4795)
		(end 134.858074 82.4795)
		(width 0.155)
		(layer "B.Cu")
		(net 5)
	)
	(segment
		(start 136.6305 85.291926)
		(end 137.763074 86.4245)
		(width 0.155)
		(layer "B.Cu")
		(net 5)
	)
	(segment
		(start 141.736926 86.4245)
		(end 142.261926 85.8995)
		(width 0.155)
		(layer "B.Cu")
		(net 5)
	)
	(segment
		(start 130.029 81.93)
		(end 130.029 81.590499)
		(width 0.155)
		(layer "B.Cu")
		(net 5)
	)
	(segment
		(start 127.811925 81.7495)
		(end 128.188074 81.7495)
		(width 0.155)
		(layer "B.Cu")
		(net 5)
	)
	(segment
		(start 128.188074 81.7495)
		(end 128.918074 82.4795)
		(width 0.155)
		(layer "B.Cu")
		(net 5)
	)
	(arc
		(start 132.13 83.069501)
		(mid 132.290945 83.458056)
		(end 132.6795 83.619001)
		(width 0.155)
		(layer "B.Cu")
		(net 5)
	)
	(arc
		(start 131.0795 83.619001)
		(mid 131.468055 83.458056)
		(end 131.629 83.069501)
		(width 0.155)
		(layer "B.Cu")
		(net 5)
	)
	(arc
		(start 129.4795 82.4795)
		(mid 129.868055 82.318555)
		(end 130.029 81.93)
		(width 0.155)
		(layer "B.Cu")
		(net 5)
	)
	(arc
		(start 130.2795 81.339999)
		(mid 130.45663 81.413369)
		(end 130.53 81.590499)
		(width 0.155)
		(layer "B.Cu")
		(net 5)
	)
	(arc
		(start 130.53 83.069501)
		(mid 130.690945 83.458056)
		(end 131.0795 83.619001)
		(width 0.155)
		(layer "B.Cu")
		(net 5)
	)
	(arc
		(start 131.8795 81.339999)
		(mid 132.05663 81.413369)
		(end 132.13 81.590499)
		(width 0.155)
		(layer "B.Cu")
		(net 5)
	)
	(arc
		(start 130.029 81.590499)
		(mid 130.10237 81.413369)
		(end 130.2795 81.339999)
		(width 0.155)
		(layer "B.Cu")
		(net 5)
	)
	(arc
		(start 133.4795 81.339999)
		(mid 133.65663 81.413369)
		(end 133.73 81.590499)
		(width 0.155)
		(layer "B.Cu")
		(net 5)
	)
	(arc
		(start 133.229 81.590499)
		(mid 133.30237 81.413369)
		(end 133.4795 81.339999)
		(width 0.155)
		(layer "B.Cu")
		(net 5)
	)
	(arc
		(start 132.6795 83.619001)
		(mid 133.068055 83.458056)
		(end 133.229 83.069501)
		(width 0.155)
		(layer "B.Cu")
		(net 5)
	)
	(arc
		(start 133.73 81.93)
		(mid 133.890945 82.318555)
		(end 134.2795 82.4795)
		(width 0.155)
		(layer "B.Cu")
		(net 5)
	)
	(arc
		(start 131.629 81.590499)
		(mid 131.70237 81.413369)
		(end 131.8795 81.339999)
		(width 0.155)
		(layer "B.Cu")
		(net 5)
	)
	(segment
		(start 124.19 70.47)
		(end 124.097323 70.562677)
		(width 0.155)
		(layer "F.Cu")
		(net 6)
	)
	(segment
		(start 124.097323 70.562677)
		(end 124.097323 72.005136)
		(width 0.155)
		(layer "F.Cu")
		(net 6)
	)
	(via
		(at 85.22 70.77)
		(size 0.45)
		(drill 0.1)
		(layers "F.Cu" "B.Cu")
		(net 6)
	)
	(via
		(at 124.19 70.47)
		(size 0.45)
		(drill 0.1)
		(layers "F.Cu" "B.Cu")
		(net 6)
	)
	(segment
		(start 119.148 71.242785)
		(end 119.148 72.707215)
		(width 0.16)
		(layer "In5.Cu")
		(net 6)
	)
	(segment
		(start 91.363282 71.199)
		(end 90.363282 70.199)
		(width 0.16)
		(layer "In5.Cu")
		(net 6)
	)
	(segment
		(start 85.701 70.199)
		(end 85.22 70.68)
		(width 0.16)
		(layer "In5.Cu")
		(net 6)
	)
	(segment
		(start 110.598282 71.579)
		(end 110.181 71.161718)
		(width 0.16)
		(layer "In5.Cu")
		(net 6)
	)
	(segment
		(start 110.181 70.551718)
		(end 109.788282 70.159)
		(width 0.16)
		(layer "In5.Cu")
		(net 6)
	)
	(segment
		(start 115.893282 72.124)
		(end 115.348282 71.579)
		(width 0.16)
		(layer "In5.Cu")
		(net 6)
	)
	(segment
		(start 120.648 72.35)
		(end 120.648 72.707215)
		(width 0.16)
		(layer "In5.Cu")
		(net 6)
	)
	(segment
		(start 109.788282 70.159)
		(end 96.701718 70.159)
		(width 0.16)
		(layer "In5.Cu")
		(net 6)
	)
	(segment
		(start 115.348282 71.579)
		(end 110.598282 71.579)
		(width 0.16)
		(layer "In5.Cu")
		(net 6)
	)
	(segment
		(start 90.363282 70.199)
		(end 85.701 70.199)
		(width 0.16)
		(layer "In5.Cu")
		(net 6)
	)
	(segment
		(start 85.22 70.68)
		(end 85.22 70.77)
		(width 0.16)
		(layer "In5.Cu")
		(net 6)
	)
	(segment
		(start 124.19 70.47)
		(end 124.04 70.62)
		(width 0.16)
		(layer "In5.Cu")
		(net 6)
	)
	(segment
		(start 96.701718 70.159)
		(end 95.661718 71.199)
		(width 0.16)
		(layer "In5.Cu")
		(net 6)
	)
	(segment
		(start 124.04 70.62)
		(end 124.04 71.090718)
		(width 0.16)
		(layer "In5.Cu")
		(net 6)
	)
	(segment
		(start 95.661718 71.199)
		(end 91.363282 71.199)
		(width 0.16)
		(layer "In5.Cu")
		(net 6)
	)
	(segment
		(start 119.6 72.707215)
		(end 119.6 71.242785)
		(width 0.16)
		(layer "In5.Cu")
		(net 6)
	)
	(segment
		(start 118.1 72.707215)
		(end 118.1 72.35)
		(width 0.16)
		(layer "In5.Cu")
		(net 6)
	)
	(segment
		(start 117.874 72.124)
		(end 115.893282 72.124)
		(width 0.16)
		(layer "In5.Cu")
		(net 6)
	)
	(segment
		(start 123.006718 72.124)
		(end 120.874 72.124)
		(width 0.16)
		(layer "In5.Cu")
		(net 6)
	)
	(segment
		(start 110.181 71.161718)
		(end 110.181 70.551718)
		(width 0.16)
		(layer "In5.Cu")
		(net 6)
	)
	(segment
		(start 124.04 71.090718)
		(end 123.006718 72.124)
		(width 0.16)
		(layer "In5.Cu")
		(net 6)
	)
	(arc
		(start 118.1 72.35)
		(mid 118.033806 72.190194)
		(end 117.874 72.124)
		(width 0.16)
		(layer "In5.Cu")
		(net 6)
	)
	(arc
		(start 120.124 73.231215)
		(mid 119.753476 73.077739)
		(end 119.6 72.707215)
		(width 0.16)
		(layer "In5.Cu")
		(net 6)
	)
	(arc
		(start 119.6 71.242785)
		(mid 119.533806 71.082979)
		(end 119.374 71.016785)
		(width 0.16)
		(layer "In5.Cu")
		(net 6)
	)
	(arc
		(start 118.624 73.231215)
		(mid 118.253476 73.077739)
		(end 118.1 72.707215)
		(width 0.16)
		(layer "In5.Cu")
		(net 6)
	)
	(arc
		(start 119.374 71.016785)
		(mid 119.214194 71.082979)
		(end 119.148 71.242785)
		(width 0.16)
		(layer "In5.Cu")
		(net 6)
	)
	(arc
		(start 120.648 72.707215)
		(mid 120.494524 73.077739)
		(end 120.124 73.231215)
		(width 0.16)
		(layer "In5.Cu")
		(net 6)
	)
	(arc
		(start 120.874 72.124)
		(mid 120.714194 72.190194)
		(end 120.648 72.35)
		(width 0.16)
		(layer "In5.Cu")
		(net 6)
	)
	(arc
		(start 119.148 72.707215)
		(mid 118.994524 73.077739)
		(end 118.624 73.231215)
		(width 0.16)
		(layer "In5.Cu")
		(net 6)
	)
	(segment
		(start 85.7605 70.3295)
		(end 85.32 70.77)
		(width 0.155)
		(layer "B.Cu")
		(net 6)
	)
	(segment
		(start 86.298074 70.3295)
		(end 85.7605 70.3295)
		(width 0.155)
		(layer "B.Cu")
		(net 6)
	)
	(segment
		(start 86.6605 70.691926)
		(end 86.298074 70.3295)
		(width 0.155)
		(layer "B.Cu")
		(net 6)
	)
	(segment
		(start 81.005 73.1)
		(end 81.1055 72.9995)
		(width 0.155)
		(layer "B.Cu")
		(net 6)
	)
	(segment
		(start 81.1055 72.9995)
		(end 81.1055 72.763074)
		(width 0.155)
		(layer "B.Cu")
		(net 6)
	)
	(segment
		(start 85.808074 72.2605)
		(end 86.6605 71.408074)
		(width 0.155)
		(layer "B.Cu")
		(net 6)
	)
	(segment
		(start 85.32 70.77)
		(end 85.22 70.77)
		(width 0.155)
		(layer "B.Cu")
		(net 6)
	)
	(segment
		(start 86.6605 71.408074)
		(end 86.6605 70.691926)
		(width 0.155)
		(layer "B.Cu")
		(net 6)
	)
	(segment
		(start 81.608074 72.2605)
		(end 85.808074 72.2605)
		(width 0.155)
		(layer "B.Cu")
		(net 6)
	)
	(segment
		(start 81.1055 72.763074)
		(end 81.608074 72.2605)
		(width 0.155)
		(layer "B.Cu")
		(net 6)
	)
	(segment
		(start 123.847323 80.205136)
		(end 123.847323 81.517637)
		(width 0.155)
		(layer "F.Cu")
		(net 7)
	)
	(segment
		(start 131.000721 80.982387)
		(end 131.570695 81.552361)
		(width 0.155)
		(layer "F.Cu")
		(net 7)
	)
	(segment
		(start 125.881926 82.7805)
		(end 126.171926 83.0705)
		(width 0.155)
		(layer "F.Cu")
		(net 7)
	)
	(segment
		(start 130.181511 83.727246)
		(end 130.654765 84.2005)
		(width 0.155)
		(layer "F.Cu")
		(net 7)
	)
	(segment
		(start 130.654765 84.2005)
		(end 131.2125 84.2005)
		(width 0.155)
		(layer "F.Cu")
		(net 7)
	)
	(segment
		(start 128.3705 82.318074)
		(end 128.3705 81.6595)
		(width 0.155)
		(layer "F.Cu")
		(net 7)
	)
	(segment
		(start 130.181511 83.309915)
		(end 130.181511 83.727246)
		(width 0.155)
		(layer "F.Cu")
		(net 7)
	)
	(segment
		(start 131.570695 82.452361)
		(end 131.570695 82.54811)
		(width 0.155)
		(layer "F.Cu")
		(net 7)
	)
	(segment
		(start 131.781989 82.213654)
		(end 131.781988 82.213654)
		(width 0.155)
		(layer "F.Cu")
		(net 7)
	)
	(segment
		(start 128.3705 81.6595)
		(end 129.047613 80.982387)
		(width 0.155)
		(layer "F.Cu")
		(net 7)
	)
	(segment
		(start 131.781988 81.763654)
		(end 131.781989 81.763654)
		(width 0.155)
		(layer "F.Cu")
		(net 7)
	)
	(segment
		(start 130.421926 83.0695)
		(end 130.181511 83.309915)
		(width 0.155)
		(layer "F.Cu")
		(net 7)
	)
	(segment
		(start 131.049305 83.0695)
		(end 130.421926 83.0695)
		(width 0.155)
		(layer "F.Cu")
		(net 7)
	)
	(segment
		(start 131.993282 81.974947)
		(end 131.993282 82.002361)
		(width 0.155)
		(layer "F.Cu")
		(net 7)
	)
	(segment
		(start 123.746823 82.425397)
		(end 124.101926 82.7805)
		(width 0.155)
		(layer "F.Cu")
		(net 7)
	)
	(segment
		(start 126.171926 83.0705)
		(end 127.618074 83.0705)
		(width 0.155)
		(layer "F.Cu")
		(net 7)
	)
	(segment
		(start 124.101926 82.7805)
		(end 125.881926 82.7805)
		(width 0.155)
		(layer "F.Cu")
		(net 7)
	)
	(segment
		(start 131.2125 84.2005)
		(end 131.36 84.053)
		(width 0.155)
		(layer "F.Cu")
		(net 7)
	)
	(segment
		(start 123.746823 81.618137)
		(end 123.746823 82.425397)
		(width 0.155)
		(layer "F.Cu")
		(net 7)
	)
	(segment
		(start 131.570695 82.54811)
		(end 131.049305 83.0695)
		(width 0.155)
		(layer "F.Cu")
		(net 7)
	)
	(segment
		(start 129.047613 80.982387)
		(end 131.000721 80.982387)
		(width 0.155)
		(layer "F.Cu")
		(net 7)
	)
	(segment
		(start 123.847323 81.517637)
		(end 123.746823 81.618137)
		(width 0.155)
		(layer "F.Cu")
		(net 7)
	)
	(segment
		(start 127.618074 83.0705)
		(end 128.3705 82.318074)
		(width 0.155)
		(layer "F.Cu")
		(net 7)
	)
	(segment
		(start 131.570695 82.424947)
		(end 131.570695 82.452361)
		(width 0.155)
		(layer "F.Cu")
		(net 7)
	)
	(via
		(at 131.36 84.053)
		(size 0.45)
		(drill 0.1)
		(layers "F.Cu" "B.Cu")
		(net 7)
	)
	(arc
		(start 131.993282 82.002361)
		(mid 131.931396 82.151768)
		(end 131.781989 82.213654)
		(width 0.155)
		(layer "F.Cu")
		(net 7)
	)
	(arc
		(start 131.781988 82.213654)
		(mid 131.632581 82.27554)
		(end 131.570695 82.424947)
		(width 0.155)
		(layer "F.Cu")
		(net 7)
	)
	(arc
		(start 131.570695 81.552361)
		(mid 131.632581 81.701768)
		(end 131.781988 81.763654)
		(width 0.155)
		(layer "F.Cu")
		(net 7)
	)
	(arc
		(start 131.781989 81.763654)
		(mid 131.931396 81.82554)
		(end 131.993282 81.974947)
		(width 0.155)
		(layer "F.Cu")
		(net 7)
	)
	(segment
		(start 134.491926 84.2005)
		(end 131.5075 84.2005)
		(width 0.155)
		(layer "B.Cu")
		(net 7)
	)
	(segment
		(start 137.391926 87.1005)
		(end 134.491926 84.2005)
		(width 0.155)
		(layer "B.Cu")
		(net 7)
	)
	(segment
		(start 143.15 87)
		(end 142.249999 87)
		(width 0.155)
		(layer "B.Cu")
		(net 7)
	)
	(segment
		(start 142.149499 87.1005)
		(end 137.391926 87.1005)
		(width 0.155)
		(layer "B.Cu")
		(net 7)
	)
	(segment
		(start 131.5075 84.2005)
		(end 131.36 84.053)
		(width 0.155)
		(layer "B.Cu")
		(net 7)
	)
	(segment
		(start 142.249999 87)
		(end 142.149499 87.1005)
		(width 0.155)
		(layer "B.Cu")
		(net 7)
	)
	(segment
		(start 123.597323 70.692635)
		(end 123.597323 72.005136)
		(width 0.155)
		(layer "F.Cu")
		(net 8)
	)
	(segment
		(start 123.61 70.48)
		(end 123.697823 70.567823)
		(width 0.155)
		(layer "F.Cu")
		(net 8)
	)
	(segment
		(start 123.697823 70.592135)
		(end 123.597323 70.692635)
		(width 0.155)
		(layer "F.Cu")
		(net 8)
	)
	(segment
		(start 123.697823 70.567823)
		(end 123.697823 70.592135)
		(width 0.155)
		(layer "F.Cu")
		(net 8)
	)
	(via
		(at 85.08 70.21)
		(size 0.45)
		(drill 0.1)
		(layers "F.Cu" "B.Cu")
		(net 8)
	)
	(via
		(at 123.61 70.48)
		(size 0.45)
		(drill 0.1)
		(layers "F.Cu" "B.Cu")
		(net 8)
	)
	(segment
		(start 123.61 70.48)
		(end 123.698323 70.568323)
		(width 0.16)
		(layer "In5.Cu")
		(net 8)
	)
	(segment
		(start 91.486718 70.901)
		(end 90.486718 69.901)
		(width 0.16)
		(layer "In5.Cu")
		(net 8)
	)
	(segment
		(start 115.471718 71.281)
		(end 110.721718 71.281)
		(width 0.16)
		(layer "In5.Cu")
		(net 8)
	)
	(segment
		(start 122.883282 71.826)
		(end 120.874 71.826)
		(width 0.16)
		(layer "In5.Cu")
		(net 8)
	)
	(segment
		(start 118.85 71.242785)
		(end 118.85 72.707215)
		(width 0.16)
		(layer "In5.Cu")
		(net 8)
	)
	(segment
		(start 85.488282 69.901)
		(end 85.179282 70.21)
		(width 0.16)
		(layer "In5.Cu")
		(net 8)
	)
	(segment
		(start 110.721718 71.281)
		(end 110.479 71.038282)
		(width 0.16)
		(layer "In5.Cu")
		(net 8)
	)
	(segment
		(start 110.479 71.038282)
		(end 110.479 70.428282)
		(width 0.16)
		(layer "In5.Cu")
		(net 8)
	)
	(segment
		(start 123.698323 70.568323)
		(end 123.698323 71.010959)
		(width 0.16)
		(layer "In5.Cu")
		(net 8)
	)
	(segment
		(start 85.179282 70.21)
		(end 85.08 70.21)
		(width 0.16)
		(layer "In5.Cu")
		(net 8)
	)
	(segment
		(start 110.479 70.428282)
		(end 109.911718 69.861)
		(width 0.16)
		(layer "In5.Cu")
		(net 8)
	)
	(segment
		(start 116.016718 71.826)
		(end 115.471718 71.281)
		(width 0.16)
		(layer "In5.Cu")
		(net 8)
	)
	(segment
		(start 95.538282 70.901)
		(end 91.486718 70.901)
		(width 0.16)
		(layer "In5.Cu")
		(net 8)
	)
	(segment
		(start 120.35 72.35)
		(end 120.35 72.707215)
		(width 0.16)
		(layer "In5.Cu")
		(net 8)
	)
	(segment
		(start 90.486718 69.901)
		(end 85.488282 69.901)
		(width 0.16)
		(layer "In5.Cu")
		(net 8)
	)
	(segment
		(start 118.398 72.707215)
		(end 118.398 72.35)
		(width 0.16)
		(layer "In5.Cu")
		(net 8)
	)
	(segment
		(start 123.698323 71.010959)
		(end 122.883282 71.826)
		(width 0.16)
		(layer "In5.Cu")
		(net 8)
	)
	(segment
		(start 117.874 71.826)
		(end 116.016718 71.826)
		(width 0.16)
		(layer "In5.Cu")
		(net 8)
	)
	(segment
		(start 96.578282 69.861)
		(end 95.538282 70.901)
		(width 0.16)
		(layer "In5.Cu")
		(net 8)
	)
	(segment
		(start 119.898 72.707215)
		(end 119.898 71.242785)
		(width 0.16)
		(layer "In5.Cu")
		(net 8)
	)
	(segment
		(start 109.911718 69.861)
		(end 96.578282 69.861)
		(width 0.16)
		(layer "In5.Cu")
		(net 8)
	)
	(arc
		(start 120.874 71.826)
		(mid 120.503476 71.979476)
		(end 120.35 72.35)
		(width 0.16)
		(layer "In5.Cu")
		(net 8)
	)
	(arc
		(start 119.898 71.242785)
		(mid 119.744524 70.872261)
		(end 119.374 70.718785)
		(width 0.16)
		(layer "In5.Cu")
		(net 8)
	)
	(arc
		(start 118.624 72.933215)
		(mid 118.464194 72.867021)
		(end 118.398 72.707215)
		(width 0.16)
		(layer "In5.Cu")
		(net 8)
	)
	(arc
		(start 118.85 72.707215)
		(mid 118.783806 72.867021)
		(end 118.624 72.933215)
		(width 0.16)
		(layer "In5.Cu")
		(net 8)
	)
	(arc
		(start 119.374 70.718785)
		(mid 119.003476 70.872261)
		(end 118.85 71.242785)
		(width 0.16)
		(layer "In5.Cu")
		(net 8)
	)
	(arc
		(start 120.35 72.707215)
		(mid 120.283806 72.867021)
		(end 120.124 72.933215)
		(width 0.16)
		(layer "In5.Cu")
		(net 8)
	)
	(arc
		(start 120.124 72.933215)
		(mid 119.964194 72.867021)
		(end 119.898 72.707215)
		(width 0.16)
		(layer "In5.Cu")
		(net 8)
	)
	(arc
		(start 118.398 72.35)
		(mid 118.244524 71.979476)
		(end 117.874 71.826)
		(width 0.16)
		(layer "In5.Cu")
		(net 8)
	)
	(segment
		(start 81.731926 72.5595)
		(end 85.931926 72.5595)
		(width 0.155)
		(layer "B.Cu")
		(net 8)
	)
	(segment
		(start 81.4045 72.9995)
		(end 81.4045 72.886926)
		(width 0.155)
		(layer "B.Cu")
		(net 8)
	)
	(segment
		(start 85.931926 72.5595)
		(end 86.9595 71.531926)
		(width 0.155)
		(layer "B.Cu")
		(net 8)
	)
	(segment
		(start 86.9595 71.531926)
		(end 86.9595 70.568074)
		(width 0.155)
		(layer "B.Cu")
		(net 8)
	)
	(segment
		(start 85.4995 70.0305)
		(end 85.32 70.21)
		(width 0.155)
		(layer "B.Cu")
		(net 8)
	)
	(segment
		(start 86.421926 70.0305)
		(end 85.4995 70.0305)
		(width 0.155)
		(layer "B.Cu")
		(net 8)
	)
	(segment
		(start 86.9595 70.568074)
		(end 86.421926 70.0305)
		(width 0.155)
		(layer "B.Cu")
		(net 8)
	)
	(segment
		(start 85.32 70.21)
		(end 85.08 70.21)
		(width 0.155)
		(layer "B.Cu")
		(net 8)
	)
	(segment
		(start 81.505 73.1)
		(end 81.4045 72.9995)
		(width 0.155)
		(layer "B.Cu")
		(net 8)
	)
	(segment
		(start 81.4045 72.886926)
		(end 81.731926 72.5595)
		(width 0.155)
		(layer "B.Cu")
		(net 8)
	)
	(segment
		(start 131.2125 84.4995)
		(end 131.36 84.647)
		(width 0.155)
		(layer "F.Cu")
		(net 9)
	)
	(segment
		(start 131.271695 81.676213)
		(end 131.271695 82.424258)
		(width 0.155)
		(layer "F.Cu")
		(net 9)
	)
	(segment
		(start 126.048074 83.3695)
		(end 127.741926 83.3695)
		(width 0.155)
		(layer "F.Cu")
		(net 9)
	)
	(segment
		(start 128.6695 82.441926)
		(end 128.6695 81.801926)
		(width 0.155)
		(layer "F.Cu")
		(net 9)
	)
	(segment
		(start 129.882511 83.851098)
		(end 130.530913 84.4995)
		(width 0.155)
		(layer "F.Cu")
		(net 9)
	)
	(segment
		(start 123.978074 83.0795)
		(end 125.758074 83.0795)
		(width 0.155)
		(layer "F.Cu")
		(net 9)
	)
	(segment
		(start 123.347323 80.205136)
		(end 123.347323 81.517637)
		(width 0.155)
		(layer "F.Cu")
		(net 9)
	)
	(segment
		(start 130.879269 81.283787)
		(end 131.271695 81.676213)
		(width 0.155)
		(layer "F.Cu")
		(net 9)
	)
	(segment
		(start 123.347323 81.517637)
		(end 123.447823 81.618137)
		(width 0.155)
		(layer "F.Cu")
		(net 9)
	)
	(segment
		(start 125.758074 83.0795)
		(end 126.048074 83.3695)
		(width 0.155)
		(layer "F.Cu")
		(net 9)
	)
	(segment
		(start 131.271695 82.424258)
		(end 130.925453 82.7705)
		(width 0.155)
		(layer "F.Cu")
		(net 9)
	)
	(segment
		(start 123.447823 81.618137)
		(end 123.447823 82.549249)
		(width 0.155)
		(layer "F.Cu")
		(net 9)
	)
	(segment
		(start 130.298074 82.7705)
		(end 129.882511 83.186063)
		(width 0.155)
		(layer "F.Cu")
		(net 9)
	)
	(segment
		(start 129.882511 83.186063)
		(end 129.882511 83.851098)
		(width 0.155)
		(layer "F.Cu")
		(net 9)
	)
	(segment
		(start 128.6695 81.801926)
		(end 129.187639 81.283787)
		(width 0.155)
		(layer "F.Cu")
		(net 9)
	)
	(segment
		(start 130.298074 82.7705)
		(end 130.925453 82.7705)
		(width 0.155)
		(layer "F.Cu")
		(net 9)
	)
	(segment
		(start 123.447823 82.549249)
		(end 123.978074 83.0795)
		(width 0.155)
		(layer "F.Cu")
		(net 9)
	)
	(segment
		(start 130.530913 84.4995)
		(end 131.2125 84.4995)
		(width 0.155)
		(layer "F.Cu")
		(net 9)
	)
	(segment
		(start 129.187639 81.283787)
		(end 130.879269 81.283787)
		(width 0.155)
		(layer "F.Cu")
		(net 9)
	)
	(segment
		(start 127.741926 83.3695)
		(end 128.6695 82.441926)
		(width 0.155)
		(layer "F.Cu")
		(net 9)
	)
	(via
		(at 131.36 84.647)
		(size 0.45)
		(drill 0.1)
		(layers "F.Cu" "B.Cu")
		(net 9)
	)
	(segment
		(start 134.368074 84.4995)
		(end 131.5075 84.4995)
		(width 0.155)
		(layer "B.Cu")
		(net 9)
	)
	(segment
		(start 137.268074 87.3995)
		(end 134.368074 84.4995)
		(width 0.155)
		(layer "B.Cu")
		(net 9)
	)
	(segment
		(start 142.249999 87.5)
		(end 142.149499 87.3995)
		(width 0.155)
		(layer "B.Cu")
		(net 9)
	)
	(segment
		(start 131.5075 84.4995)
		(end 131.36 84.647)
		(width 0.155)
		(layer "B.Cu")
		(net 9)
	)
	(segment
		(start 143.15 87.5)
		(end 142.249999 87.5)
		(width 0.155)
		(layer "B.Cu")
		(net 9)
	)
	(segment
		(start 142.149499 87.3995)
		(end 137.268074 87.3995)
		(width 0.155)
		(layer "B.Cu")
		(net 9)
	)
	(segment
		(start 120.208074 74.9395)
		(end 119.8505 74.581926)
		(width 0.155)
		(layer "F.Cu")
		(net 10)
	)
	(segment
		(start 122.597323 73.434103)
		(end 121.091926 74.9395)
		(width 0.155)
		(layer "F.Cu")
		(net 10)
	)
	(segment
		(start 119.8505 74.581926)
		(end 119.8505 74.008074)
		(width 0.155)
		(layer "F.Cu")
		(net 10)
	)
	(segment
		(start 120.158574 73.7)
		(end 120.89 73.7)
		(width 0.155)
		(layer "F.Cu")
		(net 10)
	)
	(segment
		(start 122.597323 72.005136)
		(end 122.597323 73.434103)
		(width 0.155)
		(layer "F.Cu")
		(net 10)
	)
	(segment
		(start 121.091926 74.9395)
		(end 120.208074 74.9395)
		(width 0.155)
		(layer "F.Cu")
		(net 10)
	)
	(segment
		(start 120.89 73.7)
		(end 120.93 73.66)
		(width 0.155)
		(layer "F.Cu")
		(net 10)
	)
	(segment
		(start 119.8505 74.008074)
		(end 120.158574 73.7)
		(width 0.155)
		(layer "F.Cu")
		(net 10)
	)
	(via
		(at 120.93 73.66)
		(size 0.45)
		(drill 0.1)
		(layers "F.Cu" "B.Cu")
		(net 10)
	)
	(segment
		(start 120.93 73.66)
		(end 121.0641 73.7941)
		(width 0.155)
		(layer "B.Cu")
		(net 10)
	)
	(segment
		(start 121.9822 73.7504)
		(end 122.7704 73.7504)
		(width 0.155)
		(layer "B.Cu")
		(net 10)
	)
	(segment
		(start 120.8496 73.7404)
		(end 120.93 73.66)
		(width 0.155)
		(layer "B.Cu")
		(net 10)
	)
	(segment
		(start 121.9385 73.7941)
		(end 121.9822 73.7504)
		(width 0.155)
		(layer "B.Cu")
		(net 10)
	)
	(segment
		(start 120.0507 73.7404)
		(end 120.8496 73.7404)
		(width 0.155)
		(layer "B.Cu")
		(net 10)
	)
	(segment
		(start 121.0641 73.7941)
		(end 121.9385 73.7941)
		(width 0.155)
		(layer "B.Cu")
		(net 10)
	)
	(segment
		(start 122.7704 73.7504)
		(end 122.78 73.76)
		(width 0.155)
		(layer "B.Cu")
		(net 10)
	)
	(segment
		(start 122.347323 80.205136)
		(end 122.347323 79.480136)
		(width 0.155)
		(layer "F.Cu")
		(net 11)
	)
	(segment
		(start 122.347323 79.480136)
		(end 122.246823 79.379636)
		(width 0.155)
		(layer "F.Cu")
		(net 11)
	)
	(segment
		(start 122.246823 78.7375)
		(end 122.394323 78.59)
		(width 0.155)
		(layer "F.Cu")
		(net 11)
	)
	(segment
		(start 122.246823 79.379636)
		(end 122.246823 78.7375)
		(width 0.155)
		(layer "F.Cu")
		(net 11)
	)
	(via
		(at 122.394323 78.59)
		(size 0.45)
		(drill 0.1)
		(layers "F.Cu" "B.Cu")
		(net 11)
	)
	(segment
		(start 133.2605 79.8905)
		(end 134.501926 79.8905)
		(width 0.155)
		(layer "B.Cu")
		(net 11)
	)
	(segment
		(start 143.0495 84.6005)
		(end 143.15 84.5)
		(width 0.155)
		(layer "B.Cu")
		(net 11)
	)
	(segment
		(start 126.5005 79.028074)
		(end 126.788074 78.7405)
		(width 0.155)
		(layer "B.Cu")
		(net 11)
	)
	(segment
		(start 126.788074 78.7405)
		(end 127.9805 78.7405)
		(width 0.155)
		(layer "B.Cu")
		(net 11)
	)
	(segment
		(start 122.394323 78.59)
		(end 122.246823 78.7375)
		(width 0.155)
		(layer "B.Cu")
		(net 11)
	)
	(segment
		(start 122.811926 80.2005)
		(end 126.008074 80.2005)
		(width 0.155)
		(layer "B.Cu")
		(net 11)
	)
	(segment
		(start 132.6605 79.6905)
		(end 132.6605 79.671117)
		(width 0.155)
		(layer "B.Cu")
		(net 11)
	)
	(segment
		(start 133.0605 79.671117)
		(end 133.0605 79.6905)
		(width 0.155)
		(layer "B.Cu")
		(net 11)
	)
	(segment
		(start 129.4805 78.7405)
		(end 130.881926 78.7405)
		(width 0.155)
		(layer "B.Cu")
		(net 11)
	)
	(segment
		(start 126.008074 80.2005)
		(end 126.5005 79.708074)
		(width 0.155)
		(layer "B.Cu")
		(net 11)
	)
	(segment
		(start 130.881926 78.7405)
		(end 132.031926 79.8905)
		(width 0.155)
		(layer "B.Cu")
		(net 11)
	)
	(segment
		(start 128.206 78.515)
		(end 128.206 77.870527)
		(width 0.155)
		(layer "B.Cu")
		(net 11)
	)
	(segment
		(start 129.255 77.870527)
		(end 129.255 78.515)
		(width 0.155)
		(layer "B.Cu")
		(net 11)
	)
	(segment
		(start 122.246823 78.7375)
		(end 122.246823 79.635397)
		(width 0.155)
		(layer "B.Cu")
		(net 11)
	)
	(segment
		(start 134.501926 79.8905)
		(end 139.211926 84.6005)
		(width 0.155)
		(layer "B.Cu")
		(net 11)
	)
	(segment
		(start 122.246823 79.635397)
		(end 122.811926 80.2005)
		(width 0.155)
		(layer "B.Cu")
		(net 11)
	)
	(segment
		(start 126.5005 79.708074)
		(end 126.5005 79.028074)
		(width 0.155)
		(layer "B.Cu")
		(net 11)
	)
	(segment
		(start 139.211926 84.6005)
		(end 143.0495 84.6005)
		(width 0.155)
		(layer "B.Cu")
		(net 11)
	)
	(segment
		(start 132.031926 79.8905)
		(end 132.4605 79.8905)
		(width 0.155)
		(layer "B.Cu")
		(net 11)
	)
	(arc
		(start 127.9805 78.7405)
		(mid 128.139953 78.674453)
		(end 128.206 78.515)
		(width 0.155)
		(layer "B.Cu")
		(net 11)
	)
	(arc
		(start 128.206 77.870527)
		(mid 128.359622 77.499649)
		(end 128.7305 77.346027)
		(width 0.155)
		(layer "B.Cu")
		(net 11)
	)
	(arc
		(start 132.8605 79.471117)
		(mid 133.001921 79.529696)
		(end 133.0605 79.671117)
		(width 0.155)
		(layer "B.Cu")
		(net 11)
	)
	(arc
		(start 133.0605 79.6905)
		(mid 133.119079 79.831921)
		(end 133.2605 79.8905)
		(width 0.155)
		(layer "B.Cu")
		(net 11)
	)
	(arc
		(start 132.4605 79.8905)
		(mid 132.601921 79.831921)
		(end 132.6605 79.6905)
		(width 0.155)
		(layer "B.Cu")
		(net 11)
	)
	(arc
		(start 129.255 78.515)
		(mid 129.321047 78.674453)
		(end 129.4805 78.7405)
		(width 0.155)
		(layer "B.Cu")
		(net 11)
	)
	(arc
		(start 128.7305 77.346027)
		(mid 129.101378 77.499649)
		(end 129.255 77.870527)
		(width 0.155)
		(layer "B.Cu")
		(net 11)
	)
	(arc
		(start 132.6605 79.671117)
		(mid 132.719079 79.529696)
		(end 132.8605 79.471117)
		(width 0.155)
		(layer "B.Cu")
		(net 11)
	)
	(segment
		(start 121.8 73.16)
		(end 121.8 73.61)
		(width 0.155)
		(layer "F.Cu")
		(net 12)
	)
	(segment
		(start 121.15 74.45)
		(end 121.158574 74.45)
		(width 0.155)
		(layer "F.Cu")
		(net 12)
	)
	(segment
		(start 121.234319 74.374252)
		(end 121.234322 74.374252)
		(width 0.155)
		(layer "F.Cu")
		(net 12)
	)
	(segment
		(start 121.158574 74.45)
		(end 121.234319 74.374252)
		(width 0.155)
		(layer "F.Cu")
		(net 12)
	)
	(segment
		(start 120.1495 74.131926)
		(end 120.1495 74.458074)
		(width 0.155)
		(layer "F.Cu")
		(net 12)
	)
	(segment
		(start 120.968074 74.631926)
		(end 121.15 74.45)
		(width 0.155)
		(layer "F.Cu")
		(net 12)
	)
	(segment
		(start 120.331926 74.6405)
		(end 120.968074 74.6405)
		(width 0.155)
		(layer "F.Cu")
		(net 12)
	)
	(segment
		(start 121.958574 73.65)
		(end 122.18 73.428574)
		(width 0.155)
		(layer "F.Cu")
		(net 12)
	)
	(segment
		(start 121.32 73.1)
		(end 121.74 73.1)
		(width 0.155)
		(layer "F.Cu")
		(net 12)
	)
	(segment
		(start 120.76 74.21)
		(end 120.5445 73.9945)
		(width 0.155)
		(layer "F.Cu")
		(net 12)
	)
	(segment
		(start 121.74 73.1)
		(end 121.8 73.16)
		(width 0.155)
		(layer "F.Cu")
		(net 12)
	)
	(segment
		(start 120.968074 74.6405)
		(end 120.968074 74.631926)
		(width 0.155)
		(layer "F.Cu")
		(net 12)
	)
	(segment
		(start 121.26 73.16)
		(end 121.32 73.1)
		(width 0.155)
		(layer "F.Cu")
		(net 12)
	)
	(segment
		(start 120.1495 74.458074)
		(end 120.331926 74.6405)
		(width 0.155)
		(layer "F.Cu")
		(net 12)
	)
	(segment
		(start 120.5445 73.9945)
		(end 120.286926 73.9945)
		(width 0.155)
		(layer "F.Cu")
		(net 12)
	)
	(segment
		(start 121.36 73.86)
		(end 121.36 73.48)
		(width 0.155)
		(layer "F.Cu")
		(net 12)
	)
	(segment
		(start 122.18 72.087813)
		(end 122.097323 72.005136)
		(width 0.155)
		(layer "F.Cu")
		(net 12)
	)
	(segment
		(start 120.286926 73.9945)
		(end 120.1495 74.131926)
		(width 0.155)
		(layer "F.Cu")
		(net 12)
	)
	(segment
		(start 122.18 73.428574)
		(end 122.18 72.087813)
		(width 0.155)
		(layer "F.Cu")
		(net 12)
	)
	(segment
		(start 121.26 73.38)
		(end 121.26 73.16)
		(width 0.155)
		(layer "F.Cu")
		(net 12)
	)
	(segment
		(start 121.234322 74.374252)
		(end 121.234322 73.985678)
		(width 0.155)
		(layer "F.Cu")
		(net 12)
	)
	(segment
		(start 121.234322 73.985678)
		(end 121.36 73.86)
		(width 0.155)
		(layer "F.Cu")
		(net 12)
	)
	(segment
		(start 121.8 73.61)
		(end 121.84 73.65)
		(width 0.155)
		(layer "F.Cu")
		(net 12)
	)
	(segment
		(start 121.36 73.48)
		(end 121.26 73.38)
		(width 0.155)
		(layer "F.Cu")
		(net 12)
	)
	(segment
		(start 121.84 73.65)
		(end 121.958574 73.65)
		(width 0.155)
		(layer "F.Cu")
		(net 12)
	)
	(via
		(at 120.76 74.21)
		(size 0.45)
		(drill 0.1)
		(layers "F.Cu" "B.Cu")
		(net 12)
	)
	(segment
		(start 120.0507 74.1468)
		(end 120.6968 74.1468)
		(width 0.155)
		(layer "B.Cu")
		(net 12)
	)
	(segment
		(start 120.6968 74.1468)
		(end 120.76 74.21)
		(width 0.155)
		(layer "B.Cu")
		(net 12)
	)
	(segment
		(start 122.7768 74.1568)
		(end 122.78 74.16)
		(width 0.155)
		(layer "B.Cu")
		(net 12)
	)
	(segment
		(start 121.9385 74.0931)
		(end 122.0022 74.1568)
		(width 0.155)
		(layer "B.Cu")
		(net 12)
	)
	(segment
		(start 120.76 74.21)
		(end 120.8769 74.0931)
		(width 0.155)
		(layer "B.Cu")
		(net 12)
	)
	(segment
		(start 122.0022 74.1568)
		(end 122.7768 74.1568)
		(width 0.155)
		(layer "B.Cu")
		(net 12)
	)
	(segment
		(start 120.8769 74.0931)
		(end 121.9385 74.0931)
		(width 0.155)
		(layer "B.Cu")
		(net 12)
	)
	(segment
		(start 121.947823 79.379636)
		(end 121.947823 78.7375)
		(width 0.155)
		(layer "F.Cu")
		(net 13)
	)
	(segment
		(start 121.847323 80.205136)
		(end 121.847323 79.480136)
		(width 0.155)
		(layer "F.Cu")
		(net 13)
	)
	(segment
		(start 121.947823 78.7375)
		(end 121.800323 78.59)
		(width 0.155)
		(layer "F.Cu")
		(net 13)
	)
	(segment
		(start 121.847323 79.480136)
		(end 121.947823 79.379636)
		(width 0.155)
		(layer "F.Cu")
		(net 13)
	)
	(via
		(at 121.800323 78.59)
		(size 0.45)
		(drill 0.1)
		(layers "F.Cu" "B.Cu")
		(net 13)
	)
	(segment
		(start 126.7995 79.831926)
		(end 126.7995 79.151926)
		(width 0.155)
		(layer "B.Cu")
		(net 13)
	)
	(segment
		(start 121.947823 79.759249)
		(end 122.688074 80.4995)
		(width 0.155)
		(layer "B.Cu")
		(net 13)
	)
	(segment
		(start 122.688074 80.4995)
		(end 126.131926 80.4995)
		(width 0.155)
		(layer "B.Cu")
		(net 13)
	)
	(segment
		(start 143.0495 84.8995)
		(end 143.15 85)
		(width 0.155)
		(layer "B.Cu")
		(net 13)
	)
	(segment
		(start 130.758074 79.0395)
		(end 131.908074 80.1895)
		(width 0.155)
		(layer "B.Cu")
		(net 13)
	)
	(segment
		(start 134.378074 80.1895)
		(end 139.088074 84.8995)
		(width 0.155)
		(layer "B.Cu")
		(net 13)
	)
	(segment
		(start 121.947823 78.7375)
		(end 121.947823 79.759249)
		(width 0.155)
		(layer "B.Cu")
		(net 13)
	)
	(segment
		(start 128.956 77.870527)
		(end 128.956 78.515)
		(width 0.155)
		(layer "B.Cu")
		(net 13)
	)
	(segment
		(start 126.7995 79.151926)
		(end 126.911926 79.0395)
		(width 0.155)
		(layer "B.Cu")
		(net 13)
	)
	(segment
		(start 126.911926 79.0395)
		(end 127.9805 79.0395)
		(width 0.155)
		(layer "B.Cu")
		(net 13)
	)
	(segment
		(start 139.088074 84.8995)
		(end 143.0495 84.8995)
		(width 0.155)
		(layer "B.Cu")
		(net 13)
	)
	(segment
		(start 126.131926 80.4995)
		(end 126.7995 79.831926)
		(width 0.155)
		(layer "B.Cu")
		(net 13)
	)
	(segment
		(start 121.800323 78.59)
		(end 121.947823 78.7375)
		(width 0.155)
		(layer "B.Cu")
		(net 13)
	)
	(segment
		(start 128.505 78.515)
		(end 128.505 77.870527)
		(width 0.155)
		(layer "B.Cu")
		(net 13)
	)
	(segment
		(start 129.4805 79.0395)
		(end 130.758074 79.0395)
		(width 0.155)
		(layer "B.Cu")
		(net 13)
	)
	(segment
		(start 131.908074 80.1895)
		(end 134.378074 80.1895)
		(width 0.155)
		(layer "B.Cu")
		(net 13)
	)
	(arc
		(start 128.7305 77.645027)
		(mid 128.889953 77.711074)
		(end 128.956 77.870527)
		(width 0.155)
		(layer "B.Cu")
		(net 13)
	)
	(arc
		(start 128.956 78.515)
		(mid 129.109622 78.885878)
		(end 129.4805 79.0395)
		(width 0.155)
		(layer "B.Cu")
		(net 13)
	)
	(arc
		(start 128.505 77.870527)
		(mid 128.571047 77.711074)
		(end 128.7305 77.645027)
		(width 0.155)
		(layer "B.Cu")
		(net 13)
	)
	(arc
		(start 127.9805 79.0395)
		(mid 128.351378 78.885878)
		(end 128.505 78.515)
		(width 0.155)
		(layer "B.Cu")
		(net 13)
	)
	(segment
		(start 120.6295 76.148074)
		(end 119.5195 75.038074)
		(width 0.155)
		(layer "F.Cu")
		(net 14)
	)
	(segment
		(start 111.388574 75.4)
		(end 111.5405 75.551926)
		(width 0.155)
		(layer "F.Cu")
		(net 14)
	)
	(segment
		(start 118.008074 77.9495)
		(end 118.268074 78.2095)
		(width 0.155)
		(layer "F.Cu")
		(net 14)
	)
	(segment
		(start 111.5405 75.551926)
		(end 111.5405 76.161926)
		(width 0.155)
		(layer "F.Cu")
		(net 14)
	)
	(segment
		(start 119.5195 75.038074)
		(end 119.5195 73.861926)
		(width 0.155)
		(layer "F.Cu")
		(net 14)
	)
	(segment
		(start 119.971926 73.4095)
		(end 120.561926 73.4095)
		(width 0.155)
		(layer "F.Cu")
		(net 14)
	)
	(segment
		(start 119.751926 78.2095)
		(end 120.6295 77.331926)
		(width 0.155)
		(layer "F.Cu")
		(net 14)
	)
	(segment
		(start 119.5195 73.861926)
		(end 119.971926 73.4095)
		(width 0.155)
		(layer "F.Cu")
		(net 14)
	)
	(segment
		(start 120.561926 73.4095)
		(end 120.996823 72.974603)
		(width 0.155)
		(layer "F.Cu")
		(net 14)
	)
	(segment
		(start 111.5405 76.161926)
		(end 113.328074 77.9495)
		(width 0.155)
		(layer "F.Cu")
		(net 14)
	)
	(segment
		(start 111.17 75.4)
		(end 111.388574 75.4)
		(width 0.155)
		(layer "F.Cu")
		(net 14)
	)
	(segment
		(start 120.996823 72.974603)
		(end 120.996823 72.830636)
		(width 0.155)
		(layer "F.Cu")
		(net 14)
	)
	(segment
		(start 120.996823 72.830636)
		(end 121.097323 72.730136)
		(width 0.155)
		(layer "F.Cu")
		(net 14)
	)
	(segment
		(start 118.268074 78.2095)
		(end 119.751926 78.2095)
		(width 0.155)
		(layer "F.Cu")
		(net 14)
	)
	(segment
		(start 111.04 75.53)
		(end 111.17 75.4)
		(width 0.155)
		(layer "F.Cu")
		(net 14)
	)
	(segment
		(start 120.6295 77.331926)
		(end 120.6295 76.148074)
		(width 0.155)
		(layer "F.Cu")
		(net 14)
	)
	(segment
		(start 113.328074 77.9495)
		(end 118.008074 77.9495)
		(width 0.155)
		(layer "F.Cu")
		(net 14)
	)
	(via
		(at 111.04 75.53)
		(size 0.45)
		(drill 0.1)
		(layers "F.Cu" "B.Cu")
		(net 14)
	)
	(segment
		(start 111.92 75.23)
		(end 111.34 75.23)
		(width 0.155)
		(layer "B.Cu")
		(net 14)
	)
	(segment
		(start 111.04 75.53)
		(end 111 75.49)
		(width 0.155)
		(layer "B.Cu")
		(net 14)
	)
	(segment
		(start 111 75.49)
		(end 110.080997 75.49)
		(width 0.155)
		(layer "B.Cu")
		(net 14)
	)
	(segment
		(start 110.080997 75.49)
		(end 109.860597 75.2696)
		(width 0.155)
		(layer "B.Cu")
		(net 14)
	)
	(segment
		(start 111.34 75.23)
		(end 111.04 75.53)
		(width 0.155)
		(layer "B.Cu")
		(net 14)
	)
	(segment
		(start 109.860597 75.2696)
		(end 109.4007 75.2696)
		(width 0.155)
		(layer "B.Cu")
		(net 14)
	)
	(segment
		(start 120.746823 79.187366)
		(end 120.894323 79.039866)
		(width 0.155)
		(layer "F.Cu")
		(net 15)
	)
	(segment
		(start 120.746823 79.379636)
		(end 120.746823 79.187366)
		(width 0.155)
		(layer "F.Cu")
		(net 15)
	)
	(segment
		(start 120.847323 79.480136)
		(end 120.746823 79.379636)
		(width 0.155)
		(layer "F.Cu")
		(net 15)
	)
	(via
		(at 139.59 88.18)
		(size 0.45)
		(drill 0.1)
		(layers "F.Cu" "B.Cu")
		(net 15)
	)
	(via
		(at 120.894323 79.039866)
		(size 0.45)
		(drill 0.1)
		(layers "F.Cu" "B.Cu")
		(net 15)
	)
	(segment
		(start 138.621 82.031718)
		(end 137.988933 81.399651)
		(width 0.16)
		(layer "In5.Cu")
		(net 15)
	)
	(segment
		(start 121.211718 77.499)
		(end 120.746323 77.964395)
		(width 0.16)
		(layer "In5.Cu")
		(net 15)
	)
	(segment
		(start 137.704676 81.399652)
		(end 137.599318 81.505011)
		(width 0.16)
		(layer "In5.Cu")
		(net 15)
	)
	(segment
		(start 137.120609 79.862403)
		(end 136.344208 80.638808)
		(width 0.16)
		(layer "In5.Cu")
		(net 15)
	)
	(segment
		(start 141.221 86.041)
		(end 141.221 85.601718)
		(width 0.16)
		(layer "In5.Cu")
		(net 15)
	)
	(segment
		(start 140.306134 86.267)
		(end 140.995 86.267)
		(width 0.16)
		(layer "In5.Cu")
		(net 15)
	)
	(segment
		(start 139.113042 86.267)
		(end 139.403 86.267)
		(width 0.16)
		(layer "In5.Cu")
		(net 15)
	)
	(segment
		(start 135.830852 79.030852)
		(end 135.283553 79.578152)
		(width 0.16)
		(layer "In5.Cu")
		(net 15)
	)
	(segment
		(start 139.59 88.529282)
		(end 140.220718 89.16)
		(width 0.16)
		(layer "In5.Cu")
		(net 15)
	)
	(segment
		(start 134.628282 78.039)
		(end 129.699 78.039)
		(width 0.16)
		(layer "In5.Cu")
		(net 15)
	)
	(segment
		(start 126.541718 78.449)
		(end 125.668282 78.449)
		(width 0.16)
		(layer "In5.Cu")
		(net 15)
	)
	(segment
		(start 126.951718 78.039)
		(end 126.541718 78.449)
		(width 0.16)
		(layer "In5.Cu")
		(net 15)
	)
	(segment
		(start 140.995 87.315)
		(end 139.113042 87.315)
		(width 0.16)
		(layer "In5.Cu")
		(net 15)
	)
	(segment
		(start 136.059953 78.801747)
		(end 135.830851 79.03085)
		(width 0.16)
		(layer "In5.Cu")
		(net 15)
	)
	(segment
		(start 136.893626 81.505011)
		(end 136.858271 81.469656)
		(width 0.16)
		(layer "In5.Cu")
		(net 15)
	)
	(segment
		(start 140.078 85.742)
		(end 140.078 86.042)
		(width 0.16)
		(layer "In5.Cu")
		(net 15)
	)
	(segment
		(start 139.858171 83.534611)
		(end 139.858171 83.534612)
		(width 0.16)
		(layer "In5.Cu")
		(net 15)
	)
	(segment
		(start 128.099 78.039)
		(end 126.951718 78.039)
		(width 0.16)
		(layer "In5.Cu")
		(net 15)
	)
	(segment
		(start 136.858271 80.763963)
		(end 137.440223 80.182015)
		(width 0.16)
		(layer "In5.Cu")
		(net 15)
	)
	(segment
		(start 134.824641 78.235358)
		(end 134.628282 78.039)
		(width 0.16)
		(layer "In5.Cu")
		(net 15)
	)
	(segment
		(start 140.89974 83.975139)
		(end 140.617603 84.257273)
		(width 0.16)
		(layer "In5.Cu")
		(net 15)
	)
	(segment
		(start 139.628 86.042)
		(end 139.628 85.742)
		(width 0.16)
		(layer "In5.Cu")
		(net 15)
	)
	(segment
		(start 139.538559 83.214999)
		(end 139.433202 83.320359)
		(width 0.16)
		(layer "In5.Cu")
		(net 15)
	)
	(segment
		(start 140.617603 84.257273)
		(end 140.512246 84.362633)
		(width 0.16)
		(layer "In5.Cu")
		(net 15)
	)
	(segment
		(start 135.603161 79.897761)
		(end 136.379567 79.121359)
		(width 0.16)
		(layer "In5.Cu")
		(net 15)
	)
	(segment
		(start 141.221 85.601718)
		(end 140.937215 85.317933)
		(width 0.16)
		(layer "In5.Cu")
		(net 15)
	)
	(segment
		(start 140.220718 89.16)
		(end 140.379282 89.16)
		(width 0.16)
		(layer "In5.Cu")
		(net 15)
	)
	(segment
		(start 141.221 88.318285)
		(end 141.221 87.541)
		(width 0.16)
		(layer "In5.Cu")
		(net 15)
	)
	(segment
		(start 140.461114 89.078171)
		(end 141.221 88.318285)
		(width 0.16)
		(layer "In5.Cu")
		(net 15)
	)
	(segment
		(start 129.15 77.49)
		(end 129.15 77.141)
		(width 0.16)
		(layer "In5.Cu")
		(net 15)
	)
	(segment
		(start 125.668282 78.449)
		(end 124.718282 77.499)
		(width 0.16)
		(layer "In5.Cu")
		(net 15)
	)
	(segment
		(start 137.440223 80.145245)
		(end 137.157379 79.862403)
		(width 0.16)
		(layer "In5.Cu")
		(net 15)
	)
	(segment
		(start 141.219352 84.294751)
		(end 141.219351 84.294752)
		(width 0.16)
		(layer "In5.Cu")
		(net 15)
	)
	(segment
		(start 140.937215 84.576885)
		(end 141.219352 84.294751)
		(width 0.16)
		(layer "In5.Cu")
		(net 15)
	)
	(segment
		(start 128.648 77.141)
		(end 128.648 77.49)
		(width 0.16)
		(layer "In5.Cu")
		(net 15)
	)
	(segment
		(start 138.621 83.001718)
		(end 138.621 82.031718)
		(width 0.16)
		(layer "In5.Cu")
		(net 15)
	)
	(segment
		(start 135.830851 79.03085)
		(end 135.830852 79.030852)
		(width 0.16)
		(layer "In5.Cu")
		(net 15)
	)
	(segment
		(start 139.858172 83.462487)
		(end 139.610685 83.215)
		(width 0.16)
		(layer "In5.Cu")
		(net 15)
	)
	(segment
		(start 136.344208 80.638808)
		(end 136.344209 80.638807)
		(width 0.16)
		(layer "In5.Cu")
		(net 15)
	)
	(segment
		(start 136.379567 79.084589)
		(end 136.096723 78.801747)
		(width 0.16)
		(layer "In5.Cu")
		(net 15)
	)
	(segment
		(start 140.512246 84.362633)
		(end 139.840493 85.034384)
		(width 0.16)
		(layer "In5.Cu")
		(net 15)
	)
	(segment
		(start 134.542505 78.837106)
		(end 134.824641 78.554971)
		(width 0.16)
		(layer "In5.Cu")
		(net 15)
	)
	(segment
		(start 139.59 88.18)
		(end 139.59 88.529282)
		(width 0.16)
		(layer "In5.Cu")
		(net 15)
	)
	(segment
		(start 124.718282 77.499)
		(end 121.211718 77.499)
		(width 0.16)
		(layer "In5.Cu")
		(net 15)
	)
	(segment
		(start 139.099446 84.293337)
		(end 139.858171 83.534611)
		(width 0.16)
		(layer "In5.Cu")
		(net 15)
	)
	(segment
		(start 140.379282 89.16)
		(end 140.461114 89.078171)
		(width 0.16)
		(layer "In5.Cu")
		(net 15)
	)
	(segment
		(start 120.746323 77.964395)
		(end 120.746323 78.891866)
		(width 0.16)
		(layer "In5.Cu")
		(net 15)
	)
	(segment
		(start 140.303 86.267)
		(end 140.306134 86.267)
		(width 0.16)
		(layer "In5.Cu")
		(net 15)
	)
	(segment
		(start 136.858271 81.469656)
		(end 136.858272 81.469656)
		(width 0.16)
		(layer "In5.Cu")
		(net 15)
	)
	(segment
		(start 120.746323 78.891866)
		(end 120.894323 79.039866)
		(width 0.16)
		(layer "In5.Cu")
		(net 15)
	)
	(segment
		(start 138.93964 83.320357)
		(end 138.621 83.001718)
		(width 0.16)
		(layer "In5.Cu")
		(net 15)
	)
	(segment
		(start 139.610685 83.215)
		(end 139.610684 83.214998)
		(width 0.16)
		(layer "In5.Cu")
		(net 15)
	)
	(segment
		(start 134.824641 78.554971)
		(end 134.824641 78.554972)
		(width 0.16)
		(layer "In5.Cu")
		(net 15)
	)
	(arc
		(start 139.853 85.517)
		(mid 140.012099 85.582901)
		(end 140.078 85.742)
		(width 0.16)
		(layer "In5.Cu")
		(net 15)
	)
	(arc
		(start 135.283553 79.578152)
		(mid 134.913029 79.731629)
		(end 134.542505 79.578154)
		(width 0.16)
		(layer "In5.Cu")
		(net 15)
	)
	(arc
		(start 139.099446 85.034385)
		(mid 138.94597 84.663861)
		(end 139.099446 84.293337)
		(width 0.16)
		(layer "In5.Cu")
		(net 15)
	)
	(arc
		(start 135.603161 80.638809)
		(mid 135.449685 80.268285)
		(end 135.603161 79.897761)
		(width 0.16)
		(layer "In5.Cu")
		(net 15)
	)
	(arc
		(start 139.610684 83.214998)
		(mid 139.574621 83.200061)
		(end 139.538559 83.214999)
		(width 0.16)
		(layer "In5.Cu")
		(net 15)
	)
	(arc
		(start 139.840493 85.034384)
		(mid 139.46997 85.18786)
		(end 139.099446 85.034385)
		(width 0.16)
		(layer "In5.Cu")
		(net 15)
	)
	(arc
		(start 137.988933 81.399651)
		(mid 137.846804 81.34078)
		(end 137.704676 81.399652)
		(width 0.16)
		(layer "In5.Cu")
		(net 15)
	)
	(arc
		(start 136.379567 79.121359)
		(mid 136.387182 79.102974)
		(end 136.379567 79.084589)
		(width 0.16)
		(layer "In5.Cu")
		(net 15)
	)
	(arc
		(start 129.699 78.039)
		(mid 129.310798 77.878202)
		(end 129.15 77.49)
		(width 0.16)
		(layer "In5.Cu")
		(net 15)
	)
	(arc
		(start 139.113042 87.315)
		(mid 138.742518 87.161524)
		(end 138.589042 86.791)
		(width 0.16)
		(layer "In5.Cu")
		(net 15)
	)
	(arc
		(start 140.078 86.042)
		(mid 140.143901 86.201099)
		(end 140.303 86.267)
		(width 0.16)
		(layer "In5.Cu")
		(net 15)
	)
	(arc
		(start 128.648 77.49)
		(mid 128.487202 77.878202)
		(end 128.099 78.039)
		(width 0.16)
		(layer "In5.Cu")
		(net 15)
	)
	(arc
		(start 137.599318 81.505011)
		(mid 137.246472 81.651165)
		(end 136.893626 81.505011)
		(width 0.16)
		(layer "In5.Cu")
		(net 15)
	)
	(arc
		(start 138.589042 86.791)
		(mid 138.742518 86.420476)
		(end 139.113042 86.267)
		(width 0.16)
		(layer "In5.Cu")
		(net 15)
	)
	(arc
		(start 139.858171 83.534612)
		(mid 139.873109 83.49855)
		(end 139.858172 83.462487)
		(width 0.16)
		(layer "In5.Cu")
		(net 15)
	)
	(arc
		(start 134.542505 79.578154)
		(mid 134.389029 79.20763)
		(end 134.542505 78.837106)
		(width 0.16)
		(layer "In5.Cu")
		(net 15)
	)
	(arc
		(start 128.899 76.89)
		(mid 128.721516 76.963516)
		(end 128.648 77.141)
		(width 0.16)
		(layer "In5.Cu")
		(net 15)
	)
	(arc
		(start 136.858272 81.469656)
		(mid 136.712118 81.11681)
		(end 136.858271 80.763963)
		(width 0.16)
		(layer "In5.Cu")
		(net 15)
	)
	(arc
		(start 139.433202 83.320359)
		(mid 139.186422 83.422579)
		(end 138.93964 83.320357)
		(width 0.16)
		(layer "In5.Cu")
		(net 15)
	)
	(arc
		(start 141.219351 84.294752)
		(mid 141.285545 84.134945)
		(end 141.219352 83.975139)
		(width 0.16)
		(layer "In5.Cu")
		(net 15)
	)
	(arc
		(start 137.157379 79.862403)
		(mid 137.138994 79.854788)
		(end 137.120609 79.862403)
		(width 0.16)
		(layer "In5.Cu")
		(net 15)
	)
	(arc
		(start 141.219352 83.975139)
		(mid 141.059546 83.908945)
		(end 140.89974 83.975139)
		(width 0.16)
		(layer "In5.Cu")
		(net 15)
	)
	(arc
		(start 141.221 87.541)
		(mid 141.154806 87.381194)
		(end 140.995 87.315)
		(width 0.16)
		(layer "In5.Cu")
		(net 15)
	)
	(arc
		(start 134.824641 78.554972)
		(mid 134.890835 78.395165)
		(end 134.824641 78.235358)
		(width 0.16)
		(layer "In5.Cu")
		(net 15)
	)
	(arc
		(start 129.15 77.141)
		(mid 129.076484 76.963516)
		(end 128.899 76.89)
		(width 0.16)
		(layer "In5.Cu")
		(net 15)
	)
	(arc
		(start 139.403 86.267)
		(mid 139.562099 86.201099)
		(end 139.628 86.042)
		(width 0.16)
		(layer "In5.Cu")
		(net 15)
	)
	(arc
		(start 140.937215 85.317933)
		(mid 140.783739 84.947409)
		(end 140.937215 84.576885)
		(width 0.16)
		(layer "In5.Cu")
		(net 15)
	)
	(arc
		(start 136.096723 78.801747)
		(mid 136.078338 78.794132)
		(end 136.059953 78.801747)
		(width 0.16)
		(layer "In5.Cu")
		(net 15)
	)
	(arc
		(start 140.995 86.267)
		(mid 141.154806 86.200806)
		(end 141.221 86.041)
		(width 0.16)
		(layer "In5.Cu")
		(net 15)
	)
	(arc
		(start 136.344209 80.638807)
		(mid 135.973685 80.792284)
		(end 135.603161 80.638809)
		(width 0.16)
		(layer "In5.Cu")
		(net 15)
	)
	(arc
		(start 139.628 85.742)
		(mid 139.693901 85.582901)
		(end 139.853 85.517)
		(width 0.16)
		(layer "In5.Cu")
		(net 15)
	)
	(arc
		(start 137.440223 80.182015)
		(mid 137.447838 80.16363)
		(end 137.440223 80.145245)
		(width 0.16)
		(layer "In5.Cu")
		(net 15)
	)
	(segment
		(start 140.0095 88.9905)
		(end 140.2095 88.9905)
		(width 0.155)
		(layer "B.Cu")
		(net 15)
	)
	(segment
		(start 140.2095 89.3905)
		(end 140.0095 89.3905)
		(width 0.155)
		(layer "B.Cu")
		(net 15)
	)
	(segment
		(start 139.8095 88.678074)
		(end 139.8095 88.7905)
		(width 0.155)
		(layer "B.Cu")
		(net 15)
	)
	(segment
		(start 136.6195 93.288074)
		(end 138.211926 94.8805)
		(width 0.155)
		(layer "B.Cu")
		(net 15)
	)
	(segment
		(start 140.248074 94.8805)
		(end 140.528074 94.6005)
		(width 0.155)
		(layer "B.Cu")
		(net 15)
	)
	(segment
		(start 137.251926 91.8095)
		(end 136.6195 92.441926)
		(width 0.155)
		(layer "B.Cu")
		(net 15)
	)
	(segment
		(start 139.8095 89.6405)
		(end 139.8095 89.981926)
		(width 0.155)
		(layer "B.Cu")
		(net 15)
	)
	(segment
		(start 142.5995 94.6005)
		(end 142.7 94.5)
		(width 0.155)
		(layer "B.Cu")
		(net 15)
	)
	(segment
		(start 137.981926 91.8095)
		(end 137.251926 91.8095)
		(width 0.155)
		(layer "B.Cu")
		(net 15)
	)
	(segment
		(start 142.7 94.5)
		(end 143.15 94.5)
		(width 0.155)
		(layer "B.Cu")
		(net 15)
	)
	(segment
		(start 140.528074 94.6005)
		(end 142.5995 94.6005)
		(width 0.155)
		(layer "B.Cu")
		(net 15)
	)
	(segment
		(start 139.8095 89.5905)
		(end 139.8095 89.6405)
		(width 0.155)
		(layer "B.Cu")
		(net 15)
	)
	(segment
		(start 139.59 88.18)
		(end 139.59 88.458574)
		(width 0.155)
		(layer "B.Cu")
		(net 15)
	)
	(segment
		(start 139.8095 89.981926)
		(end 137.981926 91.8095)
		(width 0.155)
		(layer "B.Cu")
		(net 15)
	)
	(segment
		(start 139.59 88.458574)
		(end 139.8095 88.678074)
		(width 0.155)
		(layer "B.Cu")
		(net 15)
	)
	(segment
		(start 138.211926 94.8805)
		(end 140.248074 94.8805)
		(width 0.155)
		(layer "B.Cu")
		(net 15)
	)
	(segment
		(start 136.6195 92.441926)
		(end 136.6195 93.288074)
		(width 0.155)
		(layer "B.Cu")
		(net 15)
	)
	(arc
		(start 140.0095 89.3905)
		(mid 139.868079 89.449079)
		(end 139.8095 89.5905)
		(width 0.155)
		(layer "B.Cu")
		(net 15)
	)
	(arc
		(start 140.4095 89.1905)
		(mid 140.350921 89.331921)
		(end 140.2095 89.3905)
		(width 0.155)
		(layer "B.Cu")
		(net 15)
	)
	(arc
		(start 140.2095 88.9905)
		(mid 140.350921 89.049079)
		(end 140.4095 89.1905)
		(width 0.155)
		(layer "B.Cu")
		(net 15)
	)
	(arc
		(start 139.8095 88.7905)
		(mid 139.868079 88.931921)
		(end 140.0095 88.9905)
		(width 0.155)
		(layer "B.Cu")
		(net 15)
	)
	(segment
		(start 120.438074 73.1105)
		(end 120.697823 72.850751)
		(width 0.155)
		(layer "F.Cu")
		(net 16)
	)
	(segment
		(start 118.131926 77.6505)
		(end 118.391926 77.9105)
		(width 0.155)
		(layer "F.Cu")
		(net 16)
	)
	(segment
		(start 119.2205 75.161926)
		(end 119.2205 73.738074)
		(width 0.155)
		(layer "F.Cu")
		(net 16)
	)
	(segment
		(start 113.451926 77.6505)
		(end 115.2005 77.6505)
		(width 0.155)
		(layer "F.Cu")
		(net 16)
	)
	(segment
		(start 120.697823 72.850751)
		(end 120.697823 72.830636)
		(width 0.155)
		(layer "F.Cu")
		(net 16)
	)
	(segment
		(start 115.841948 77.6505)
		(end 115.9005 77.6505)
		(width 0.155)
		(layer "F.Cu")
		(net 16)
	)
	(segment
		(start 119.628074 77.9105)
		(end 120.3305 77.208074)
		(width 0.155)
		(layer "F.Cu")
		(net 16)
	)
	(segment
		(start 120.3305 76.271926)
		(end 119.2205 75.161926)
		(width 0.155)
		(layer "F.Cu")
		(net 16)
	)
	(segment
		(start 115.9005 77.6505)
		(end 118.131926 77.6505)
		(width 0.155)
		(layer "F.Cu")
		(net 16)
	)
	(segment
		(start 119.2205 73.738074)
		(end 119.848074 73.1105)
		(width 0.155)
		(layer "F.Cu")
		(net 16)
	)
	(segment
		(start 118.391926 77.9105)
		(end 119.628074 77.9105)
		(width 0.155)
		(layer "F.Cu")
		(net 16)
	)
	(segment
		(start 110.8 75)
		(end 111.411426 75)
		(width 0.155)
		(layer "F.Cu")
		(net 16)
	)
	(segment
		(start 119.848074 73.1105)
		(end 120.438074 73.1105)
		(width 0.155)
		(layer "F.Cu")
		(net 16)
	)
	(segment
		(start 111.8395 76.038074)
		(end 113.451926 77.6505)
		(width 0.155)
		(layer "F.Cu")
		(net 16)
	)
	(segment
		(start 120.3305 77.208074)
		(end 120.3305 76.271926)
		(width 0.155)
		(layer "F.Cu")
		(net 16)
	)
	(segment
		(start 111.411426 75)
		(end 111.8395 75.428074)
		(width 0.155)
		(layer "F.Cu")
		(net 16)
	)
	(segment
		(start 120.697823 72.830636)
		(end 120.597323 72.730136)
		(width 0.155)
		(layer "F.Cu")
		(net 16)
	)
	(segment
		(start 111.8395 75.428074)
		(end 111.8395 76.038074)
		(width 0.155)
		(layer "F.Cu")
		(net 16)
	)
	(segment
		(start 115.491948 77.359052)
		(end 115.5505 77.359052)
		(width 0.155)
		(layer "F.Cu")
		(net 16)
	)
	(via
		(at 110.8 75)
		(size 0.45)
		(drill 0.1)
		(layers "F.Cu" "B.Cu")
		(net 16)
	)
	(arc
		(start 115.5505 77.359052)
		(mid 115.653542 77.401734)
		(end 115.696224 77.504776)
		(width 0.155)
		(layer "F.Cu")
		(net 16)
	)
	(arc
		(start 115.2005 77.6505)
		(mid 115.303542 77.607818)
		(end 115.346224 77.504776)
		(width 0.155)
		(layer "F.Cu")
		(net 16)
	)
	(arc
		(start 115.696224 77.504776)
		(mid 115.738906 77.607818)
		(end 115.841948 77.6505)
		(width 0.155)
		(layer "F.Cu")
		(net 16)
	)
	(arc
		(start 115.346224 77.504776)
		(mid 115.388906 77.401734)
		(end 115.491948 77.359052)
		(width 0.155)
		(layer "F.Cu")
		(net 16)
	)
	(segment
		(start 110.213849 75.2)
		(end 109.877049 74.8632)
		(width 0.155)
		(layer "B.Cu")
		(net 16)
	)
	(segment
		(start 111.2468 74.8332)
		(end 111.08 75)
		(width 0.155)
		(layer "B.Cu")
		(net 16)
	)
	(segment
		(start 110.8 75)
		(end 110.6 75.2)
		(width 0.155)
		(layer "B.Cu")
		(net 16)
	)
	(segment
		(start 111.6993 74.8332)
		(end 111.2468 74.8332)
		(width 0.155)
		(layer "B.Cu")
		(net 16)
	)
	(segment
		(start 111.08 75)
		(end 110.8 75)
		(width 0.155)
		(layer "B.Cu")
		(net 16)
	)
	(segment
		(start 109.877049 74.8632)
		(end 109.4007 74.8632)
		(width 0.155)
		(layer "B.Cu")
		(net 16)
	)
	(segment
		(start 110.6 75.2)
		(end 110.213849 75.2)
		(width 0.155)
		(layer "B.Cu")
		(net 16)
	)
	(segment
		(start 120.347323 79.480136)
		(end 120.447823 79.379636)
		(width 0.155)
		(layer "F.Cu")
		(net 17)
	)
	(segment
		(start 120.447823 79.379636)
		(end 120.447823 79.187366)
		(width 0.155)
		(layer "F.Cu")
		(net 17)
	)
	(segment
		(start 120.447823 79.187366)
		(end 120.300323 79.039866)
		(width 0.155)
		(layer "F.Cu")
		(net 17)
	)
	(via
		(at 120.300323 79.039866)
		(size 0.45)
		(drill 0.1)
		(layers "F.Cu" "B.Cu")
		(net 17)
	)
	(via
		(at 139.13 88.53)
		(size 0.45)
		(drill 0.1)
		(layers "F.Cu" "B.Cu")
		(net 17)
	)
	(segment
		(start 134.751718 77.741)
		(end 129.699 77.741)
		(width 0.16)
		(layer "In5.Cu")
		(net 17)
	)
	(segment
		(start 139.310164 84.504055)
		(end 140.068889 83.745329)
		(width 0.16)
		(layer "In5.Cu")
		(net 17)
	)
	(segment
		(start 139.169282 88.53)
		(end 140.099282 89.46)
		(width 0.16)
		(layer "In5.Cu")
		(net 17)
	)
	(segment
		(start 135.035359 78.765688)
		(end 135.035358 78.765689)
		(width 0.16)
		(layer "In5.Cu")
		(net 17)
	)
	(segment
		(start 137.493959 81.188934)
		(end 137.388601 81.294293)
		(width 0.16)
		(layer "In5.Cu")
		(net 17)
	)
	(segment
		(start 128.099 77.741)
		(end 126.828282 77.741)
		(width 0.16)
		(layer "In5.Cu")
		(net 17)
	)
	(segment
		(start 135.035358 78.024641)
		(end 134.751718 77.741)
		(width 0.16)
		(layer "In5.Cu")
		(net 17)
	)
	(segment
		(start 135.813879 80.108479)
		(end 136.590284 79.332076)
		(width 0.16)
		(layer "In5.Cu")
		(net 17)
	)
	(segment
		(start 139.150357 83.10964)
		(end 138.919 82.878282)
		(width 0.16)
		(layer "In5.Cu")
		(net 17)
	)
	(segment
		(start 138.919 82.878282)
		(end 138.919 81.908281)
		(width 0.16)
		(layer "In5.Cu")
		(net 17)
	)
	(segment
		(start 136.909891 79.651685)
		(end 136.133491 80.42809)
		(width 0.16)
		(layer "In5.Cu")
		(net 17)
	)
	(segment
		(start 140.68902 83.764419)
		(end 140.406886 84.046556)
		(width 0.16)
		(layer "In5.Cu")
		(net 17)
	)
	(segment
		(start 140.500718 89.46)
		(end 141.519 88.441719)
		(width 0.16)
		(layer "In5.Cu")
		(net 17)
	)
	(segment
		(start 134.753223 79.047823)
		(end 135.035359 78.765688)
		(width 0.16)
		(layer "In5.Cu")
		(net 17)
	)
	(segment
		(start 120.448323 78.891866)
		(end 120.300323 79.039866)
		(width 0.16)
		(layer "In5.Cu")
		(net 17)
	)
	(segment
		(start 136.590284 79.332076)
		(end 136.590284 79.332077)
		(width 0.16)
		(layer "In5.Cu")
		(net 17)
	)
	(segment
		(start 141.519 88.441719)
		(end 141.519 87.541)
		(width 0.16)
		(layer "In5.Cu")
		(net 17)
	)
	(segment
		(start 140.301526 84.151913)
		(end 139.629777 84.823666)
		(width 0.16)
		(layer "In5.Cu")
		(net 17)
	)
	(segment
		(start 137.368097 79.651686)
		(end 137.368097 79.651685)
		(width 0.16)
		(layer "In5.Cu")
		(net 17)
	)
	(segment
		(start 140.099282 89.46)
		(end 140.500718 89.46)
		(width 0.16)
		(layer "In5.Cu")
		(net 17)
	)
	(segment
		(start 136.133491 80.42809)
		(end 136.133492 80.42809)
		(width 0.16)
		(layer "In5.Cu")
		(net 17)
	)
	(segment
		(start 138.919 81.908281)
		(end 138.199652 81.188933)
		(width 0.16)
		(layer "In5.Cu")
		(net 17)
	)
	(segment
		(start 124.841718 77.201)
		(end 121.088282 77.201)
		(width 0.16)
		(layer "In5.Cu")
		(net 17)
	)
	(segment
		(start 141.147934 84.787603)
		(end 141.430069 84.505467)
		(width 0.16)
		(layer "In5.Cu")
		(net 17)
	)
	(segment
		(start 137.068989 81.258938)
		(end 137.06899 81.258938)
		(width 0.16)
		(layer "In5.Cu")
		(net 17)
	)
	(segment
		(start 128.35 77.141)
		(end 128.35 77.49)
		(width 0.16)
		(layer "In5.Cu")
		(net 17)
	)
	(segment
		(start 137.650939 79.934528)
		(end 137.368097 79.651686)
		(width 0.16)
		(layer "In5.Cu")
		(net 17)
	)
	(segment
		(start 141.430069 84.505467)
		(end 141.430069 84.505468)
		(width 0.16)
		(layer "In5.Cu")
		(net 17)
	)
	(segment
		(start 129.448 77.49)
		(end 129.448 77.141)
		(width 0.16)
		(layer "In5.Cu")
		(net 17)
	)
	(segment
		(start 126.418282 78.151)
		(end 125.791718 78.151)
		(width 0.16)
		(layer "In5.Cu")
		(net 17)
	)
	(segment
		(start 136.590283 78.873872)
		(end 136.307441 78.59103)
		(width 0.16)
		(layer "In5.Cu")
		(net 17)
	)
	(segment
		(start 137.068989 80.974681)
		(end 137.65094 80.392732)
		(width 0.16)
		(layer "In5.Cu")
		(net 17)
	)
	(segment
		(start 139.821402 83.004282)
		(end 139.821403 83.004282)
		(width 0.16)
		(layer "In5.Cu")
		(net 17)
	)
	(segment
		(start 137.65094 80.392732)
		(end 137.65094 80.392733)
		(width 0.16)
		(layer "In5.Cu")
		(net 17)
	)
	(segment
		(start 141.519 85.478282)
		(end 141.147934 85.107215)
		(width 0.16)
		(layer "In5.Cu")
		(net 17)
	)
	(segment
		(start 139.327842 83.004283)
		(end 139.222483 83.109641)
		(width 0.16)
		(layer "In5.Cu")
		(net 17)
	)
	(segment
		(start 139.222483 83.109641)
		(end 139.222485 83.109642)
		(width 0.16)
		(layer "In5.Cu")
		(net 17)
	)
	(segment
		(start 120.448323 77.840959)
		(end 120.448323 78.891866)
		(width 0.16)
		(layer "In5.Cu")
		(net 17)
	)
	(segment
		(start 125.791718 78.151)
		(end 124.841718 77.201)
		(width 0.16)
		(layer "In5.Cu")
		(net 17)
	)
	(segment
		(start 140.068889 83.251769)
		(end 139.821402 83.004282)
		(width 0.16)
		(layer "In5.Cu")
		(net 17)
	)
	(segment
		(start 140.995 87.017)
		(end 139.113042 87.017)
		(width 0.16)
		(layer "In5.Cu")
		(net 17)
	)
	(segment
		(start 135.849235 78.591029)
		(end 135.072835 79.367434)
		(width 0.16)
		(layer "In5.Cu")
		(net 17)
	)
	(segment
		(start 139.13 88.53)
		(end 139.169282 88.53)
		(width 0.16)
		(layer "In5.Cu")
		(net 17)
	)
	(segment
		(start 137.388601 81.294293)
		(end 137.388601 81.294292)
		(width 0.16)
		(layer "In5.Cu")
		(net 17)
	)
	(segment
		(start 135.072835 79.367434)
		(end 135.072836 79.367434)
		(width 0.16)
		(layer "In5.Cu")
		(net 17)
	)
	(segment
		(start 121.088282 77.201)
		(end 120.448323 77.840959)
		(width 0.16)
		(layer "In5.Cu")
		(net 17)
	)
	(segment
		(start 139.113042 86.565)
		(end 140.995 86.565)
		(width 0.16)
		(layer "In5.Cu")
		(net 17)
	)
	(segment
		(start 141.519 86.041)
		(end 141.519 85.478282)
		(width 0.16)
		(layer "In5.Cu")
		(net 17)
	)
	(segment
		(start 126.828282 77.741)
		(end 126.418282 78.151)
		(width 0.16)
		(layer "In5.Cu")
		(net 17)
	)
	(segment
		(start 137.104344 81.294293)
		(end 137.068989 81.258938)
		(width 0.16)
		(layer "In5.Cu")
		(net 17)
	)
	(segment
		(start 140.406886 84.046556)
		(end 140.301526 84.151913)
		(width 0.16)
		(layer "In5.Cu")
		(net 17)
	)
	(segment
		(start 136.307441 78.59103)
		(end 136.307441 78.591029)
		(width 0.16)
		(layer "In5.Cu")
		(net 17)
	)
	(arc
		(start 136.133492 80.42809)
		(mid 135.973686 80.494285)
		(end 135.813879 80.428091)
		(width 0.16)
		(layer "In5.Cu")
		(net 17)
	)
	(arc
		(start 139.222485 83.109642)
		(mid 139.186421 83.124579)
		(end 139.150357 83.10964)
		(width 0.16)
		(layer "In5.Cu")
		(net 17)
	)
	(arc
		(start 139.113042 87.017)
		(mid 138.953236 86.950806)
		(end 138.887042 86.791)
		(width 0.16)
		(layer "In5.Cu")
		(net 17)
	)
	(arc
		(start 129.699 77.741)
		(mid 129.521516 77.667484)
		(end 129.448 77.49)
		(width 0.16)
		(layer "In5.Cu")
		(net 17)
	)
	(arc
		(start 137.65094 80.392733)
		(mid 137.745837 80.16363)
		(end 137.650939 79.934528)
		(width 0.16)
		(layer "In5.Cu")
		(net 17)
	)
	(arc
		(start 141.147934 85.107215)
		(mid 141.08174 84.947409)
		(end 141.147934 84.787603)
		(width 0.16)
		(layer "In5.Cu")
		(net 17)
	)
	(arc
		(start 136.307441 78.591029)
		(mid 136.078339 78.496132)
		(end 135.849235 78.591029)
		(width 0.16)
		(layer "In5.Cu")
		(net 17)
	)
	(arc
		(start 135.813879 80.428091)
		(mid 135.747685 80.268285)
		(end 135.813879 80.108479)
		(width 0.16)
		(layer "In5.Cu")
		(net 17)
	)
	(arc
		(start 141.430069 84.505468)
		(mid 141.583544 84.134944)
		(end 141.43007 83.764421)
		(width 0.16)
		(layer "In5.Cu")
		(net 17)
	)
	(arc
		(start 135.072836 79.367434)
		(mid 134.91303 79.433629)
		(end 134.753223 79.367435)
		(width 0.16)
		(layer "In5.Cu")
		(net 17)
	)
	(arc
		(start 141.43007 83.764421)
		(mid 141.059546 83.610945)
		(end 140.68902 83.764419)
		(width 0.16)
		(layer "In5.Cu")
		(net 17)
	)
	(arc
		(start 140.995 86.565)
		(mid 141.365524 86.411524)
		(end 141.519 86.041)
		(width 0.16)
		(layer "In5.Cu")
		(net 17)
	)
	(arc
		(start 139.821403 83.004282)
		(mid 139.574622 82.902063)
		(end 139.327842 83.004283)
		(width 0.16)
		(layer "In5.Cu")
		(net 17)
	)
	(arc
		(start 128.35 77.49)
		(mid 128.276484 77.667484)
		(end 128.099 77.741)
		(width 0.16)
		(layer "In5.Cu")
		(net 17)
	)
	(arc
		(start 139.310164 84.823667)
		(mid 139.24397 84.663861)
		(end 139.310164 84.504055)
		(width 0.16)
		(layer "In5.Cu")
		(net 17)
	)
	(arc
		(start 129.448 77.141)
		(mid 129.287202 76.752798)
		(end 128.899 76.592)
		(width 0.16)
		(layer "In5.Cu")
		(net 17)
	)
	(arc
		(start 138.199652 81.188933)
		(mid 137.846805 81.04278)
		(end 137.493959 81.188934)
		(width 0.16)
		(layer "In5.Cu")
		(net 17)
	)
	(arc
		(start 137.368097 79.651685)
		(mid 137.138995 79.556788)
		(end 136.909891 79.651685)
		(width 0.16)
		(layer "In5.Cu")
		(net 17)
	)
	(arc
		(start 141.519 87.541)
		(mid 141.365524 87.170476)
		(end 140.995 87.017)
		(width 0.16)
		(layer "In5.Cu")
		(net 17)
	)
	(arc
		(start 139.629777 84.823666)
		(mid 139.469971 84.889861)
		(end 139.310164 84.823667)
		(width 0.16)
		(layer "In5.Cu")
		(net 17)
	)
	(arc
		(start 136.590284 79.332077)
		(mid 136.685181 79.102974)
		(end 136.590283 78.873872)
		(width 0.16)
		(layer "In5.Cu")
		(net 17)
	)
	(arc
		(start 134.753223 79.367435)
		(mid 134.687029 79.207629)
		(end 134.753223 79.047823)
		(width 0.16)
		(layer "In5.Cu")
		(net 17)
	)
	(arc
		(start 137.06899 81.258938)
		(mid 137.010118 81.11681)
		(end 137.068989 80.974681)
		(width 0.16)
		(layer "In5.Cu")
		(net 17)
	)
	(arc
		(start 135.035358 78.765689)
		(mid 135.188834 78.395165)
		(end 135.035358 78.024641)
		(width 0.16)
		(layer "In5.Cu")
		(net 17)
	)
	(arc
		(start 137.388601 81.294292)
		(mid 137.246473 81.353164)
		(end 137.104344 81.294293)
		(width 0.16)
		(layer "In5.Cu")
		(net 17)
	)
	(arc
		(start 140.068889 83.745329)
		(mid 140.171109 83.498549)
		(end 140.068889 83.251769)
		(width 0.16)
		(layer "In5.Cu")
		(net 17)
	)
	(arc
		(start 138.887042 86.791)
		(mid 138.953236 86.631194)
		(end 139.113042 86.565)
		(width 0.16)
		(layer "In5.Cu")
		(net 17)
	)
	(arc
		(start 128.899 76.592)
		(mid 128.510798 76.752798)
		(end 128.35 77.141)
		(width 0.16)
		(layer "In5.Cu")
		(net 17)
	)
	(segment
		(start 139.5105 89.858074)
		(end 137.858074 91.5105)
		(width 0.155)
		(layer "B.Cu")
		(net 17)
	)
	(segment
		(start 137.858074 91.5105)
		(end 137.128074 91.5105)
		(width 0.155)
		(layer "B.Cu")
		(net 17)
	)
	(segment
		(start 136.3205 93.411926)
		(end 138.088074 95.1795)
		(width 0.155)
		(layer "B.Cu")
		(net 17)
	)
	(segment
		(start 137.128074 91.5105)
		(end 136.3205 92.318074)
		(width 0.155)
		(layer "B.Cu")
		(net 17)
	)
	(segment
		(start 140.371926 95.1795)
		(end 140.651926 94.8995)
		(width 0.155)
		(layer "B.Cu")
		(net 17)
	)
	(segment
		(start 140.651926 94.8995)
		(end 142.5995 94.8995)
		(width 0.155)
		(layer "B.Cu")
		(net 17)
	)
	(segment
		(start 139.238574 88.53)
		(end 139.5105 88.801926)
		(width 0.155)
		(layer "B.Cu")
		(net 17)
	)
	(segment
		(start 142.5995 94.8995)
		(end 142.7 95)
		(width 0.155)
		(layer "B.Cu")
		(net 17)
	)
	(segment
		(start 136.3205 92.318074)
		(end 136.3205 93.411926)
		(width 0.155)
		(layer "B.Cu")
		(net 17)
	)
	(segment
		(start 139.5105 88.801926)
		(end 139.5105 89.858074)
		(width 0.155)
		(layer "B.Cu")
		(net 17)
	)
	(segment
		(start 139.13 88.53)
		(end 139.238574 88.53)
		(width 0.155)
		(layer "B.Cu")
		(net 17)
	)
	(segment
		(start 142.7 95)
		(end 143.15 95)
		(width 0.155)
		(layer "B.Cu")
		(net 17)
	)
	(segment
		(start 138.088074 95.1795)
		(end 140.371926 95.1795)
		(width 0.155)
		(layer "B.Cu")
		(net 17)
	)
	(segment
		(start 118.7095 74.681926)
		(end 118.0895 75.301926)
		(width 0.155)
		(layer "F.Cu")
		(net 18)
	)
	(segment
		(start 118.0895 76.071926)
		(end 117.491926 76.6695)
		(width 0.155)
		(layer "F.Cu")
		(net 18)
	)
	(segment
		(start 119.496823 72.105636)
		(end 119.496823 72.934603)
		(width 0.155)
		(layer "F.Cu")
		(net 18)
	)
	(segment
		(start 119.496823 72.934603)
		(end 118.7095 73.721926)
		(width 0.155)
		(layer "F.Cu")
		(net 18)
	)
	(segment
		(start 117.2575 76.6695)
		(end 117.11 76.817)
		(width 0.155)
		(layer "F.Cu")
		(net 18)
	)
	(segment
		(start 117.491926 76.6695)
		(end 117.2575 76.6695)
		(width 0.155)
		(layer "F.Cu")
		(net 18)
	)
	(segment
		(start 118.0895 75.301926)
		(end 118.0895 76.071926)
		(width 0.155)
		(layer "F.Cu")
		(net 18)
	)
	(segment
		(start 119.597323 72.005136)
		(end 119.496823 72.105636)
		(width 0.155)
		(layer "F.Cu")
		(net 18)
	)
	(segment
		(start 118.7095 73.721926)
		(end 118.7095 74.681926)
		(width 0.155)
		(layer "F.Cu")
		(net 18)
	)
	(via
		(at 91.12789 75.35789)
		(size 0.45)
		(drill 0.1)
		(layers "F.Cu" "B.Cu")
		(net 18)
	)
	(via
		(at 117.11 76.817)
		(size 0.45)
		(drill 0.1)
		(layers "F.Cu" "B.Cu")
		(net 18)
	)
	(segment
		(start 115.24 77.759635)
		(end 115.24 75.680365)
		(width 0.16)
		(layer "In3.Cu")
		(net 18)
	)
	(segment
		(start 91.12789 75.35789)
		(end 91.12789 75.152828)
		(width 0.16)
		(layer "In3.Cu")
		(net 18)
	)
	(segment
		(start 109.758282 76.669)
		(end 112.291 76.669)
		(width 0.16)
		(layer "In3.Cu")
		(net 18)
	)
	(segment
		(start 113.64 77.359635)
		(end 113.64 76.175682)
		(width 0.16)
		(layer "In3.Cu")
		(net 18)
	)
	(segment
		(start 91.12789 75.152828)
		(end 91.491718 74.789)
		(width 0.16)
		(layer "In3.Cu")
		(net 18)
	)
	(segment
		(start 112.542 76.92)
		(end 112.542 77.359635)
		(width 0.16)
		(layer "In3.Cu")
		(net 18)
	)
	(segment
		(start 114.142 76.175682)
		(end 114.142 77.759635)
		(width 0.16)
		(layer "In3.Cu")
		(net 18)
	)
	(segment
		(start 105.888282 75.329)
		(end 106.708282 76.149)
		(width 0.16)
		(layer "In3.Cu")
		(net 18)
	)
	(segment
		(start 109.238282 76.149)
		(end 109.758282 76.669)
		(width 0.16)
		(layer "In3.Cu")
		(net 18)
	)
	(segment
		(start 99.248282 74.789)
		(end 99.788282 75.329)
		(width 0.16)
		(layer "In3.Cu")
		(net 18)
	)
	(segment
		(start 113.686317 76.129365)
		(end 114.095683 76.129365)
		(width 0.16)
		(layer "In3.Cu")
		(net 18)
	)
	(segment
		(start 106.708282 76.149)
		(end 109.238282 76.149)
		(width 0.16)
		(layer "In3.Cu")
		(net 18)
	)
	(segment
		(start 116.291 76.669)
		(end 116.962 76.669)
		(width 0.16)
		(layer "In3.Cu")
		(net 18)
	)
	(segment
		(start 99.788282 75.329)
		(end 105.888282 75.329)
		(width 0.16)
		(layer "In3.Cu")
		(net 18)
	)
	(segment
		(start 91.491718 74.789)
		(end 99.248282 74.789)
		(width 0.16)
		(layer "In3.Cu")
		(net 18)
	)
	(segment
		(start 116.962 76.669)
		(end 117.11 76.817)
		(width 0.16)
		(layer "In3.Cu")
		(net 18)
	)
	(segment
		(start 115.742 75.680365)
		(end 115.742 76.12)
		(width 0.16)
		(layer "In3.Cu")
		(net 18)
	)
	(arc
		(start 114.142 77.759635)
		(mid 114.302798 78.147837)
		(end 114.691 78.308635)
		(width 0.16)
		(layer "In3.Cu")
		(net 18)
	)
	(arc
		(start 114.691 78.308635)
		(mid 115.079202 78.147837)
		(end 115.24 77.759635)
		(width 0.16)
		(layer "In3.Cu")
		(net 18)
	)
	(arc
		(start 115.491 75.429365)
		(mid 115.668484 75.502881)
		(end 115.742 75.680365)
		(width 0.16)
		(layer "In3.Cu")
		(net 18)
	)
	(arc
		(start 113.091 77.908635)
		(mid 113.479202 77.747837)
		(end 113.64 77.359635)
		(width 0.16)
		(layer "In3.Cu")
		(net 18)
	)
	(arc
		(start 113.64 76.175682)
		(mid 113.653566 76.142931)
		(end 113.686317 76.129365)
		(width 0.16)
		(layer "In3.Cu")
		(net 18)
	)
	(arc
		(start 114.095683 76.129365)
		(mid 114.128434 76.142931)
		(end 114.142 76.175682)
		(width 0.16)
		(layer "In3.Cu")
		(net 18)
	)
	(arc
		(start 112.291 76.669)
		(mid 112.468484 76.742516)
		(end 112.542 76.92)
		(width 0.16)
		(layer "In3.Cu")
		(net 18)
	)
	(arc
		(start 115.742 76.12)
		(mid 115.902798 76.508202)
		(end 116.291 76.669)
		(width 0.16)
		(layer "In3.Cu")
		(net 18)
	)
	(arc
		(start 112.542 77.359635)
		(mid 112.702798 77.747837)
		(end 113.091 77.908635)
		(width 0.16)
		(layer "In3.Cu")
		(net 18)
	)
	(arc
		(start 115.24 75.680365)
		(mid 115.313516 75.502881)
		(end 115.491 75.429365)
		(width 0.16)
		(layer "In3.Cu")
		(net 18)
	)
	(segment
		(start 90.811925 75.4695)
		(end 90.298074 75.4695)
		(width 0.155)
		(layer "B.Cu")
		(net 18)
	)
	(segment
		(start 90.09 73.635)
		(end 90.005 73.55)
		(width 0.155)
		(layer "B.Cu")
		(net 18)
	)
	(segment
		(start 90.923535 75.35789)
		(end 90.811925 75.4695)
		(width 0.155)
		(layer "B.Cu")
		(net 18)
	)
	(segment
		(start 89.9405 74.438074)
		(end 90.09 74.288574)
		(width 0.155)
		(layer "B.Cu")
		(net 18)
	)
	(segment
		(start 90.298074 75.4695)
		(end 89.9405 75.111926)
		(width 0.155)
		(layer "B.Cu")
		(net 18)
	)
	(segment
		(start 91.12789 75.35789)
		(end 90.923535 75.35789)
		(width 0.155)
		(layer "B.Cu")
		(net 18)
	)
	(segment
		(start 89.9405 75.111926)
		(end 89.9405 74.438074)
		(width 0.155)
		(layer "B.Cu")
		(net 18)
	)
	(segment
		(start 90.09 74.288574)
		(end 90.09 73.635)
		(width 0.155)
		(layer "B.Cu")
		(net 18)
	)
	(segment
		(start 119.621926 81.9305)
		(end 119.246823 81.555397)
		(width 0.155)
		(layer "F.Cu")
		(net 19)
	)
	(segment
		(start 119.246823 81.030636)
		(end 119.347323 80.930136)
		(width 0.155)
		(layer "F.Cu")
		(net 19)
	)
	(segment
		(start 120.7595 82.288074)
		(end 120.401926 81.9305)
		(width 0.155)
		(layer "F.Cu")
		(net 19)
	)
	(segment
		(start 120.7595 83.123075)
		(end 120.7595 82.288074)
		(width 0.155)
		(layer "F.Cu")
		(net 19)
	)
	(segment
		(start 121.001414 83.364989)
		(end 120.7595 83.123075)
		(width 0.155)
		(layer "F.Cu")
		(net 19)
	)
	(segment
		(start 119.246823 81.555397)
		(end 119.246823 81.030636)
		(width 0.155)
		(layer "F.Cu")
		(net 19)
	)
	(segment
		(start 121.210011 83.364989)
		(end 121.001414 83.364989)
		(width 0.155)
		(layer "F.Cu")
		(net 19)
	)
	(segment
		(start 120.401926 81.9305)
		(end 119.621926 81.9305)
		(width 0.155)
		(layer "F.Cu")
		(net 19)
	)
	(via
		(at 139.04 95.73)
		(size 0.45)
		(drill 0.1)
		(layers "F.Cu" "B.Cu")
		(net 19)
	)
	(via
		(at 121.210011 83.364989)
		(size 0.45)
		(drill 0.1)
		(layers "F.Cu" "B.Cu")
		(net 19)
	)
	(segment
		(start 129.5 86.012)
		(end 129.5 86.289)
		(width 0.16)
		(layer "In5.Cu")
		(net 19)
	)
	(segment
		(start 136.048174 94.297456)
		(end 136.331017 94.5803)
		(width 0.16)
		(layer "In5.Cu")
		(net 19)
	)
	(segment
		(start 134.526 92.315)
		(end 134.675 92.315)
		(width 0.16)
		(layer "In5.Cu")
		(net 19)
	)
	(segment
		(start 134.426 89.415)
		(end 134.575 89.415)
		(width 0.16)
		(layer "In5.Cu")
		(net 19)
	)
	(segment
		(start 137.051718 96.471)
		(end 138.038282 96.471)
		(width 0.16)
		(layer "In5.Cu")
		(net 19)
	)
	(segment
		(start 135.870691 93.414281)
		(end 136.153534 93.697124)
		(width 0.16)
		(layer "In5.Cu")
		(net 19)
	)
	(segment
		(start 136.367789 94.580302)
		(end 136.473146 94.474942)
		(width 0.16)
		(layer "In5.Cu")
		(net 19)
	)
	(segment
		(start 129.5 81.749282)
		(end 129.5 84.912)
		(width 0.16)
		(layer "In5.Cu")
		(net 19)
	)
	(segment
		(start 131.351 82.591)
		(end 132.621718 82.591)
		(width 0.16)
		(layer "In5.Cu")
		(net 19)
	)
	(segment
		(start 126.181718 82.591)
		(end 126.439 82.591)
		(width 0.16)
		(layer "In5.Cu")
		(net 19)
	)
	(segment
		(start 131.1 81.641)
		(end 131.1 82.34)
		(width 0.16)
		(layer "In5.Cu")
		(net 19)
	)
	(segment
		(start 135.424 88.013)
		(end 135.275 88.013)
		(width 0.16)
		(layer "In5.Cu")
		(net 19)
	)
	(segment
		(start 135.898 91.289)
		(end 135.898 91.389)
		(width 0.16)
		(layer "In5.Cu")
		(net 19)
	)
	(segment
		(start 135.898 85.939)
		(end 135.898 86.039)
		(width 0.16)
		(layer "In5.Cu")
		(net 19)
	)
	(segment
		(start 129.176 85.236)
		(end 129.027 85.236)
		(width 0.16)
		(layer "In5.Cu")
		(net 19)
	)
	(segment
		(start 133.214611 83.852816)
		(end 133.77888 83.288543)
		(width 0.16)
		(layer "In5.Cu")
		(net 19)
	)
	(segment
		(start 121.210011 83.574293)
		(end 121.736718 84.101)
		(width 0.16)
		(layer "In5.Cu")
		(net 19)
	)
	(segment
		(start 127.039 82.366031)
		(end 127.039 82.391)
		(width 0.16)
		(layer "In5.Cu")
		(net 19)
	)
	(segment
		(start 135.424 86.513)
		(end 135.275 86.513)
		(width 0.16)
		(layer "In5.Cu")
		(net 19)
	)
	(segment
		(start 122.411 83.888282)
		(end 122.411 82.548282)
		(width 0.16)
		(layer "In5.Cu")
		(net 19)
	)
	(segment
		(start 134.519929 84.029591)
		(end 134.519929 84.029592)
		(width 0.16)
		(layer "In5.Cu")
		(net 19)
	)
	(segment
		(start 132.894998 83.569973)
		(end 133.177841 83.852816)
		(width 0.16)
		(layer "In5.Cu")
		(net 19)
	)
	(segment
		(start 135.275 86.965)
		(end 135.424 86.965)
		(width 0.16)
		(layer "In5.Cu")
		(net 19)
	)
	(segment
		(start 128.568282 81.461)
		(end 129.211718 81.461)
		(width 0.16)
		(layer "In5.Cu")
		(net 19)
	)
	(segment
		(start 130.376 84.014)
		(end 130.525 84.014)
		(width 0.16)
		(layer "In5.Cu")
		(net 19)
	)
	(segment
		(start 121.736718 84.101)
		(end 122.198282 84.101)
		(width 0.16)
		(layer "In5.Cu")
		(net 19)
	)
	(segment
		(start 137.214195 95.215989)
		(end 136.919 95.511182)
		(width 0.16)
		(layer "In5.Cu")
		(net 19)
	)
	(segment
		(start 136.931351 94.474941)
		(end 137.214194 94.757784)
		(width 0.16)
		(layer "In5.Cu")
		(net 19)
	)
	(segment
		(start 122.411 82.548282)
		(end 123.178282 81.781)
		(width 0.16)
		(layer "In5.Cu")
		(net 19)
	)
	(segment
		(start 127.958282 82.591)
		(end 128.205011 82.344271)
		(width 0.16)
		(layer "In5.Cu")
		(net 19)
	)
	(segment
		(start 125.371718 81.781)
		(end 126.181718 82.591)
		(width 0.16)
		(layer "In5.Cu")
		(net 19)
	)
	(segment
		(start 138.613282 95.896)
		(end 138.874 95.896)
		(width 0.16)
		(layer "In5.Cu")
		(net 19)
	)
	(segment
		(start 135.275 90.815)
		(end 135.424 90.815)
		(width 0.16)
		(layer "In5.Cu")
		(net 19)
	)
	(segment
		(start 130.525 83.562)
		(end 130.376 83.562)
		(width 0.16)
		(layer "In5.Cu")
		(net 19)
	)
	(segment
		(start 135.099 88.189)
		(end 135.099 88.439)
		(width 0.16)
		(layer "In5.Cu")
		(net 19)
	)
	(segment
		(start 135.275 85.465)
		(end 135.424 85.465)
		(width 0.16)
		(layer "In5.Cu")
		(net 19)
	)
	(segment
		(start 130.601 83.938)
		(end 130.601 83.638)
		(width 0.16)
		(layer "In5.Cu")
		(net 19)
	)
	(segment
		(start 134.519929 84.029592)
		(end 134.414569 84.134949)
		(width 0.16)
		(layer "In5.Cu")
		(net 19)
	)
	(segment
		(start 138.874 95.896)
		(end 139.04 95.73)
		(width 0.16)
		(layer "In5.Cu")
		(net 19)
	)
	(segment
		(start 122.198282 84.101)
		(end 122.411 83.888282)
		(width 0.16)
		(layer "In5.Cu")
		(net 19)
	)
	(segment
		(start 138.038282 96.471)
		(end 138.613282 95.896)
		(width 0.16)
		(layer "In5.Cu")
		(net 19)
	)
	(segment
		(start 135.099 86.689)
		(end 135.099 86.789)
		(width 0.16)
		(layer "In5.Cu")
		(net 19)
	)
	(segment
		(start 134.4 91.989)
		(end 134.4 92.189)
		(width 0.16)
		(layer "In5.Cu")
		(net 19)
	)
	(segment
		(start 130.002 86.289)
		(end 130.002 86.088)
		(width 0.16)
		(layer "In5.Cu")
		(net 19)
	)
	(segment
		(start 134.44922 83.288545)
		(end 134.449218 83.288544)
		(width 0.16)
		(layer "In5.Cu")
		(net 19)
	)
	(segment
		(start 133.000358 83.427846)
		(end 132.894999 83.533204)
		(width 0.16)
		(layer "In5.Cu")
		(net 19)
	)
	(segment
		(start 135.898 87.439)
		(end 135.898 87.539)
		(width 0.16)
		(layer "In5.Cu")
		(net 19)
	)
	(segment
		(start 135.099 92.739)
		(end 135.099 93.348282)
		(width 0.16)
		(layer "In5.Cu")
		(net 19)
	)
	(segment
		(start 127.239 82.591)
		(end 127.958282 82.591)
		(width 0.16)
		(layer "In5.Cu")
		(net 19)
	)
	(segment
		(start 130.675 85.112)
		(end 130.526 85.112)
		(width 0.16)
		(layer "In5.Cu")
		(net 19)
	)
	(segment
		(start 135.099 85.068282)
		(end 135.099 85.289)
		(width 0.16)
		(layer "In5.Cu")
		(net 19)
	)
	(segment
		(start 128.205011 81.824271)
		(end 128.568282 81.461)
		(width 0.16)
		(layer "In5.Cu")
		(net 19)
	)
	(segment
		(start 123.178282 81.781)
		(end 125.371718 81.781)
		(width 0.16)
		(layer "In5.Cu")
		(net 19)
	)
	(segment
		(start 128.205011 82.344271)
		(end 128.205011 81.824271)
		(width 0.16)
		(layer "In5.Cu")
		(net 19)
	)
	(segment
		(start 134.414568 84.38385)
		(end 135.099 85.068282)
		(width 0.16)
		(layer "In5.Cu")
		(net 19)
	)
	(segment
		(start 133.000358 83.427845)
		(end 133.000358 83.427846)
		(width 0.16)
		(layer "In5.Cu")
		(net 19)
	)
	(segment
		(start 129.211718 81.461)
		(end 129.5 81.749282)
		(width 0.16)
		(layer "In5.Cu")
		(net 19)
	)
	(segment
		(start 135.424 91.863)
		(end 134.526 91.863)
		(width 0.16)
		(layer "In5.Cu")
		(net 19)
	)
	(segment
		(start 121.210011 83.364989)
		(end 121.210011 83.574293)
		(width 0.16)
		(layer "In5.Cu")
		(net 19)
	)
	(segment
		(start 134.449218 83.288544)
		(end 134.519928 83.359254)
		(width 0.16)
		(layer "In5.Cu")
		(net 19)
	)
	(segment
		(start 130.002 84.588)
		(end 130.002 84.388)
		(width 0.16)
		(layer "In5.Cu")
		(net 19)
	)
	(segment
		(start 126.639 82.391)
		(end 126.639 82.366031)
		(width 0.16)
		(layer "In5.Cu")
		(net 19)
	)
	(segment
		(start 135.099 89.939)
		(end 135.099 90.639)
		(width 0.16)
		(layer "In5.Cu")
		(net 19)
	)
	(segment
		(start 134.575 88.963)
		(end 134.426 88.963)
		(width 0.16)
		(layer "In5.Cu")
		(net 19)
	)
	(segment
		(start 135.307129 93.519642)
		(end 135.412486 93.414282)
		(width 0.16)
		(layer "In5.Cu")
		(net 19)
	)
	(segment
		(start 136.919 95.511182)
		(end 136.919 96.338282)
		(width 0.16)
		(layer "In5.Cu")
		(net 19)
	)
	(segment
		(start 136.919 96.338282)
		(end 137.051718 96.471)
		(width 0.16)
		(layer "In5.Cu")
		(net 19)
	)
	(segment
		(start 135.099 93.348282)
		(end 135.270357 93.51964)
		(width 0.16)
		(layer "In5.Cu")
		(net 19)
	)
	(segment
		(start 136.153535 94.155329)
		(end 136.153535 94.15533)
		(width 0.16)
		(layer "In5.Cu")
		(net 19)
	)
	(segment
		(start 130.002 83.188)
		(end 130.002 81.641)
		(width 0.16)
		(layer "In5.Cu")
		(net 19)
	)
	(segment
		(start 129.001 85.262)
		(end 129.001 85.662)
		(width 0.16)
		(layer "In5.Cu")
		(net 19)
	)
	(segment
		(start 136.153535 94.15533)
		(end 136.048175 94.260687)
		(width 0.16)
		(layer "In5.Cu")
		(net 19)
	)
	(segment
		(start 129.027 85.688)
		(end 129.176 85.688)
		(width 0.16)
		(layer "In5.Cu")
		(net 19)
	)
	(segment
		(start 132.621718 82.591)
		(end 133.000358 82.969641)
		(width 0.16)
		(layer "In5.Cu")
		(net 19)
	)
	(segment
		(start 130.526 85.564)
		(end 130.675 85.564)
		(width 0.16)
		(layer "In5.Cu")
		(net 19)
	)
	(arc
		(start 135.099 85.289)
		(mid 135.150549 85.413451)
		(end 135.275 85.465)
		(width 0.16)
		(layer "In5.Cu")
		(net 19)
	)
	(arc
		(start 135.412486 93.414282)
		(mid 135.641588 93.319384)
		(end 135.870691 93.414281)
		(width 0.16)
		(layer "In5.Cu")
		(net 19)
	)
	(arc
		(start 134.414569 84.134949)
		(mid 134.363019 84.259399)
		(end 134.414568 84.38385)
		(width 0.16)
		(layer "In5.Cu")
		(net 19)
	)
	(arc
		(start 133.177841 83.852816)
		(mid 133.196226 83.860431)
		(end 133.214611 83.852816)
		(width 0.16)
		(layer "In5.Cu")
		(net 19)
	)
	(arc
		(start 130.002 84.388)
		(mid 130.111542 84.123542)
		(end 130.376 84.014)
		(width 0.16)
		(layer "In5.Cu")
		(net 19)
	)
	(arc
		(start 132.894999 83.533204)
		(mid 132.887383 83.551588)
		(end 132.894998 83.569973)
		(width 0.16)
		(layer "In5.Cu")
		(net 19)
	)
	(arc
		(start 126.639 82.366031)
		(mid 126.697579 82.22461)
		(end 126.839 82.166031)
		(width 0.16)
		(layer "In5.Cu")
		(net 19)
	)
	(arc
		(start 134.675 92.315)
		(mid 134.974813 92.439187)
		(end 135.099 92.739)
		(width 0.16)
		(layer "In5.Cu")
		(net 19)
	)
	(arc
		(start 130.002 86.088)
		(mid 130.155476 85.717476)
		(end 130.526 85.564)
		(width 0.16)
		(layer "In5.Cu")
		(net 19)
	)
	(arc
		(start 130.601 83.638)
		(mid 130.57874 83.58426)
		(end 130.525 83.562)
		(width 0.16)
		(layer "In5.Cu")
		(net 19)
	)
	(arc
		(start 135.270357 93.51964)
		(mid 135.288744 93.527257)
		(end 135.307129 93.519642)
		(width 0.16)
		(layer "In5.Cu")
		(net 19)
	)
	(arc
		(start 134.2 89.189)
		(mid 134.266194 89.348806)
		(end 134.426 89.415)
		(width 0.16)
		(layer "In5.Cu")
		(net 19)
	)
	(arc
		(start 135.099 90.639)
		(mid 135.150549 90.763451)
		(end 135.275 90.815)
		(width 0.16)
		(layer "In5.Cu")
		(net 19)
	)
	(arc
		(start 130.376 83.562)
		(mid 130.111542 83.452458)
		(end 130.002 83.188)
		(width 0.16)
		(layer "In5.Cu")
		(net 19)
	)
	(arc
		(start 136.048175 94.260687)
		(mid 136.040559 94.279071)
		(end 136.048174 94.297456)
		(width 0.16)
		(layer "In5.Cu")
		(net 19)
	)
	(arc
		(start 135.898 86.039)
		(mid 135.759169 86.374169)
		(end 135.424 86.513)
		(width 0.16)
		(layer "In5.Cu")
		(net 19)
	)
	(arc
		(start 130.526 85.112)
		(mid 130.155476 84.958524)
		(end 130.002 84.588)
		(width 0.16)
		(layer "In5.Cu")
		(net 19)
	)
	(arc
		(start 129.001 85.662)
		(mid 129.008615 85.680385)
		(end 129.027 85.688)
		(width 0.16)
		(layer "In5.Cu")
		(net 19)
	)
	(arc
		(start 135.275 86.513)
		(mid 135.150549 86.564549)
		(end 135.099 86.689)
		(width 0.16)
		(layer "In5.Cu")
		(net 19)
	)
	(arc
		(start 126.439 82.591)
		(mid 126.580421 82.532421)
		(end 126.639 82.391)
		(width 0.16)
		(layer "In5.Cu")
		(net 19)
	)
	(arc
		(start 136.473146 94.474942)
		(mid 136.702248 94.380044)
		(end 136.931351 94.474941)
		(width 0.16)
		(layer "In5.Cu")
		(net 19)
	)
	(arc
		(start 134.4 92.189)
		(mid 134.436905 92.278095)
		(end 134.526 92.315)
		(width 0.16)
		(layer "In5.Cu")
		(net 19)
	)
	(arc
		(start 136.331017 94.5803)
		(mid 136.349404 94.587917)
		(end 136.367789 94.580302)
		(width 0.16)
		(layer "In5.Cu")
		(net 19)
	)
	(arc
		(start 135.424 86.965)
		(mid 135.759169 87.103831)
		(end 135.898 87.439)
		(width 0.16)
		(layer "In5.Cu")
		(net 19)
	)
	(arc
		(start 126.839 82.166031)
		(mid 126.980421 82.22461)
		(end 127.039 82.366031)
		(width 0.16)
		(layer "In5.Cu")
		(net 19)
	)
	(arc
		(start 130.002 81.641)
		(mid 130.162798 81.252798)
		(end 130.551 81.092)
		(width 0.16)
		(layer "In5.Cu")
		(net 19)
	)
	(arc
		(start 135.099 86.789)
		(mid 135.150549 86.913451)
		(end 135.275 86.965)
		(width 0.16)
		(layer "In5.Cu")
		(net 19)
	)
	(arc
		(start 127.039 82.391)
		(mid 127.097579 82.532421)
		(end 127.239 82.591)
		(width 0.16)
		(layer "In5.Cu")
		(net 19)
	)
	(arc
		(start 133.77888 83.288543)
		(mid 134.11405 83.149712)
		(end 134.44922 83.288545)
		(width 0.16)
		(layer "In5.Cu")
		(net 19)
	)
	(arc
		(start 134.526 91.863)
		(mid 134.436905 91.899905)
		(end 134.4 91.989)
		(width 0.16)
		(layer "In5.Cu")
		(net 19)
	)
	(arc
		(start 130.901 85.338)
		(mid 130.834806 85.178194)
		(end 130.675 85.112)
		(width 0.16)
		(layer "In5.Cu")
		(net 19)
	)
	(arc
		(start 129.027 85.236)
		(mid 129.008615 85.243615)
		(end 129.001 85.262)
		(width 0.16)
		(layer "In5.Cu")
		(net 19)
	)
	(arc
		(start 130.551 81.092)
		(mid 130.939202 81.252798)
		(end 131.1 81.641)
		(width 0.16)
		(layer "In5.Cu")
		(net 19)
	)
	(arc
		(start 135.898 91.389)
		(mid 135.759169 91.724169)
		(end 135.424 91.863)
		(width 0.16)
		(layer "In5.Cu")
		(net 19)
	)
	(arc
		(start 129.5 84.912)
		(mid 129.405103 85.141103)
		(end 129.176 85.236)
		(width 0.16)
		(layer "In5.Cu")
		(net 19)
	)
	(arc
		(start 134.426 88.963)
		(mid 134.266194 89.029194)
		(end 134.2 89.189)
		(width 0.16)
		(layer "In5.Cu")
		(net 19)
	)
	(arc
		(start 135.099 88.439)
		(mid 134.945524 88.809524)
		(end 134.575 88.963)
		(width 0.16)
		(layer "In5.Cu")
		(net 19)
	)
	(arc
		(start 135.898 87.539)
		(mid 135.759169 87.874169)
		(end 135.424 88.013)
		(width 0.16)
		(layer "In5.Cu")
		(net 19)
	)
	(arc
		(start 129.5 86.289)
		(mid 129.573516 86.466484)
		(end 129.751 86.54)
		(width 0.16)
		(layer "In5.Cu")
		(net 19)
	)
	(arc
		(start 131.1 82.34)
		(mid 131.173516 82.517484)
		(end 131.351 82.591)
		(width 0.16)
		(layer "In5.Cu")
		(net 19)
	)
	(arc
		(start 129.751 86.54)
		(mid 129.928484 86.466484)
		(end 130.002 86.289)
		(width 0.16)
		(layer "In5.Cu")
		(net 19)
	)
	(arc
		(start 130.525 84.014)
		(mid 130.57874 83.99174)
		(end 130.601 83.938)
		(width 0.16)
		(layer "In5.Cu")
		(net 19)
	)
	(arc
		(start 134.519928 83.359254)
		(mid 134.65876 83.694422)
		(end 134.519929 84.029591)
		(width 0.16)
		(layer "In5.Cu")
		(net 19)
	)
	(arc
		(start 137.214194 94.757784)
		(mid 137.309092 94.986886)
		(end 137.214195 95.215989)
		(width 0.16)
		(layer "In5.Cu")
		(net 19)
	)
	(arc
		(start 135.424 85.465)
		(mid 135.759169 85.603831)
		(end 135.898 85.939)
		(width 0.16)
		(layer "In5.Cu")
		(net 19)
	)
	(arc
		(start 133.000358 82.969641)
		(mid 133.095255 83.198743)
		(end 133.000358 83.427845)
		(width 0.16)
		(layer "In5.Cu")
		(net 19)
	)
	(arc
		(start 136.153534 93.697124)
		(mid 136.248432 93.926226)
		(end 136.153535 94.155329)
		(width 0.16)
		(layer "In5.Cu")
		(net 19)
	)
	(arc
		(start 129.176 85.688)
		(mid 129.405103 85.782897)
		(end 129.5 86.012)
		(width 0.16)
		(layer "In5.Cu")
		(net 19)
	)
	(arc
		(start 130.675 85.564)
		(mid 130.834806 85.497806)
		(end 130.901 85.338)
		(width 0.16)
		(layer "In5.Cu")
		(net 19)
	)
	(arc
		(start 135.275 88.013)
		(mid 135.150549 88.064549)
		(end 135.099 88.189)
		(width 0.16)
		(layer "In5.Cu")
		(net 19)
	)
	(arc
		(start 134.575 89.415)
		(mid 134.945524 89.568476)
		(end 135.099 89.939)
		(width 0.16)
		(layer "In5.Cu")
		(net 19)
	)
	(arc
		(start 135.424 90.815)
		(mid 135.759169 90.953831)
		(end 135.898 91.289)
		(width 0.16)
		(layer "In5.Cu")
		(net 19)
	)
	(segment
		(start 143.15 96)
		(end 142.7 96)
		(width 0.155)
		(layer "B.Cu")
		(net 19)
	)
	(segment
		(start 142.7 96)
		(end 142.5995 96.1005)
		(width 0.155)
		(layer "B.Cu")
		(net 19)
	)
	(segment
		(start 140.341926 96.1005)
		(end 140.6095 96.1005)
		(width 0.155)
		(layer "B.Cu")
		(net 19)
	)
	(segment
		(start 140.081926 95.8405)
		(end 139.1505 95.8405)
		(width 0.155)
		(layer "B.Cu")
		(net 19)
	)
	(segment
		(start 142.5995 96.1005)
		(end 142.2095 96.1005)
		(width 0.155)
		(layer "B.Cu")
		(net 19)
	)
	(segment
		(start 141.159 97.0495)
		(end 141.159 96.65)
		(width 0.155)
		(layer "B.Cu")
		(net 19)
	)
	(segment
		(start 140.341926 96.1005)
		(end 140.081926 95.8405)
		(width 0.155)
		(layer "B.Cu")
		(net 19)
	)
	(segment
		(start 141.66 96.65)
		(end 141.66 97.0495)
		(width 0.155)
		(layer "B.Cu")
		(net 19)
	)
	(segment
		(start 139.1505 95.8405)
		(end 139.04 95.73)
		(width 0.155)
		(layer "B.Cu")
		(net 19)
	)
	(arc
		(start 141.66 97.0495)
		(mid 141.58663 97.22663)
		(end 141.4095 97.3)
		(width 0.155)
		(layer "B.Cu")
		(net 19)
	)
	(arc
		(start 141.159 96.65)
		(mid 140.998055 96.261445)
		(end 140.6095 96.1005)
		(width 0.155)
		(layer "B.Cu")
		(net 19)
	)
	(arc
		(start 141.4095 97.3)
		(mid 141.23237 97.22663)
		(end 141.159 97.0495)
		(width 0.155)
		(layer "B.Cu")
		(net 19)
	)
	(arc
		(start 142.2095 96.1005)
		(mid 141.820945 96.261445)
		(end 141.66 96.65)
		(width 0.155)
		(layer "B.Cu")
		(net 19)
	)
	(segment
		(start 118.4105 73.5095)
		(end 118.4105 74.558074)
		(width 0.155)
		(layer "F.Cu")
		(net 20)
	)
	(segment
		(start 119.197823 72.105636)
		(end 119.197823 72.722177)
		(width 0.155)
		(layer "F.Cu")
		(net 20)
	)
	(segment
		(start 117.7905 75.948074)
		(end 117.368074 76.3705)
		(width 0.155)
		(layer "F.Cu")
		(net 20)
	)
	(segment
		(start 117.2575 76.3705)
		(end 117.11 76.223)
		(width 0.155)
		(layer "F.Cu")
		(net 20)
	)
	(segment
		(start 117.368074 76.3705)
		(end 117.2575 76.3705)
		(width 0.155)
		(layer "F.Cu")
		(net 20)
	)
	(segment
		(start 119.097323 72.005136)
		(end 119.197823 72.105636)
		(width 0.155)
		(layer "F.Cu")
		(net 20)
	)
	(segment
		(start 118.4105 74.558074)
		(end 117.7905 75.178074)
		(width 0.155)
		(layer "F.Cu")
		(net 20)
	)
	(segment
		(start 119.197823 72.722177)
		(end 118.4105 73.5095)
		(width 0.155)
		(layer "F.Cu")
		(net 20)
	)
	(segment
		(start 117.7905 75.178074)
		(end 117.7905 75.948074)
		(width 0.155)
		(layer "F.Cu")
		(net 20)
	)
	(via
		(at 90.71211 74.94211)
		(size 0.45)
		(drill 0.1)
		(layers "F.Cu" "B.Cu")
		(net 20)
	)
	(via
		(at 117.11 76.223)
		(size 0.45)
		(drill 0.1)
		(layers "F.Cu" "B.Cu")
		(net 20)
	)
	(segment
		(start 106.011718 75.031)
		(end 99.911718 75.031)
		(width 0.16)
		(layer "In3.Cu")
		(net 20)
	)
	(segment
		(start 91.368282 74.491)
		(end 90.917172 74.94211)
		(width 0.16)
		(layer "In3.Cu")
		(net 20)
	)
	(segment
		(start 106.831718 75.851)
		(end 106.011718 75.031)
		(width 0.16)
		(layer "In3.Cu")
		(net 20)
	)
	(segment
		(start 109.361718 75.851)
		(end 106.831718 75.851)
		(width 0.16)
		(layer "In3.Cu")
		(net 20)
	)
	(segment
		(start 90.917172 74.94211)
		(end 90.71211 74.94211)
		(width 0.16)
		(layer "In3.Cu")
		(net 20)
	)
	(segment
		(start 114.44 77.759635)
		(end 114.44 76.175682)
		(width 0.16)
		(layer "In3.Cu")
		(net 20)
	)
	(segment
		(start 114.095683 75.831365)
		(end 113.686317 75.831365)
		(width 0.16)
		(layer "In3.Cu")
		(net 20)
	)
	(segment
		(start 111.466 75.91818)
		(end 111.466 76.096)
		(width 0.16)
		(layer "In3.Cu")
		(net 20)
	)
	(segment
		(start 114.942 75.680365)
		(end 114.942 77.759635)
		(width 0.16)
		(layer "In3.Cu")
		(net 20)
	)
	(segment
		(start 109.881718 76.371)
		(end 111.191 76.371)
		(width 0.16)
		(layer "In3.Cu")
		(net 20)
	)
	(segment
		(start 99.371718 74.491)
		(end 91.368282 74.491)
		(width 0.16)
		(layer "In3.Cu")
		(net 20)
	)
	(segment
		(start 112.84 77.359635)
		(end 112.84 76.92)
		(width 0.16)
		(layer "In3.Cu")
		(net 20)
	)
	(segment
		(start 117.11 76.223)
		(end 116.962 76.371)
		(width 0.16)
		(layer "In3.Cu")
		(net 20)
	)
	(segment
		(start 116.04 76.12)
		(end 116.04 75.680365)
		(width 0.16)
		(layer "In3.Cu")
		(net 20)
	)
	(segment
		(start 112.016 76.096)
		(end 112.016 75.91818)
		(width 0.16)
		(layer "In3.Cu")
		(net 20)
	)
	(segment
		(start 99.911718 75.031)
		(end 99.371718 74.491)
		(width 0.16)
		(layer "In3.Cu")
		(net 20)
	)
	(segment
		(start 116.962 76.371)
		(end 116.291 76.371)
		(width 0.16)
		(layer "In3.Cu")
		(net 20)
	)
	(segment
		(start 113.342 76.175682)
		(end 113.342 77.359635)
		(width 0.16)
		(layer "In3.Cu")
		(net 20)
	)
	(segment
		(start 109.881718 76.371)
		(end 109.361718 75.851)
		(width 0.16)
		(layer "In3.Cu")
		(net 20)
	)
	(arc
		(start 116.291 76.371)
		(mid 116.113516 76.297484)
		(end 116.04 76.12)
		(width 0.16)
		(layer "In3.Cu")
		(net 20)
	)
	(arc
		(start 112.291 76.371)
		(mid 112.096546 76.290454)
		(end 112.016 76.096)
		(width 0.16)
		(layer "In3.Cu")
		(net 20)
	)
	(arc
		(start 114.44 76.175682)
		(mid 114.339152 75.932213)
		(end 114.095683 75.831365)
		(width 0.16)
		(layer "In3.Cu")
		(net 20)
	)
	(arc
		(start 112.84 76.92)
		(mid 112.679202 76.531798)
		(end 112.291 76.371)
		(width 0.16)
		(layer "In3.Cu")
		(net 20)
	)
	(arc
		(start 113.342 77.359635)
		(mid 113.268484 77.537119)
		(end 113.091 77.610635)
		(width 0.16)
		(layer "In3.Cu")
		(net 20)
	)
	(arc
		(start 113.091 77.610635)
		(mid 112.913516 77.537119)
		(end 112.84 77.359635)
		(width 0.16)
		(layer "In3.Cu")
		(net 20)
	)
	(arc
		(start 115.491 75.131365)
		(mid 115.102798 75.292163)
		(end 114.942 75.680365)
		(width 0.16)
		(layer "In3.Cu")
		(net 20)
	)
	(arc
		(start 111.466 76.096)
		(mid 111.385454 76.290454)
		(end 111.191 76.371)
		(width 0.16)
		(layer "In3.Cu")
		(net 20)
	)
	(arc
		(start 114.942 77.759635)
		(mid 114.868484 77.937119)
		(end 114.691 78.010635)
		(width 0.16)
		(layer "In3.Cu")
		(net 20)
	)
	(arc
		(start 112.016 75.91818)
		(mid 111.935454 75.723726)
		(end 111.741 75.64318)
		(width 0.16)
		(layer "In3.Cu")
		(net 20)
	)
	(arc
		(start 114.691 78.010635)
		(mid 114.513516 77.937119)
		(end 114.44 77.759635)
		(width 0.16)
		(layer "In3.Cu")
		(net 20)
	)
	(arc
		(start 113.686317 75.831365)
		(mid 113.442848 75.932213)
		(end 113.342 76.175682)
		(width 0.16)
		(layer "In3.Cu")
		(net 20)
	)
	(arc
		(start 111.741 75.64318)
		(mid 111.546546 75.723726)
		(end 111.466 75.91818)
		(width 0.16)
		(layer "In3.Cu")
		(net 20)
	)
	(arc
		(start 116.04 75.680365)
		(mid 115.879202 75.292163)
		(end 115.491 75.131365)
		(width 0.16)
		(layer "In3.Cu")
		(net 20)
	)
	(segment
		(start 90.71211 75.146465)
		(end 90.71211 74.94211)
		(width 0.155)
		(layer "B.Cu")
		(net 20)
	)
	(segment
		(start 90.688075 75.1705)
		(end 90.71211 75.146465)
		(width 0.155)
		(layer "B.Cu")
		(net 20)
	)
	(segment
		(start 90.421926 75.1705)
		(end 90.688075 75.1705)
		(width 0.155)
		(layer "B.Cu")
		(net 20)
	)
	(segment
		(start 90.505 73.55)
		(end 90.505 74.296426)
		(width 0.155)
		(layer "B.Cu")
		(net 20)
	)
	(segment
		(start 90.2395 74.561926)
		(end 90.2395 74.988074)
		(width 0.155)
		(layer "B.Cu")
		(net 20)
	)
	(segment
		(start 90.505 74.296426)
		(end 90.2395 74.561926)
		(width 0.155)
		(layer "B.Cu")
		(net 20)
	)
	(segment
		(start 90.2395 74.988074)
		(end 90.421926 75.1705)
		(width 0.155)
		(layer "B.Cu")
		(net 20)
	)
	(segment
		(start 118.947823 81.679249)
		(end 118.947823 81.030636)
		(width 0.155)
		(layer "F.Cu")
		(net 21)
	)
	(segment
		(start 119.498074 82.2295)
		(end 118.947823 81.679249)
		(width 0.155)
		(layer "F.Cu")
		(net 21)
	)
	(segment
		(start 120.278074 82.2295)
		(end 119.498074 82.2295)
		(width 0.155)
		(layer "F.Cu")
		(net 21)
	)
	(segment
		(start 120.789989 83.785011)
		(end 120.789989 83.576414)
		(width 0.155)
		(layer "F.Cu")
		(net 21)
	)
	(segment
		(start 120.4605 82.411926)
		(end 120.278074 82.2295)
		(width 0.155)
		(layer "F.Cu")
		(net 21)
	)
	(segment
		(start 120.789989 83.576414)
		(end 120.4605 83.246925)
		(width 0.155)
		(layer "F.Cu")
		(net 21)
	)
	(segment
		(start 120.4605 83.246925)
		(end 120.4605 82.411926)
		(width 0.155)
		(layer "F.Cu")
		(net 21)
	)
	(segment
		(start 118.947823 81.030636)
		(end 118.847323 80.930136)
		(width 0.155)
		(layer "F.Cu")
		(net 21)
	)
	(via
		(at 120.789989 83.785011)
		(size 0.45)
		(drill 0.1)
		(layers "F.Cu" "B.Cu")
		(net 21)
	)
	(via
		(at 138.99 96.31)
		(size 0.45)
		(drill 0.1)
		(layers "F.Cu" "B.Cu")
		(net 21)
	)
	(segment
		(start 128.502991 82.467727)
		(end 128.502991 81.947727)
		(width 0.16)
		(layer "In5.Cu")
		(net 21)
	)
	(segment
		(start 138.874 96.194)
		(end 138.99 96.31)
		(width 0.16)
		(layer "In5.Cu")
		(net 21)
	)
	(segment
		(start 134.801 92.739)
		(end 134.801 93.471718)
		(width 0.16)
		(layer "In5.Cu")
		(net 21)
	)
	(segment
		(start 134.801 86.689)
		(end 134.801 86.789)
		(width 0.16)
		(layer "In5.Cu")
		(net 21)
	)
	(segment
		(start 135.275 87.263)
		(end 135.424 87.263)
		(width 0.16)
		(layer "In5.Cu")
		(net 21)
	)
	(segment
		(start 134.801 93.471718)
		(end 135.05964 93.730357)
		(width 0.16)
		(layer "In5.Cu")
		(net 21)
	)
	(segment
		(start 132.684281 83.780691)
		(end 132.967124 84.063534)
		(width 0.16)
		(layer "In5.Cu")
		(net 21)
	)
	(segment
		(start 130.3 84.588)
		(end 130.3 84.388)
		(width 0.16)
		(layer "In5.Cu")
		(net 21)
	)
	(segment
		(start 130.376 84.312)
		(end 130.525 84.312)
		(width 0.16)
		(layer "In5.Cu")
		(net 21)
	)
	(segment
		(start 129.088282 81.759)
		(end 129.202 81.872718)
		(width 0.16)
		(layer "In5.Cu")
		(net 21)
	)
	(segment
		(start 130.525 83.264)
		(end 130.376 83.264)
		(width 0.16)
		(layer "In5.Cu")
		(net 21)
	)
	(segment
		(start 129.027 85.986)
		(end 129.176 85.986)
		(width 0.16)
		(layer "In5.Cu")
		(net 21)
	)
	(segment
		(start 128.703 85.262)
		(end 128.703 85.662)
		(width 0.16)
		(layer "In5.Cu")
		(net 21)
	)
	(segment
		(start 136.621 95.399)
		(end 136.621 96.461718)
		(width 0.16)
		(layer "In5.Cu")
		(net 21)
	)
	(segment
		(start 138.161718 96.769)
		(end 138.736718 96.194)
		(width 0.16)
		(layer "In5.Cu")
		(net 21)
	)
	(segment
		(start 135.517846 93.730359)
		(end 135.517846 93.730358)
		(width 0.16)
		(layer "In5.Cu")
		(net 21)
	)
	(segment
		(start 135.837456 94.508174)
		(end 136.1203 94.791017)
		(width 0.16)
		(layer "In5.Cu")
		(net 21)
	)
	(segment
		(start 125.248282 82.079)
		(end 126.058282 82.889)
		(width 0.16)
		(layer "In5.Cu")
		(net 21)
	)
	(segment
		(start 129.202 81.872718)
		(end 129.202 84.912)
		(width 0.16)
		(layer "In5.Cu")
		(net 21)
	)
	(segment
		(start 120.789989 83.785011)
		(end 120.999293 83.785011)
		(width 0.16)
		(layer "In5.Cu")
		(net 21)
	)
	(segment
		(start 137.003477 95.005272)
		(end 136.898117 95.110629)
		(width 0.16)
		(layer "In5.Cu")
		(net 21)
	)
	(segment
		(start 134.575 88.665)
		(end 134.426 88.665)
		(width 0.16)
		(layer "In5.Cu")
		(net 21)
	)
	(segment
		(start 134.801 85.191718)
		(end 134.801 85.289)
		(width 0.16)
		(layer "In5.Cu")
		(net 21)
	)
	(segment
		(start 135.6 85.939)
		(end 135.6 86.039)
		(width 0.16)
		(layer "In5.Cu")
		(net 21)
	)
	(segment
		(start 128.081718 82.889)
		(end 128.502991 82.467727)
		(width 0.16)
		(layer "In5.Cu")
		(net 21)
	)
	(segment
		(start 134.238502 83.499263)
		(end 134.309212 83.569973)
		(width 0.16)
		(layer "In5.Cu")
		(net 21)
	)
	(segment
		(start 121.613282 84.399)
		(end 122.321718 84.399)
		(width 0.16)
		(layer "In5.Cu")
		(net 21)
	)
	(segment
		(start 129.202 86.012)
		(end 129.202 86.289)
		(width 0.16)
		(layer "In5.Cu")
		(net 21)
	)
	(segment
		(start 133.425329 84.063535)
		(end 133.65443 83.83443)
		(width 0.16)
		(layer "In5.Cu")
		(net 21)
	)
	(segment
		(start 135.659974 93.624999)
		(end 135.942817 93.907842)
		(width 0.16)
		(layer "In5.Cu")
		(net 21)
	)
	(segment
		(start 134.102 91.989)
		(end 134.102 92.189)
		(width 0.16)
		(layer "In5.Cu")
		(net 21)
	)
	(segment
		(start 122.709 82.671718)
		(end 123.301718 82.079)
		(width 0.16)
		(layer "In5.Cu")
		(net 21)
	)
	(segment
		(start 135.942817 93.944612)
		(end 135.837457 94.049969)
		(width 0.16)
		(layer "In5.Cu")
		(net 21)
	)
	(segment
		(start 131.351 82.889)
		(end 132.498282 82.889)
		(width 0.16)
		(layer "In5.Cu")
		(net 21)
	)
	(segment
		(start 135.424 87.715)
		(end 135.275 87.715)
		(width 0.16)
		(layer "In5.Cu")
		(net 21)
	)
	(segment
		(start 134.203851 84.594569)
		(end 134.801 85.191718)
		(width 0.16)
		(layer "In5.Cu")
		(net 21)
	)
	(segment
		(start 130.526 85.862)
		(end 130.675 85.862)
		(width 0.16)
		(layer "In5.Cu")
		(net 21)
	)
	(segment
		(start 134.426 89.713)
		(end 134.575 89.713)
		(width 0.16)
		(layer "In5.Cu")
		(net 21)
	)
	(segment
		(start 133.65443 83.83443)
		(end 133.9896 83.499263)
		(width 0.16)
		(layer "In5.Cu")
		(net 21)
	)
	(segment
		(start 136.898117 95.121883)
		(end 136.621 95.399)
		(width 0.16)
		(layer "In5.Cu")
		(net 21)
	)
	(segment
		(start 136.898117 95.110629)
		(end 136.898117 95.121883)
		(width 0.16)
		(layer "In5.Cu")
		(net 21)
	)
	(segment
		(start 138.736718 96.194)
		(end 138.874 96.194)
		(width 0.16)
		(layer "In5.Cu")
		(net 21)
	)
	(segment
		(start 122.709 84.011718)
		(end 122.709 82.671718)
		(width 0.16)
		(layer "In5.Cu")
		(net 21)
	)
	(segment
		(start 130.3 86.289)
		(end 130.3 86.088)
		(width 0.16)
		(layer "In5.Cu")
		(net 21)
	)
	(segment
		(start 130.899 83.938)
		(end 130.899 83.638)
		(width 0.16)
		(layer "In5.Cu")
		(net 21)
	)
	(segment
		(start 120.999293 83.785011)
		(end 121.613282 84.399)
		(width 0.16)
		(layer "In5.Cu")
		(net 21)
	)
	(segment
		(start 135.517846 93.730358)
		(end 135.623205 93.625)
		(width 0.16)
		(layer "In5.Cu")
		(net 21)
	)
	(segment
		(start 135.424 91.565)
		(end 134.526 91.565)
		(width 0.16)
		(layer "In5.Cu")
		(net 21)
	)
	(segment
		(start 134.801 89.939)
		(end 134.801 90.639)
		(width 0.16)
		(layer "In5.Cu")
		(net 21)
	)
	(segment
		(start 123.301718 82.079)
		(end 125.248282 82.079)
		(width 0.16)
		(layer "In5.Cu")
		(net 21)
	)
	(segment
		(start 134.801 88.189)
		(end 134.801 88.439)
		(width 0.16)
		(layer "In5.Cu")
		(net 21)
	)
	(segment
		(start 134.309212 83.818875)
		(end 134.203852 83.924232)
		(width 0.16)
		(layer "In5.Cu")
		(net 21)
	)
	(segment
		(start 132.498282 82.889)
		(end 132.789641 83.180358)
		(width 0.16)
		(layer "In5.Cu")
		(net 21)
	)
	(segment
		(start 135.6 87.439)
		(end 135.6 87.539)
		(width 0.16)
		(layer "In5.Cu")
		(net 21)
	)
	(segment
		(start 136.928282 96.769)
		(end 138.161718 96.769)
		(width 0.16)
		(layer "In5.Cu")
		(net 21)
	)
	(segment
		(start 130.802 81.641)
		(end 130.802 82.34)
		(width 0.16)
		(layer "In5.Cu")
		(net 21)
	)
	(segment
		(start 130.3 83.188)
		(end 130.3 81.641)
		(width 0.16)
		(layer "In5.Cu")
		(net 21)
	)
	(segment
		(start 136.621 96.461718)
		(end 136.928282 96.769)
		(width 0.16)
		(layer "In5.Cu")
		(net 21)
	)
	(segment
		(start 130.675 84.814)
		(end 130.526 84.814)
		(width 0.16)
		(layer "In5.Cu")
		(net 21)
	)
	(segment
		(start 135.6 91.289)
		(end 135.6 91.389)
		(width 0.16)
		(layer "In5.Cu")
		(net 21)
	)
	(segment
		(start 136.720634 94.685659)
		(end 137.003477 94.968502)
		(width 0.16)
		(layer "In5.Cu")
		(net 21)
	)
	(segment
		(start 136.578506 94.791018)
		(end 136.683865 94.68566)
		(width 0.16)
		(layer "In5.Cu")
		(net 21)
	)
	(segment
		(start 128.691718 81.759)
		(end 129.088282 81.759)
		(width 0.16)
		(layer "In5.Cu")
		(net 21)
	)
	(segment
		(start 135.275 91.113)
		(end 135.424 91.113)
		(width 0.16)
		(layer "In5.Cu")
		(net 21)
	)
	(segment
		(start 136.578506 94.791019)
		(end 136.578506 94.791018)
		(width 0.16)
		(layer "In5.Cu")
		(net 21)
	)
	(segment
		(start 129.176 84.938)
		(end 129.027 84.938)
		(width 0.16)
		(layer "In5.Cu")
		(net 21)
	)
	(segment
		(start 134.526 92.613)
		(end 134.675 92.613)
		(width 0.16)
		(layer "In5.Cu")
		(net 21)
	)
	(segment
		(start 132.789641 83.217128)
		(end 132.684282 83.322486)
		(width 0.16)
		(layer "In5.Cu")
		(net 21)
	)
	(segment
		(start 135.424 86.215)
		(end 135.275 86.215)
		(width 0.16)
		(layer "In5.Cu")
		(net 21)
	)
	(segment
		(start 126.058282 82.889)
		(end 128.081718 82.889)
		(width 0.16)
		(layer "In5.Cu")
		(net 21)
	)
	(segment
		(start 122.321718 84.399)
		(end 122.709 84.011718)
		(width 0.16)
		(layer "In5.Cu")
		(net 21)
	)
	(segment
		(start 135.275 85.763)
		(end 135.424 85.763)
		(width 0.16)
		(layer "In5.Cu")
		(net 21)
	)
	(segment
		(start 128.502991 81.947727)
		(end 128.691718 81.759)
		(width 0.16)
		(layer "In5.Cu")
		(net 21)
	)
	(arc
		(start 136.683865 94.68566)
		(mid 136.702249 94.678044)
		(end 136.720634 94.685659)
		(width 0.16)
		(layer "In5.Cu")
		(net 21)
	)
	(arc
		(start 132.967124 84.063534)
		(mid 133.196226 84.158432)
		(end 133.425329 84.063535)
		(width 0.16)
		(layer "In5.Cu")
		(net 21)
	)
	(arc
		(start 134.526 91.565)
		(mid 134.226187 91.689187)
		(end 134.102 91.989)
		(width 0.16)
		(layer "In5.Cu")
		(net 21)
	)
	(arc
		(start 135.424 87.263)
		(mid 135.548451 87.314549)
		(end 135.6 87.439)
		(width 0.16)
		(layer "In5.Cu")
		(net 21)
	)
	(arc
		(start 130.525 84.312)
		(mid 130.789458 84.202458)
		(end 130.899 83.938)
		(width 0.16)
		(layer "In5.Cu")
		(net 21)
	)
	(arc
		(start 135.05964 93.730357)
		(mid 135.288743 93.825255)
		(end 135.517846 93.730359)
		(width 0.16)
		(layer "In5.Cu")
		(net 21)
	)
	(arc
		(start 134.203852 83.924232)
		(mid 134.06502 84.2594)
		(end 134.203851 84.594569)
		(width 0.16)
		(layer "In5.Cu")
		(net 21)
	)
	(arc
		(start 135.6 87.539)
		(mid 135.548451 87.663451)
		(end 135.424 87.715)
		(width 0.16)
		(layer "In5.Cu")
		(net 21)
	)
	(arc
		(start 134.801 88.439)
		(mid 134.734806 88.598806)
		(end 134.575 88.665)
		(width 0.16)
		(layer "In5.Cu")
		(net 21)
	)
	(arc
		(start 135.942817 93.907842)
		(mid 135.950432 93.926227)
		(end 135.942817 93.944612)
		(width 0.16)
		(layer "In5.Cu")
		(net 21)
	)
	(arc
		(start 134.309212 83.569973)
		(mid 134.360761 83.694424)
		(end 134.309212 83.818875)
		(width 0.16)
		(layer "In5.Cu")
		(net 21)
	)
	(arc
		(start 129.751 86.838)
		(mid 130.139202 86.677202)
		(end 130.3 86.289)
		(width 0.16)
		(layer "In5.Cu")
		(net 21)
	)
	(arc
		(start 135.424 91.113)
		(mid 135.548451 91.164549)
		(end 135.6 91.289)
		(width 0.16)
		(layer "In5.Cu")
		(net 21)
	)
	(arc
		(start 130.3 81.641)
		(mid 130.373516 81.463516)
		(end 130.551 81.39)
		(width 0.16)
		(layer "In5.Cu")
		(net 21)
	)
	(arc
		(start 129.202 84.912)
		(mid 129.194385 84.930385)
		(end 129.176 84.938)
		(width 0.16)
		(layer "In5.Cu")
		(net 21)
	)
	(arc
		(start 130.526 84.814)
		(mid 130.366194 84.747806)
		(end 130.3 84.588)
		(width 0.16)
		(layer "In5.Cu")
		(net 21)
	)
	(arc
		(start 134.102 92.189)
		(mid 134.226187 92.488813)
		(end 134.526 92.613)
		(width 0.16)
		(layer "In5.Cu")
		(net 21)
	)
	(arc
		(start 130.376 83.264)
		(mid 130.32226 83.24174)
		(end 130.3 83.188)
		(width 0.16)
		(layer "In5.Cu")
		(net 21)
	)
	(arc
		(start 134.801 86.789)
		(mid 134.939831 87.124169)
		(end 135.275 87.263)
		(width 0.16)
		(layer "In5.Cu")
		(net 21)
	)
	(arc
		(start 133.902 89.189)
		(mid 134.055476 89.559524)
		(end 134.426 89.713)
		(width 0.16)
		(layer "In5.Cu")
		(net 21)
	)
	(arc
		(start 130.551 81.39)
		(mid 130.728484 81.463516)
		(end 130.802 81.641)
		(width 0.16)
		(layer "In5.Cu")
		(net 21)
	)
	(arc
		(start 132.684282 83.322486)
		(mid 132.589384 83.551588)
		(end 132.684281 83.780691)
		(width 0.16)
		(layer "In5.Cu")
		(net 21)
	)
	(arc
		(start 131.199 85.338)
		(mid 131.045524 84.967476)
		(end 130.675 84.814)
		(width 0.16)
		(layer "In5.Cu")
		(net 21)
	)
	(arc
		(start 135.275 86.215)
		(mid 134.939831 86.353831)
		(end 134.801 86.689)
		(width 0.16)
		(layer "In5.Cu")
		(net 21)
	)
	(arc
		(start 136.1203 94.791017)
		(mid 136.349403 94.885915)
		(end 136.578506 94.791019)
		(width 0.16)
		(layer "In5.Cu")
		(net 21)
	)
	(arc
		(start 134.675 92.613)
		(mid 134.764095 92.649905)
		(end 134.801 92.739)
		(width 0.16)
		(layer "In5.Cu")
		(net 21)
	)
	(arc
		(start 129.202 86.289)
		(mid 129.362798 86.677202)
		(end 129.751 86.838)
		(width 0.16)
		(layer "In5.Cu")
		(net 21)
	)
	(arc
		(start 134.801 85.289)
		(mid 134.939831 85.624169)
		(end 135.275 85.763)
		(width 0.16)
		(layer "In5.Cu")
		(net 21)
	)
	(arc
		(start 130.802 82.34)
		(mid 130.962798 82.728202)
		(end 131.351 82.889)
		(width 0.16)
		(layer "In5.Cu")
		(net 21)
	)
	(arc
		(start 135.6 86.039)
		(mid 135.548451 86.163451)
		(end 135.424 86.215)
		(width 0.16)
		(layer "In5.Cu")
		(net 21)
	)
	(arc
		(start 134.801 90.639)
		(mid 134.939831 90.974169)
		(end 135.275 91.113)
		(width 0.16)
		(layer "In5.Cu")
		(net 21)
	)
	(arc
		(start 135.424 85.763)
		(mid 135.548451 85.814549)
		(end 135.6 85.939)
		(width 0.16)
		(layer "In5.Cu")
		(net 21)
	)
	(arc
		(start 137.003477 94.968502)
		(mid 137.011092 94.986887)
		(end 137.003477 95.005272)
		(width 0.16)
		(layer "In5.Cu")
		(net 21)
	)
	(arc
		(start 129.176 85.986)
		(mid 129.194385 85.993615)
		(end 129.202 86.012)
		(width 0.16)
		(layer "In5.Cu")
		(net 21)
	)
	(arc
		(start 135.6 91.389)
		(mid 135.548451 91.513451)
		(end 135.424 91.565)
		(width 0.16)
		(layer "In5.Cu")
		(net 21)
	)
	(arc
		(start 135.275 87.715)
		(mid 134.939831 87.853831)
		(end 134.801 88.189)
		(width 0.16)
		(layer "In5.Cu")
		(net 21)
	)
	(arc
		(start 133.9896 83.499263)
		(mid 134.114051 83.447714)
		(end 134.238502 83.499263)
		(width 0.16)
		(layer "In5.Cu")
		(net 21)
	)
	(arc
		(start 130.3 86.088)
		(mid 130.366194 85.928194)
		(end 130.526 85.862)
		(width 0.16)
		(layer "In5.Cu")
		(net 21)
	)
	(arc
		(start 134.426 88.665)
		(mid 134.055476 88.818476)
		(end 133.902 89.189)
		(width 0.16)
		(layer "In5.Cu")
		(net 21)
	)
	(arc
		(start 135.623205 93.625)
		(mid 135.641589 93.617384)
		(end 135.659974 93.624999)
		(width 0.16)
		(layer "In5.Cu")
		(net 21)
	)
	(arc
		(start 132.789641 83.180358)
		(mid 132.797256 83.198743)
		(end 132.789641 83.217128)
		(width 0.16)
		(layer "In5.Cu")
		(net 21)
	)
	(arc
		(start 129.027 84.938)
		(mid 128.797897 85.032897)
		(end 128.703 85.262)
		(width 0.16)
		(layer "In5.Cu")
		(net 21)
	)
	(arc
		(start 130.3 84.388)
		(mid 130.32226 84.33426)
		(end 130.376 84.312)
		(width 0.16)
		(layer "In5.Cu")
		(net 21)
	)
	(arc
		(start 134.575 89.713)
		(mid 134.734806 89.779194)
		(end 134.801 89.939)
		(width 0.16)
		(layer "In5.Cu")
		(net 21)
	)
	(arc
		(start 130.675 85.862)
		(mid 131.045524 85.708524)
		(end 131.199 85.338)
		(width 0.16)
		(layer "In5.Cu")
		(net 21)
	)
	(arc
		(start 135.837457 94.049969)
		(mid 135.742559 94.279071)
		(end 135.837456 94.508174)
		(width 0.16)
		(layer "In5.Cu")
		(net 21)
	)
	(arc
		(start 128.703 85.662)
		(mid 128.797897 85.891103)
		(end 129.027 85.986)
		(width 0.16)
		(layer "In5.Cu")
		(net 21)
	)
	(arc
		(start 130.899 83.638)
		(mid 130.789458 83.373542)
		(end 130.525 83.264)
		(width 0.16)
		(layer "In5.Cu")
		(net 21)
	)
	(segment
		(start 140.218074 96.3995)
		(end 140.6095 96.3995)
		(width 0.155)
		(layer "B.Cu")
		(net 21)
	)
	(segment
		(start 141.959 96.65)
		(end 141.959 97.0495)
		(width 0.155)
		(layer "B.Cu")
		(net 21)
	)
	(segment
		(start 142.7 96.5)
		(end 142.5995 96.3995)
		(width 0.155)
		(layer "B.Cu")
		(net 21)
	)
	(segment
		(start 143.15 96.5)
		(end 142.7 96.5)
		(width 0.155)
		(layer "B.Cu")
		(net 21)
	)
	(segment
		(start 139.948574 96.13)
		(end 139.3 96.13)
		(width 0.155)
		(layer "B.Cu")
		(net 21)
	)
	(segment
		(start 140.86 97.0495)
		(end 140.86 96.65)
		(width 0.155)
		(layer "B.Cu")
		(net 21)
	)
	(segment
		(start 139.3 96.13)
		(end 139.12 96.31)
		(width 0.155)
		(layer "B.Cu")
		(net 21)
	)
	(segment
		(start 139.12 96.31)
		(end 138.99 96.31)
		(width 0.155)
		(layer "B.Cu")
		(net 21)
	)
	(segment
		(start 142.5995 96.3995)
		(end 142.2095 96.3995)
		(width 0.155)
		(layer "B.Cu")
		(net 21)
	)
	(segment
		(start 140.218074 96.3995)
		(end 139.948574 96.13)
		(width 0.155)
		(layer "B.Cu")
		(net 21)
	)
	(arc
		(start 141.959 97.0495)
		(mid 141.798055 97.438055)
		(end 141.4095 97.599)
		(width 0.155)
		(layer "B.Cu")
		(net 21)
	)
	(arc
		(start 142.2095 96.3995)
		(mid 142.03237 96.47287)
		(end 141.959 96.65)
		(width 0.155)
		(layer "B.Cu")
		(net 21)
	)
	(arc
		(start 140.86 96.65)
		(mid 140.78663 96.47287)
		(end 140.6095 96.3995)
		(width 0.155)
		(layer "B.Cu")
		(net 21)
	)
	(arc
		(start 141.4095 97.599)
		(mid 141.020945 97.438055)
		(end 140.86 97.0495)
		(width 0.155)
		(layer "B.Cu")
		(net 21)
	)
	(segment
		(start 111.710574 74.312)
		(end 112.2605 74.861926)
		(width 0.155)
		(layer "F.Cu")
		(net 22)
	)
	(segment
		(start 117.996823 73.204603)
		(end 117.996823 72.830636)
		(width 0.155)
		(layer "F.Cu")
		(net 22)
	)
	(segment
		(start 117.996823 72.830636)
		(end 118.097323 72.730136)
		(width 0.155)
		(layer "F.Cu")
		(net 22)
	)
	(segment
		(start 113.118074 76.6695)
		(end 114.391926 76.6695)
		(width 0.155)
		(layer "F.Cu")
		(net 22)
	)
	(segment
		(start 112.2605 74.861926)
		(end 112.2605 75.811926)
		(width 0.155)
		(layer "F.Cu")
		(net 22)
	)
	(segment
		(start 117.551926 73.6495)
		(end 117.996823 73.204603)
		(width 0.155)
		(layer "F.Cu")
		(net 22)
	)
	(segment
		(start 116.571926 73.6495)
		(end 117.551926 73.6495)
		(width 0.155)
		(layer "F.Cu")
		(net 22)
	)
	(segment
		(start 112.2605 75.811926)
		(end 113.118074 76.6695)
		(width 0.155)
		(layer "F.Cu")
		(net 22)
	)
	(segment
		(start 111.113 74.312)
		(end 111.710574 74.312)
		(width 0.155)
		(layer "F.Cu")
		(net 22)
	)
	(segment
		(start 110.975 74.45)
		(end 111.113 74.312)
		(width 0.155)
		(layer "F.Cu")
		(net 22)
	)
	(segment
		(start 115.2995 75.761926)
		(end 115.2995 74.921926)
		(width 0.155)
		(layer "F.Cu")
		(net 22)
	)
	(segment
		(start 115.2995 74.921926)
		(end 116.571926 73.6495)
		(width 0.155)
		(layer "F.Cu")
		(net 22)
	)
	(segment
		(start 114.391926 76.6695)
		(end 115.2995 75.761926)
		(width 0.155)
		(layer "F.Cu")
		(net 22)
	)
	(via
		(at 110.975 74.45)
		(size 0.45)
		(drill 0.1)
		(layers "F.Cu" "B.Cu")
		(net 22)
	)
	(segment
		(start 110.975 74.45)
		(end 111.113 74.312)
		(width 0.155)
		(layer "B.Cu")
		(net 22)
	)
	(segment
		(start 110.8681 74.3431)
		(end 109.862551 74.3431)
		(width 0.155)
		(layer "B.Cu")
		(net 22)
	)
	(segment
		(start 111.113 74.312)
		(end 111.575 74.312)
		(width 0.155)
		(layer "B.Cu")
		(net 22)
	)
	(segment
		(start 110.975 74.45)
		(end 110.8681 74.3431)
		(width 0.155)
		(layer "B.Cu")
		(net 22)
	)
	(segment
		(start 111.693 74.43)
		(end 111.575 74.312)
		(width 0.155)
		(layer "B.Cu")
		(net 22)
	)
	(segment
		(start 109.748851 74.4568)
		(end 109.4007 74.4568)
		(width 0.155)
		(layer "B.Cu")
		(net 22)
	)
	(segment
		(start 109.862551 74.3431)
		(end 109.748851 74.4568)
		(width 0.155)
		(layer "B.Cu")
		(net 22)
	)
	(segment
		(start 111.92 74.43)
		(end 111.693 74.43)
		(width 0.155)
		(layer "B.Cu")
		(net 22)
	)
	(segment
		(start 119.171426 82.97)
		(end 118.955711 82.754286)
		(width 0.155)
		(layer "F.Cu")
		(net 23)
	)
	(segment
		(start 117.612562 82.71787)
		(end 117.89505 82.435379)
		(width 0.155)
		(layer "F.Cu")
		(net 23)
	)
	(segment
		(start 117.612561 82.717871)
		(end 117.612562 82.71787)
		(width 0.155)
		(layer "F.Cu")
		(net 23)
	)
	(segment
		(start 119.736 82.97)
		(end 119.171426 82.97)
		(width 0.155)
		(layer "F.Cu")
		(net 23)
	)
	(segment
		(start 118.213955 82.754286)
		(end 118.213957 82.754287)
		(width 0.155)
		(layer "F.Cu")
		(net 23)
	)
	(segment
		(start 117.895051 81.693625)
		(end 117.746823 81.545397)
		(width 0.155)
		(layer "F.Cu")
		(net 23)
	)
	(segment
		(start 117.612561 83.036774)
		(end 117.612562 83.036776)
		(width 0.155)
		(layer "F.Cu")
		(net 23)
	)
	(segment
		(start 117.895049 81.693624)
		(end 117.895051 81.693625)
		(width 0.155)
		(layer "F.Cu")
		(net 23)
	)
	(segment
		(start 117.847323 80.930136)
		(end 117.847323 80.205136)
		(width 0.155)
		(layer "F.Cu")
		(net 23)
	)
	(segment
		(start 118.213957 82.754287)
		(end 117.931466 83.036775)
		(width 0.155)
		(layer "F.Cu")
		(net 23)
	)
	(segment
		(start 117.746823 81.030636)
		(end 117.847323 80.930136)
		(width 0.155)
		(layer "F.Cu")
		(net 23)
	)
	(segment
		(start 117.746823 81.545397)
		(end 117.746823 81.030636)
		(width 0.155)
		(layer "F.Cu")
		(net 23)
	)
	(segment
		(start 119.96 82.746)
		(end 119.736 82.97)
		(width 0.155)
		(layer "F.Cu")
		(net 23)
	)
	(via
		(at 144.12 93.766)
		(size 0.45)
		(drill 0.1)
		(layers "F.Cu" "B.Cu")
		(net 23)
	)
	(via
		(at 119.96 82.746)
		(size 0.45)
		(drill 0.1)
		(layers "F.Cu" "B.Cu")
		(net 23)
	)
	(arc
		(start 117.612562 83.036776)
		(mid 117.546514 82.877324)
		(end 117.612561 82.717871)
		(width 0.155)
		(layer "F.Cu")
		(net 23)
	)
	(arc
		(start 117.89505 82.435379)
		(mid 118.048672 82.064501)
		(end 117.895049 81.693624)
		(width 0.155)
		(layer "F.Cu")
		(net 23)
	)
	(arc
		(start 118.955711 82.754286)
		(mid 118.584834 82.600664)
		(end 118.213955 82.754286)
		(width 0.155)
		(layer "F.Cu")
		(net 23)
	)
	(arc
		(start 117.931466 83.036775)
		(mid 117.772013 83.102822)
		(end 117.612561 83.036774)
		(width 0.155)
		(layer "F.Cu")
		(net 23)
	)
	(segment
		(start 123.218282 80.301)
		(end 123.499 80.301)
		(width 0.16)
		(layer "In5.Cu")
		(net 23)
	)
	(segment
		(start 138.861 94.298282)
		(end 138.861 93.998282)
		(width 0.16)
		(layer "In5.Cu")
		(net 23)
	)
	(segment
		(start 134.972026 82.563827)
		(end 134.972024 82.563826)
		(width 0.16)
		(layer "In5.Cu")
		(net 23)
	)
	(segment
		(start 120.461 82.708282)
		(end 120.461 82.308282)
		(width 0.16)
		(layer "In5.Cu")
		(net 23)
	)
	(segment
		(start 139.308282 93.551)
		(end 139.308282 93.411718)
		(width 0.16)
		(layer "In5.Cu")
		(net 23)
	)
	(segment
		(start 122.378282 80.761)
		(end 122.758282 80.761)
		(width 0.16)
		(layer "In5.Cu")
		(net 23)
	)
	(segment
		(start 140.091718 93.551)
		(end 140.499 93.958282)
		(width 0.16)
		(layer "In5.Cu")
		(net 23)
	)
	(segment
		(start 135.81843 83.199514)
		(end 135.713072 83.304873)
		(width 0.16)
		(layer "In5.Cu")
		(net 23)
	)
	(segment
		(start 136.699 84.398282)
		(end 136.699 85.089)
		(width 0.16)
		(layer "In5.Cu")
		(net 23)
	)
	(segment
		(start 137.349309 93.448979)
		(end 137.454669 93.34362)
		(width 0.16)
		(layer "In5.Cu")
		(net 23)
	)
	(segment
		(start 122.758282 80.761)
		(end 123.218282 80.301)
		(width 0.16)
		(layer "In5.Cu")
		(net 23)
	)
	(segment
		(start 124.099 79.552)
		(end 124.249 79.552)
		(width 0.16)
		(layer "In5.Cu")
		(net 23)
	)
	(segment
		(start 129.779 79.602)
		(end 129.979 79.602)
		(width 0.16)
		(layer "In5.Cu")
		(net 23)
	)
	(segment
		(start 133.629231 82.209568)
		(end 134.018137 81.820656)
		(width 0.16)
		(layer "In5.Cu")
		(net 23)
	)
	(segment
		(start 134.018137 81.820656)
		(end 134.228856 81.60994)
		(width 0.16)
		(layer "In5.Cu")
		(net 23)
	)
	(segment
		(start 138.271718 94.691)
		(end 138.468282 94.691)
		(width 0.16)
		(layer "In5.Cu")
		(net 23)
	)
	(segment
		(start 142.661 94.691)
		(end 143.068282 94.691)
		(width 0.16)
		(layer "In5.Cu")
		(net 23)
	)
	(segment
		(start 120.105 82.891)
		(end 120.278282 82.891)
		(width 0.16)
		(layer "In5.Cu")
		(net 23)
	)
	(segment
		(start 142.41 93.361736)
		(end 142.41 94.44)
		(width 0.16)
		(layer "In5.Cu")
		(net 23)
	)
	(segment
		(start 136.699 87.839)
		(end 136.699 89.339)
		(width 0.16)
		(layer "In5.Cu")
		(net 23)
	)
	(segment
		(start 127.855 80.175)
		(end 127.855 80.026)
		(width 0.16)
		(layer "In5.Cu")
		(net 23)
	)
	(segment
		(start 137.248 91.871)
		(end 137.248 92.171)
		(width 0.16)
		(layer "In5.Cu")
		(net 23)
	)
	(segment
		(start 136.8 86.69)
		(end 136.949 86.69)
		(width 0.16)
		(layer "In5.Cu")
		(net 23)
	)
	(segment
		(start 137.348 87.089)
		(end 137.348 87.339)
		(width 0.16)
		(layer "In5.Cu")
		(net 23)
	)
	(segment
		(start 140.741718 94.691)
		(end 141.061 94.691)
		(width 0.16)
		(layer "In5.Cu")
		(net 23)
	)
	(segment
		(start 139.83 93.17)
		(end 140.091718 93.431718)
		(width 0.16)
		(layer "In5.Cu")
		(net 23)
	)
	(segment
		(start 131.903 80.026)
		(end 131.903 80.175)
		(width 0.16)
		(layer "In5.Cu")
		(net 23)
	)
	(segment
		(start 135.81843 83.199515)
		(end 135.81843 83.199514)
		(width 0.16)
		(layer "In5.Cu")
		(net 23)
	)
	(segment
		(start 136.899 92.52)
		(end 136.75 92.52)
		(width 0.16)
		(layer "In5.Cu")
		(net 23)
	)
	(segment
		(start 133.309619 82.138858)
		(end 133.380329 82.209568)
		(width 0.16)
		(layer "In5.Cu")
		(net 23)
	)
	(segment
		(start 136.699 86.339)
		(end 136.699 86.589)
		(width 0.16)
		(layer "In5.Cu")
		(net 23)
	)
	(segment
		(start 120.461 82.308282)
		(end 120.928282 81.841)
		(width 0.16)
		(layer "In5.Cu")
		(net 23)
	)
	(segment
		(start 133.909245 81.290329)
		(end 133.309619 81.889956)
		(width 0.16)
		(layer "In5.Cu")
		(net 23)
	)
	(segment
		(start 140.091718 93.431718)
		(end 140.091718 93.551)
		(width 0.16)
		(layer "In5.Cu")
		(net 23)
	)
	(segment
		(start 136.699 92.571)
		(end 136.699 93.118282)
		(width 0.16)
		(layer "In5.Cu")
		(net 23)
	)
	(segment
		(start 132.601718 80.301)
		(end 132.955357 80.65464)
		(width 0.16)
		(layer "In5.Cu")
		(net 23)
	)
	(segment
		(start 138.468282 94.691)
		(end 138.861 94.298282)
		(width 0.16)
		(layer "In5.Cu")
		(net 23)
	)
	(segment
		(start 126.86 80.999)
		(end 126.86 80.8)
		(width 0.16)
		(layer "In5.Cu")
		(net 23)
	)
	(segment
		(start 135.606299 82.458468)
		(end 135.818431 82.6706)
		(width 0.16)
		(layer "In5.Cu")
		(net 23)
	)
	(segment
		(start 124.698 80.001)
		(end 124.698 80.15)
		(width 0.16)
		(layer "In5.Cu")
		(net 23)
	)
	(segment
		(start 138.090358 94.190028)
		(end 138.090358 94.190027)
		(width 0.16)
		(layer "In5.Cu")
		(net 23)
	)
	(segment
		(start 130.855 80.175)
		(end 130.855 80.026)
		(width 0.16)
		(layer "In5.Cu")
		(net 23)
	)
	(segment
		(start 136.75 91.522)
		(end 136.899 91.522)
		(width 0.16)
		(layer "In5.Cu")
		(net 23)
	)
	(segment
		(start 136.8 85.19)
		(end 136.949 85.19)
		(width 0.16)
		(layer "In5.Cu")
		(net 23)
	)
	(segment
		(start 138.195716 94.084669)
		(end 138.090358 94.190028)
		(width 0.16)
		(layer "In5.Cu")
		(net 23)
	)
	(segment
		(start 137.824 90.613)
		(end 136.925 90.613)
		(width 0.16)
		(layer "In5.Cu")
		(net 23)
	)
	(segment
		(start 129.355 80.175)
		(end 129.355 80.026)
		(width 0.16)
		(layer "In5.Cu")
		(net 23)
	)
	(segment
		(start 136.925 89.565)
		(end 137.824 89.565)
		(width 0.16)
		(layer "In5.Cu")
		(net 23)
	)
	(segment
		(start 134.864544 82.563827)
		(end 134.864544 82.563826)
		(width 0.16)
		(layer "In5.Cu")
		(net 23)
	)
	(segment
		(start 136.949 86.238)
		(end 136.8 86.238)
		(width 0.16)
		(layer "In5.Cu")
		(net 23)
	)
	(segment
		(start 136.699 93.118282)
		(end 137.029696 93.44898)
		(width 0.16)
		(layer "In5.Cu")
		(net 23)
	)
	(segment
		(start 133.062841 80.654642)
		(end 133.062839 80.654641)
		(width 0.16)
		(layer "In5.Cu")
		(net 23)
	)
	(segment
		(start 137.348 85.589)
		(end 137.348 85.839)
		(width 0.16)
		(layer "In5.Cu")
		(net 23)
	)
	(segment
		(start 130.529 80.301)
		(end 130.729 80.301)
		(width 0.16)
		(layer "In5.Cu")
		(net 23)
	)
	(segment
		(start 134.969903 82.350987)
		(end 134.864545 82.456346)
		(width 0.16)
		(layer "In5.Cu")
		(net 23)
	)
	(segment
		(start 135.713071 83.412354)
		(end 136.699 84.398282)
		(width 0.16)
		(layer "In5.Cu")
		(net 23)
	)
	(segment
		(start 133.062839 80.654641)
		(end 133.168198 80.549283)
		(width 0.16)
		(layer "In5.Cu")
		(net 23)
	)
	(segment
		(start 143.068282 94.691)
		(end 143.848282 93.911)
		(width 0.16)
		(layer "In5.Cu")
		(net 23)
	)
	(segment
		(start 143.848282 93.911)
		(end 143.975 93.911)
		(width 0.16)
		(layer "In5.Cu")
		(net 23)
	)
	(segment
		(start 136.699 90.839)
		(end 136.699 91.471)
		(width 0.16)
		(layer "In5.Cu")
		(net 23)
	)
	(segment
		(start 136.949 87.738)
		(end 136.8 87.738)
		(width 0.16)
		(layer "In5.Cu")
		(net 23)
	)
	(segment
		(start 143.975 93.911)
		(end 144.12 93.766)
		(width 0.16)
		(layer "In5.Cu")
		(net 23)
	)
	(segment
		(start 140.499 93.958282)
		(end 140.499 94.448282)
		(width 0.16)
		(layer "In5.Cu")
		(net 23)
	)
	(segment
		(start 126.458 80.8)
		(end 126.458 80.999)
		(width 0.16)
		(layer "In5.Cu")
		(net 23)
	)
	(segment
		(start 124.849 80.301)
		(end 125.959 80.301)
		(width 0.16)
		(layer "In5.Cu")
		(net 23)
	)
	(segment
		(start 138.861 93.998282)
		(end 139.308282 93.551)
		(width 0.16)
		(layer "In5.Cu")
		(net 23)
	)
	(segment
		(start 140.499 94.448282)
		(end 140.741718 94.691)
		(width 0.16)
		(layer "In5.Cu")
		(net 23)
	)
	(segment
		(start 133.909245 81.29033)
		(end 133.909245 81.290329)
		(width 0.16)
		(layer "In5.Cu")
		(net 23)
	)
	(segment
		(start 134.864544 82.563826)
		(end 134.864542 82.563825)
		(width 0.16)
		(layer "In5.Cu")
		(net 23)
	)
	(segment
		(start 130.403 80.026)
		(end 130.403 80.175)
		(width 0.16)
		(layer "In5.Cu")
		(net 23)
	)
	(segment
		(start 120.278282 82.891)
		(end 120.461 82.708282)
		(width 0.16)
		(layer "In5.Cu")
		(net 23)
	)
	(segment
		(start 128.279 79.602)
		(end 128.479 79.602)
		(width 0.16)
		(layer "In5.Cu")
		(net 23)
	)
	(segment
		(start 120.928282 81.841)
		(end 121.298282 81.841)
		(width 0.16)
		(layer "In5.Cu")
		(net 23)
	)
	(segment
		(start 131.279 79.602)
		(end 131.479 79.602)
		(width 0.16)
		(layer "In5.Cu")
		(net 23)
	)
	(segment
		(start 138.090358 94.509641)
		(end 138.271718 94.691)
		(width 0.16)
		(layer "In5.Cu")
		(net 23)
	)
	(segment
		(start 121.298282 81.841)
		(end 122.378282 80.761)
		(width 0.16)
		(layer "In5.Cu")
		(net 23)
	)
	(segment
		(start 139.308282 93.411718)
		(end 139.55 93.17)
		(width 0.16)
		(layer "In5.Cu")
		(net 23)
	)
	(segment
		(start 134.969903 82.350988)
		(end 134.969903 82.350987)
		(width 0.16)
		(layer "In5.Cu")
		(net 23)
	)
	(segment
		(start 141.312 94.44)
		(end 141.312 93.361736)
		(width 0.16)
		(layer "In5.Cu")
		(net 23)
	)
	(segment
		(start 139.55 93.17)
		(end 139.83 93.17)
		(width 0.16)
		(layer "In5.Cu")
		(net 23)
	)
	(segment
		(start 134.757772 81.609941)
		(end 134.969904 81.822073)
		(width 0.16)
		(layer "In5.Cu")
		(net 23)
	)
	(segment
		(start 129.029 80.301)
		(end 129.229 80.301)
		(width 0.16)
		(layer "In5.Cu")
		(net 23)
	)
	(segment
		(start 127.359 80.301)
		(end 127.729 80.301)
		(width 0.16)
		(layer "In5.Cu")
		(net 23)
	)
	(segment
		(start 132.029 80.301)
		(end 132.601718 80.301)
		(width 0.16)
		(layer "In5.Cu")
		(net 23)
	)
	(segment
		(start 133.697114 80.549283)
		(end 133.909246 80.761415)
		(width 0.16)
		(layer "In5.Cu")
		(net 23)
	)
	(segment
		(start 123.65 80.15)
		(end 123.65 80.001)
		(width 0.16)
		(layer "In5.Cu")
		(net 23)
	)
	(segment
		(start 134.972024 82.563826)
		(end 135.077383 82.458468)
		(width 0.16)
		(layer "In5.Cu")
		(net 23)
	)
	(segment
		(start 134.757771 81.609941)
		(end 134.757772 81.609941)
		(width 0.16)
		(layer "In5.Cu")
		(net 23)
	)
	(segment
		(start 119.96 82.746)
		(end 120.105 82.891)
		(width 0.16)
		(layer "In5.Cu")
		(net 23)
	)
	(segment
		(start 128.903 80.026)
		(end 128.903 80.175)
		(width 0.16)
		(layer "In5.Cu")
		(net 23)
	)
	(arc
		(start 129.355 80.026)
		(mid 129.479187 79.726187)
		(end 129.779 79.602)
		(width 0.16)
		(layer "In5.Cu")
		(net 23)
	)
	(arc
		(start 136.699 85.089)
		(mid 136.728582 85.160418)
		(end 136.8 85.19)
		(width 0.16)
		(layer "In5.Cu")
		(net 23)
	)
	(arc
		(start 131.903 80.175)
		(mid 131.939905 80.264095)
		(end 132.029 80.301)
		(width 0.16)
		(layer "In5.Cu")
		(net 23)
	)
	(arc
		(start 130.729 80.301)
		(mid 130.818095 80.264095)
		(end 130.855 80.175)
		(width 0.16)
		(layer "In5.Cu")
		(net 23)
	)
	(arc
		(start 141.861 92.812736)
		(mid 142.249202 92.973534)
		(end 142.41 93.361736)
		(width 0.16)
		(layer "In5.Cu")
		(net 23)
	)
	(arc
		(start 127.729 80.301)
		(mid 127.818095 80.264095)
		(end 127.855 80.175)
		(width 0.16)
		(layer "In5.Cu")
		(net 23)
	)
	(arc
		(start 128.479 79.602)
		(mid 128.778813 79.726187)
		(end 128.903 80.026)
		(width 0.16)
		(layer "In5.Cu")
		(net 23)
	)
	(arc
		(start 141.312 93.361736)
		(mid 141.472798 92.973534)
		(end 141.861 92.812736)
		(width 0.16)
		(layer "In5.Cu")
		(net 23)
	)
	(arc
		(start 123.499 80.301)
		(mid 123.605773 80.256773)
		(end 123.65 80.15)
		(width 0.16)
		(layer "In5.Cu")
		(net 23)
	)
	(arc
		(start 137.029696 93.44898)
		(mid 137.189503 93.515174)
		(end 137.349309 93.448979)
		(width 0.16)
		(layer "In5.Cu")
		(net 23)
	)
	(arc
		(start 133.309619 81.889956)
		(mid 133.25807 82.014407)
		(end 133.309619 82.138858)
		(width 0.16)
		(layer "In5.Cu")
		(net 23)
	)
	(arc
		(start 138.090358 94.190027)
		(mid 138.024164 94.349834)
		(end 138.090358 94.509641)
		(width 0.16)
		(layer "In5.Cu")
		(net 23)
	)
	(arc
		(start 126.86 80.8)
		(mid 127.006154 80.447154)
		(end 127.359 80.301)
		(width 0.16)
		(layer "In5.Cu")
		(net 23)
	)
	(arc
		(start 136.75 92.52)
		(mid 136.713938 92.534938)
		(end 136.699 92.571)
		(width 0.16)
		(layer "In5.Cu")
		(net 23)
	)
	(arc
		(start 134.864542 82.563825)
		(mid 134.918284 82.586086)
		(end 134.972026 82.563827)
		(width 0.16)
		(layer "In5.Cu")
		(net 23)
	)
	(arc
		(start 135.713072 83.304873)
		(mid 135.69081 83.358612)
		(end 135.713071 83.412354)
		(width 0.16)
		(layer "In5.Cu")
		(net 23)
	)
	(arc
		(start 137.348 87.339)
		(mid 137.231136 87.621136)
		(end 136.949 87.738)
		(width 0.16)
		(layer "In5.Cu")
		(net 23)
	)
	(arc
		(start 128.903 80.175)
		(mid 128.939905 80.264095)
		(end 129.029 80.301)
		(width 0.16)
		(layer "In5.Cu")
		(net 23)
	)
	(arc
		(start 136.949 86.69)
		(mid 137.231136 86.806864)
		(end 137.348 87.089)
		(width 0.16)
		(layer "In5.Cu")
		(net 23)
	)
	(arc
		(start 136.8 86.238)
		(mid 136.728582 86.267582)
		(end 136.699 86.339)
		(width 0.16)
		(layer "In5.Cu")
		(net 23)
	)
	(arc
		(start 142.41 94.44)
		(mid 142.483516 94.617484)
		(end 142.661 94.691)
		(width 0.16)
		(layer "In5.Cu")
		(net 23)
	)
	(arc
		(start 124.249 79.552)
		(mid 124.566491 79.683509)
		(end 124.698 80.001)
		(width 0.16)
		(layer "In5.Cu")
		(net 23)
	)
	(arc
		(start 124.698 80.15)
		(mid 124.742227 80.256773)
		(end 124.849 80.301)
		(width 0.16)
		(layer "In5.Cu")
		(net 23)
	)
	(arc
		(start 141.061 94.691)
		(mid 141.238484 94.617484)
		(end 141.312 94.44)
		(width 0.16)
		(layer "In5.Cu")
		(net 23)
	)
	(arc
		(start 129.229 80.301)
		(mid 129.318095 80.264095)
		(end 129.355 80.175)
		(width 0.16)
		(layer "In5.Cu")
		(net 23)
	)
	(arc
		(start 136.699 89.339)
		(mid 136.765194 89.498806)
		(end 136.925 89.565)
		(width 0.16)
		(layer "In5.Cu")
		(net 23)
	)
	(arc
		(start 133.380329 82.209568)
		(mid 133.50478 82.261117)
		(end 133.629231 82.209568)
		(width 0.16)
		(layer "In5.Cu")
		(net 23)
	)
	(arc
		(start 134.969904 81.822073)
		(mid 135.079444 82.08653)
		(end 134.969903 82.350988)
		(width 0.16)
		(layer "In5.Cu")
		(net 23)
	)
	(arc
		(start 134.228856 81.60994)
		(mid 134.493313 81.500398)
		(end 134.757771 81.609941)
		(width 0.16)
		(layer "In5.Cu")
		(net 23)
	)
	(arc
		(start 133.909246 80.761415)
		(mid 134.018786 81.025872)
		(end 133.909245 81.29033)
		(width 0.16)
		(layer "In5.Cu")
		(net 23)
	)
	(arc
		(start 136.949 85.19)
		(mid 137.231136 85.306864)
		(end 137.348 85.589)
		(width 0.16)
		(layer "In5.Cu")
		(net 23)
	)
	(arc
		(start 131.479 79.602)
		(mid 131.778813 79.726187)
		(end 131.903 80.026)
		(width 0.16)
		(layer "In5.Cu")
		(net 23)
	)
	(arc
		(start 126.659 81.2)
		(mid 126.801128 81.141128)
		(end 126.86 80.999)
		(width 0.16)
		(layer "In5.Cu")
		(net 23)
	)
	(arc
		(start 137.454669 93.34362)
		(mid 137.825193 93.190145)
		(end 138.195716 93.343621)
		(width 0.16)
		(layer "In5.Cu")
		(net 23)
	)
	(arc
		(start 132.955357 80.65464)
		(mid 133.009099 80.676901)
		(end 133.062841 80.654642)
		(width 0.16)
		(layer "In5.Cu")
		(net 23)
	)
	(arc
		(start 137.248 92.171)
		(mid 137.14578 92.41778)
		(end 136.899 92.52)
		(width 0.16)
		(layer "In5.Cu")
		(net 23)
	)
	(arc
		(start 137.824 89.565)
		(mid 138.194524 89.718476)
		(end 138.348 90.089)
		(width 0.16)
		(layer "In5.Cu")
		(net 23)
	)
	(arc
		(start 138.348 90.089)
		(mid 138.194524 90.459524)
		(end 137.824 90.613)
		(width 0.16)
		(layer "In5.Cu")
		(net 23)
	)
	(arc
		(start 123.65 80.001)
		(mid 123.781509 79.683509)
		(end 124.099 79.552)
		(width 0.16)
		(layer "In5.Cu")
		(net 23)
	)
	(arc
		(start 136.699 86.589)
		(mid 136.728582 86.660418)
		(end 136.8 86.69)
		(width 0.16)
		(layer "In5.Cu")
		(net 23)
	)
	(arc
		(start 129.979 79.602)
		(mid 130.278813 79.726187)
		(end 130.403 80.026)
		(width 0.16)
		(layer "In5.Cu")
		(net 23)
	)
	(arc
		(start 133.168198 80.549283)
		(mid 133.432656 80.439741)
		(end 133.697114 80.549283)
		(width 0.16)
		(layer "In5.Cu")
		(net 23)
	)
	(arc
		(start 138.195716 93.343621)
		(mid 138.349192 93.714145)
		(end 138.195716 94.084669)
		(width 0.16)
		(layer "In5.Cu")
		(net 23)
	)
	(arc
		(start 135.818431 82.6706)
		(mid 135.927971 82.935057)
		(end 135.81843 83.199515)
		(width 0.16)
		(layer "In5.Cu")
		(net 23)
	)
	(arc
		(start 137.348 85.839)
		(mid 137.231136 86.121136)
		(end 136.949 86.238)
		(width 0.16)
		(layer "In5.Cu")
		(net 23)
	)
	(arc
		(start 134.864545 82.456346)
		(mid 134.842283 82.510085)
		(end 134.864544 82.563827)
		(width 0.16)
		(layer "In5.Cu")
		(net 23)
	)
	(arc
		(start 136.925 90.613)
		(mid 136.765194 90.679194)
		(end 136.699 90.839)
		(width 0.16)
		(layer "In5.Cu")
		(net 23)
	)
	(arc
		(start 130.855 80.026)
		(mid 130.979187 79.726187)
		(end 131.279 79.602)
		(width 0.16)
		(layer "In5.Cu")
		(net 23)
	)
	(arc
		(start 127.855 80.026)
		(mid 127.979187 79.726187)
		(end 128.279 79.602)
		(width 0.16)
		(layer "In5.Cu")
		(net 23)
	)
	(arc
		(start 126.458 80.999)
		(mid 126.516872 81.141128)
		(end 126.659 81.2)
		(width 0.16)
		(layer "In5.Cu")
		(net 23)
	)
	(arc
		(start 136.699 91.471)
		(mid 136.713938 91.507062)
		(end 136.75 91.522)
		(width 0.16)
		(layer "In5.Cu")
		(net 23)
	)
	(arc
		(start 136.8 87.738)
		(mid 136.728582 87.767582)
		(end 136.699 87.839)
		(width 0.16)
		(layer "In5.Cu")
		(net 23)
	)
	(arc
		(start 135.077383 82.458468)
		(mid 135.341841 82.348926)
		(end 135.606299 82.458468)
		(width 0.16)
		(layer "In5.Cu")
		(net 23)
	)
	(arc
		(start 125.959 80.301)
		(mid 126.311846 80.447154)
		(end 126.458 80.8)
		(width 0.16)
		(layer "In5.Cu")
		(net 23)
	)
	(arc
		(start 130.403 80.175)
		(mid 130.439905 80.264095)
		(end 130.529 80.301)
		(width 0.16)
		(layer "In5.Cu")
		(net 23)
	)
	(arc
		(start 136.899 91.522)
		(mid 137.14578 91.62422)
		(end 137.248 91.871)
		(width 0.16)
		(layer "In5.Cu")
		(net 23)
	)
	(segment
		(start 143.15 93.5)
		(end 143.854 93.5)
		(width 0.155)
		(layer "B.Cu")
		(net 23)
	)
	(segment
		(start 143.854 93.5)
		(end 144.12 93.766)
		(width 0.155)
		(layer "B.Cu")
		(net 23)
	)
	(segment
		(start 115.0005 75.638074)
		(end 115.0005 74.798074)
		(width 0.155)
		(layer "F.Cu")
		(net 24)
	)
	(segment
		(start 115.566187 74.232389)
		(end 115.566188 74.232389)
		(width 0.155)
		(layer "F.Cu")
		(net 24)
	)
	(segment
		(start 117.697823 73.080751)
		(end 117.697823 72.830636)
		(width 0.155)
		(layer "F.Cu")
		(net 24)
	)
	(segment
		(start 111.113 74.013)
		(end 111.834426 74.013)
		(width 0.155)
		(layer "F.Cu")
		(net 24)
	)
	(segment
		(start 114.268074 76.3705)
		(end 115.0005 75.638074)
		(width 0.155)
		(layer "F.Cu")
		(net 24)
	)
	(segment
		(start 115.269653 74.218699)
		(end 115.283344 74.23239)
		(width 0.155)
		(layer "F.Cu")
		(net 24)
	)
	(segment
		(start 110.975 73.875)
		(end 111.113 74.013)
		(width 0.155)
		(layer "F.Cu")
		(net 24)
	)
	(segment
		(start 117.428074 73.3505)
		(end 117.697823 73.080751)
		(width 0.155)
		(layer "F.Cu")
		(net 24)
	)
	(segment
		(start 115.269655 74.218698)
		(end 115.269653 74.218699)
		(width 0.155)
		(layer "F.Cu")
		(net 24)
	)
	(segment
		(start 117.697823 72.830636)
		(end 117.597323 72.730136)
		(width 0.155)
		(layer "F.Cu")
		(net 24)
	)
	(segment
		(start 115.0005 74.515232)
		(end 114.98681 74.501542)
		(width 0.155)
		(layer "F.Cu")
		(net 24)
	)
	(segment
		(start 112.5595 75.688074)
		(end 113.241926 76.3705)
		(width 0.155)
		(layer "F.Cu")
		(net 24)
	)
	(segment
		(start 116.448074 73.3505)
		(end 117.428074 73.3505)
		(width 0.155)
		(layer "F.Cu")
		(net 24)
	)
	(segment
		(start 112.5595 74.738074)
		(end 112.5595 75.688074)
		(width 0.155)
		(layer "F.Cu")
		(net 24)
	)
	(segment
		(start 111.834426 74.013)
		(end 112.5595 74.738074)
		(width 0.155)
		(layer "F.Cu")
		(net 24)
	)
	(segment
		(start 114.986811 74.218699)
		(end 114.986811 74.218698)
		(width 0.155)
		(layer "F.Cu")
		(net 24)
	)
	(segment
		(start 113.241926 76.3705)
		(end 114.268074 76.3705)
		(width 0.155)
		(layer "F.Cu")
		(net 24)
	)
	(segment
		(start 115.566188 74.232389)
		(end 116.448074 73.3505)
		(width 0.155)
		(layer "F.Cu")
		(net 24)
	)
	(via
		(at 110.975 73.875)
		(size 0.45)
		(drill 0.1)
		(layers "F.Cu" "B.Cu")
		(net 24)
	)
	(arc
		(start 115.0005 74.798074)
		(mid 115.059079 74.656652)
		(end 115.0005 74.515232)
		(width 0.155)
		(layer "F.Cu")
		(net 24)
	)
	(arc
		(start 115.283344 74.23239)
		(mid 115.424766 74.290968)
		(end 115.566187 74.232389)
		(width 0.155)
		(layer "F.Cu")
		(net 24)
	)
	(arc
		(start 114.986811 74.218698)
		(mid 115.128232 74.16012)
		(end 115.269655 74.218698)
		(width 0.155)
		(layer "F.Cu")
		(net 24)
	)
	(arc
		(start 114.98681 74.501542)
		(mid 114.928232 74.36012)
		(end 114.986811 74.218699)
		(width 0.155)
		(layer "F.Cu")
		(net 24)
	)
	(segment
		(start 111.92 74.03)
		(end 111.592 74.03)
		(width 0.155)
		(layer "B.Cu")
		(net 24)
	)
	(segment
		(start 110.8059 74.0441)
		(end 109.862551 74.0441)
		(width 0.155)
		(layer "B.Cu")
		(net 24)
	)
	(segment
		(start 109.856251 74.0504)
		(end 109.4007 74.0504)
		(width 0.155)
		(layer "B.Cu")
		(net 24)
	)
	(segment
		(start 110.975 73.875)
		(end 110.8059 74.0441)
		(width 0.155)
		(layer "B.Cu")
		(net 24)
	)
	(segment
		(start 111.113 74.013)
		(end 111.575 74.013)
		(width 0.155)
		(layer "B.Cu")
		(net 24)
	)
	(segment
		(start 109.862551 74.0441)
		(end 109.856251 74.0504)
		(width 0.155)
		(layer "B.Cu")
		(net 24)
	)
	(segment
		(start 111.592 74.03)
		(end 111.575 74.013)
		(width 0.155)
		(layer "B.Cu")
		(net 24)
	)
	(segment
		(start 110.975 73.875)
		(end 111.113 74.013)
		(width 0.155)
		(layer "B.Cu")
		(net 24)
	)
	(segment
		(start 117.683624 81.905049)
		(end 117.683626 81.90505)
		(width 0.155)
		(layer "F.Cu")
		(net 25)
	)
	(segment
		(start 117.401136 83.248199)
		(end 117.401137 83.248201)
		(width 0.155)
		(layer "F.Cu")
		(net 25)
	)
	(segment
		(start 118.42538 82.965711)
		(end 118.425382 82.965712)
		(width 0.155)
		(layer "F.Cu")
		(net 25)
	)
	(segment
		(start 119.946 83.32)
		(end 119.098574 83.32)
		(width 0.155)
		(layer "F.Cu")
		(net 25)
	)
	(segment
		(start 119.96 83.334)
		(end 119.946 83.32)
		(width 0.155)
		(layer "F.Cu")
		(net 25)
	)
	(segment
		(start 117.683626 81.90505)
		(end 117.447823 81.669249)
		(width 0.155)
		(layer "F.Cu")
		(net 25)
	)
	(segment
		(start 117.347323 80.930136)
		(end 117.347323 80.205136)
		(width 0.155)
		(layer "F.Cu")
		(net 25)
	)
	(segment
		(start 117.447823 81.030636)
		(end 117.347323 80.930136)
		(width 0.155)
		(layer "F.Cu")
		(net 25)
	)
	(segment
		(start 118.425382 82.965712)
		(end 118.142891 83.2482)
		(width 0.155)
		(layer "F.Cu")
		(net 25)
	)
	(segment
		(start 117.401137 82.506445)
		(end 117.683625 82.223954)
		(width 0.155)
		(layer "F.Cu")
		(net 25)
	)
	(segment
		(start 117.401136 82.506446)
		(end 117.401137 82.506445)
		(width 0.155)
		(layer "F.Cu")
		(net 25)
	)
	(segment
		(start 117.447823 81.669249)
		(end 117.447823 81.030636)
		(width 0.155)
		(layer "F.Cu")
		(net 25)
	)
	(segment
		(start 119.098574 83.32)
		(end 118.744286 82.965711)
		(width 0.155)
		(layer "F.Cu")
		(net 25)
	)
	(via
		(at 119.96 83.334)
		(size 0.45)
		(drill 0.1)
		(layers "F.Cu" "B.Cu")
		(net 25)
	)
	(via
		(at 144.12 94.354)
		(size 0.45)
		(drill 0.1)
		(layers "F.Cu" "B.Cu")
		(net 25)
	)
	(arc
		(start 117.401137 83.248201)
		(mid 117.247514 82.877324)
		(end 117.401136 82.506446)
		(width 0.155)
		(layer "F.Cu")
		(net 25)
	)
	(arc
		(start 117.683625 82.223954)
		(mid 117.749672 82.064501)
		(end 117.683624 81.905049)
		(width 0.155)
		(layer "F.Cu")
		(net 25)
	)
	(arc
		(start 118.142891 83.2482)
		(mid 117.772013 83.401822)
		(end 117.401136 83.248199)
		(width 0.155)
		(layer "F.Cu")
		(net 25)
	)
	(arc
		(start 118.744286 82.965711)
		(mid 118.584834 82.899664)
		(end 118.42538 82.965711)
		(width 0.155)
		(layer "F.Cu")
		(net 25)
	)
	(segment
		(start 127.359 80.599)
		(end 127.729 80.599)
		(width 0.16)
		(layer "In5.Cu")
		(net 25)
	)
	(segment
		(start 137.879641 94.720358)
		(end 138.148282 94.989)
		(width 0.16)
		(layer "In5.Cu")
		(net 25)
	)
	(segment
		(start 136.949 85.94)
		(end 136.8 85.94)
		(width 0.16)
		(layer "In5.Cu")
		(net 25)
	)
	(segment
		(start 133.098901 82.349576)
		(end 133.098901 82.349575)
		(width 0.16)
		(layer "In5.Cu")
		(net 25)
	)
	(segment
		(start 133.839948 82.420286)
		(end 134.175115 82.085115)
		(width 0.16)
		(layer "In5.Cu")
		(net 25)
	)
	(segment
		(start 136.8 85.488)
		(end 136.949 85.488)
		(width 0.16)
		(layer "In5.Cu")
		(net 25)
	)
	(segment
		(start 136.401 92.571)
		(end 136.401 93.241718)
		(width 0.16)
		(layer "In5.Cu")
		(net 25)
	)
	(segment
		(start 139.959282 93.84)
		(end 140.201 94.081718)
		(width 0.16)
		(layer "In5.Cu")
		(net 25)
	)
	(segment
		(start 135.395581 82.669184)
		(end 135.39558 82.669184)
		(width 0.16)
		(layer "In5.Cu")
		(net 25)
	)
	(segment
		(start 131.153 80.175)
		(end 131.153 80.026)
		(width 0.16)
		(layer "In5.Cu")
		(net 25)
	)
	(segment
		(start 135.607711 82.988797)
		(end 135.502354 83.094155)
		(width 0.16)
		(layer "In5.Cu")
		(net 25)
	)
	(segment
		(start 130.105 80.026)
		(end 130.105 80.175)
		(width 0.16)
		(layer "In5.Cu")
		(net 25)
	)
	(segment
		(start 137.665386 93.554339)
		(end 137.665386 93.554338)
		(width 0.16)
		(layer "In5.Cu")
		(net 25)
	)
	(segment
		(start 134.547055 81.820658)
		(end 134.759187 82.03279)
		(width 0.16)
		(layer "In5.Cu")
		(net 25)
	)
	(segment
		(start 134.228857 82.031376)
		(end 134.439573 81.820657)
		(width 0.16)
		(layer "In5.Cu")
		(net 25)
	)
	(segment
		(start 135.182741 82.774543)
		(end 135.2881 82.669185)
		(width 0.16)
		(layer "In5.Cu")
		(net 25)
	)
	(segment
		(start 136.75 91.82)
		(end 136.899 91.82)
		(width 0.16)
		(layer "In5.Cu")
		(net 25)
	)
	(segment
		(start 140.201 94.571718)
		(end 140.618282 94.989)
		(width 0.16)
		(layer "In5.Cu")
		(net 25)
	)
	(segment
		(start 133.273556 80.865358)
		(end 133.378915 80.76)
		(width 0.16)
		(layer "In5.Cu")
		(net 25)
	)
	(segment
		(start 119.96 83.334)
		(end 120.105 83.189)
		(width 0.16)
		(layer "In5.Cu")
		(net 25)
	)
	(segment
		(start 136.8 86.988)
		(end 136.949 86.988)
		(width 0.16)
		(layer "In5.Cu")
		(net 25)
	)
	(segment
		(start 122.501718 81.059)
		(end 122.881718 81.059)
		(width 0.16)
		(layer "In5.Cu")
		(net 25)
	)
	(segment
		(start 137.824 90.315)
		(end 136.925 90.315)
		(width 0.16)
		(layer "In5.Cu")
		(net 25)
	)
	(segment
		(start 137.984999 93.873952)
		(end 137.879641 93.979311)
		(width 0.16)
		(layer "In5.Cu")
		(net 25)
	)
	(segment
		(start 139.159 94.421718)
		(end 139.159 94.141944)
		(width 0.16)
		(layer "In5.Cu")
		(net 25)
	)
	(segment
		(start 136.401 87.839)
		(end 136.401 89.339)
		(width 0.16)
		(layer "In5.Cu")
		(net 25)
	)
	(segment
		(start 128.605 80.026)
		(end 128.605 80.175)
		(width 0.16)
		(layer "In5.Cu")
		(net 25)
	)
	(segment
		(start 140.618282 94.989)
		(end 141.061 94.989)
		(width 0.16)
		(layer "In5.Cu")
		(net 25)
	)
	(segment
		(start 137.560027 93.659697)
		(end 137.665386 93.554339)
		(width 0.16)
		(layer "In5.Cu")
		(net 25)
	)
	(segment
		(start 136.95 91.871)
		(end 136.95 92.171)
		(width 0.16)
		(layer "In5.Cu")
		(net 25)
	)
	(segment
		(start 134.759187 82.14027)
		(end 134.653827 82.245627)
		(width 0.16)
		(layer "In5.Cu")
		(net 25)
	)
	(segment
		(start 136.401 84.521718)
		(end 136.401 85.089)
		(width 0.16)
		(layer "In5.Cu")
		(net 25)
	)
	(segment
		(start 141.61 94.44)
		(end 141.61 93.361736)
		(width 0.16)
		(layer "In5.Cu")
		(net 25)
	)
	(segment
		(start 124.849 80.599)
		(end 125.959 80.599)
		(width 0.16)
		(layer "In5.Cu")
		(net 25)
	)
	(segment
		(start 122.881718 81.059)
		(end 123.341718 80.599)
		(width 0.16)
		(layer "In5.Cu")
		(net 25)
	)
	(segment
		(start 140.201 94.081718)
		(end 140.201 94.571718)
		(width 0.16)
		(layer "In5.Cu")
		(net 25)
	)
	(segment
		(start 120.759 82.831718)
		(end 120.759 82.431718)
		(width 0.16)
		(layer "In5.Cu")
		(net 25)
	)
	(segment
		(start 123.948 80.15)
		(end 123.948 80.001)
		(width 0.16)
		(layer "In5.Cu")
		(net 25)
	)
	(segment
		(start 142.661 94.989)
		(end 143.191718 94.989)
		(width 0.16)
		(layer "In5.Cu")
		(net 25)
	)
	(segment
		(start 120.759 82.431718)
		(end 121.051718 82.139)
		(width 0.16)
		(layer "In5.Cu")
		(net 25)
	)
	(segment
		(start 121.051718 82.139)
		(end 121.421718 82.139)
		(width 0.16)
		(layer "In5.Cu")
		(net 25)
	)
	(segment
		(start 136.401 90.839)
		(end 136.401 91.471)
		(width 0.16)
		(layer "In5.Cu")
		(net 25)
	)
	(segment
		(start 134.175115 82.085115)
		(end 134.228857 82.031376)
		(width 0.16)
		(layer "In5.Cu")
		(net 25)
	)
	(segment
		(start 136.899 92.222)
		(end 136.75 92.222)
		(width 0.16)
		(layer "In5.Cu")
		(net 25)
	)
	(segment
		(start 135.39558 82.669184)
		(end 135.607712 82.881316)
		(width 0.16)
		(layer "In5.Cu")
		(net 25)
	)
	(segment
		(start 138.148282 94.989)
		(end 138.591718 94.989)
		(width 0.16)
		(layer "In5.Cu")
		(net 25)
	)
	(segment
		(start 120.105 83.189)
		(end 120.401718 83.189)
		(width 0.16)
		(layer "In5.Cu")
		(net 25)
	)
	(segment
		(start 132.478282 80.599)
		(end 132.74464 80.865357)
		(width 0.16)
		(layer "In5.Cu")
		(net 25)
	)
	(segment
		(start 131.279 79.9)
		(end 131.479 79.9)
		(width 0.16)
		(layer "In5.Cu")
		(net 25)
	)
	(segment
		(start 129.779 79.9)
		(end 129.979 79.9)
		(width 0.16)
		(layer "In5.Cu")
		(net 25)
	)
	(segment
		(start 143.971718 94.209)
		(end 143.975 94.209)
		(width 0.16)
		(layer "In5.Cu")
		(net 25)
	)
	(segment
		(start 134.547054 81.820658)
		(end 134.547055 81.820658)
		(width 0.16)
		(layer "In5.Cu")
		(net 25)
	)
	(segment
		(start 137.05 85.589)
		(end 137.05 85.839)
		(width 0.16)
		(layer "In5.Cu")
		(net 25)
	)
	(segment
		(start 134.653827 82.774543)
		(end 134.653825 82.774542)
		(width 0.16)
		(layer "In5.Cu")
		(net 25)
	)
	(segment
		(start 136.401 93.241718)
		(end 136.818979 93.659697)
		(width 0.16)
		(layer "In5.Cu")
		(net 25)
	)
	(segment
		(start 136.925 89.863)
		(end 137.824 89.863)
		(width 0.16)
		(layer "In5.Cu")
		(net 25)
	)
	(segment
		(start 128.153 80.175)
		(end 128.153 80.026)
		(width 0.16)
		(layer "In5.Cu")
		(net 25)
	)
	(segment
		(start 143.975 94.209)
		(end 144.12 94.354)
		(width 0.16)
		(layer "In5.Cu")
		(net 25)
	)
	(segment
		(start 133.486395 80.759999)
		(end 133.698527 80.972131)
		(width 0.16)
		(layer "In5.Cu")
		(net 25)
	)
	(segment
		(start 136.949 87.44)
		(end 136.8 87.44)
		(width 0.16)
		(layer "In5.Cu")
		(net 25)
	)
	(segment
		(start 133.486396 80.759999)
		(end 133.486395 80.759999)
		(width 0.16)
		(layer "In5.Cu")
		(net 25)
	)
	(segment
		(start 138.591718 94.989)
		(end 139.159 94.421718)
		(width 0.16)
		(layer "In5.Cu")
		(net 25)
	)
	(segment
		(start 124.099 79.85)
		(end 124.249 79.85)
		(width 0.16)
		(layer "In5.Cu")
		(net 25)
	)
	(segment
		(start 124.4 80.001)
		(end 124.4 80.15)
		(width 0.16)
		(layer "In5.Cu")
		(net 25)
	)
	(segment
		(start 133.098901 82.349575)
		(end 133.169611 82.420285)
		(width 0.16)
		(layer "In5.Cu")
		(net 25)
	)
	(segment
		(start 135.182743 82.774544)
		(end 135.182741 82.774543)
		(width 0.16)
		(layer "In5.Cu")
		(net 25)
	)
	(segment
		(start 121.421718 82.139)
		(end 122.501718 81.059)
		(width 0.16)
		(layer "In5.Cu")
		(net 25)
	)
	(segment
		(start 120.401718 83.189)
		(end 120.759 82.831718)
		(width 0.16)
		(layer "In5.Cu")
		(net 25)
	)
	(segment
		(start 133.273558 80.865359)
		(end 133.273556 80.865358)
		(width 0.16)
		(layer "In5.Cu")
		(net 25)
	)
	(segment
		(start 130.529 80.599)
		(end 130.729 80.599)
		(width 0.16)
		(layer "In5.Cu")
		(net 25)
	)
	(segment
		(start 123.341718 80.599)
		(end 123.499 80.599)
		(width 0.16)
		(layer "In5.Cu")
		(net 25)
	)
	(segment
		(start 126.16 80.8)
		(end 126.16 80.999)
		(width 0.16)
		(layer "In5.Cu")
		(net 25)
	)
	(segment
		(start 142.112 93.361736)
		(end 142.112 94.44)
		(width 0.16)
		(layer "In5.Cu")
		(net 25)
	)
	(segment
		(start 129.029 80.599)
		(end 129.229 80.599)
		(width 0.16)
		(layer "In5.Cu")
		(net 25)
	)
	(segment
		(start 127.158 80.999)
		(end 127.158 80.8)
		(width 0.16)
		(layer "In5.Cu")
		(net 25)
	)
	(segment
		(start 133.698526 81.079612)
		(end 133.098901 81.679238)
		(width 0.16)
		(layer "In5.Cu")
		(net 25)
	)
	(segment
		(start 131.605 80.026)
		(end 131.605 80.175)
		(width 0.16)
		(layer "In5.Cu")
		(net 25)
	)
	(segment
		(start 132.029 80.599)
		(end 132.478282 80.599)
		(width 0.16)
		(layer "In5.Cu")
		(net 25)
	)
	(segment
		(start 134.759186 82.140271)
		(end 134.759187 82.14027)
		(width 0.16)
		(layer "In5.Cu")
		(net 25)
	)
	(segment
		(start 137.879641 93.979311)
		(end 137.879641 93.97931)
		(width 0.16)
		(layer "In5.Cu")
		(net 25)
	)
	(segment
		(start 135.502354 83.623071)
		(end 136.401 84.521718)
		(width 0.16)
		(layer "In5.Cu")
		(net 25)
	)
	(segment
		(start 139.460944 93.84)
		(end 139.959282 93.84)
		(width 0.16)
		(layer "In5.Cu")
		(net 25)
	)
	(segment
		(start 139.159 94.141944)
		(end 139.460944 93.84)
		(width 0.16)
		(layer "In5.Cu")
		(net 25)
	)
	(segment
		(start 128.279 79.9)
		(end 128.479 79.9)
		(width 0.16)
		(layer "In5.Cu")
		(net 25)
	)
	(segment
		(start 137.984999 93.554339)
		(end 137.985 93.554339)
		(width 0.16)
		(layer "In5.Cu")
		(net 25)
	)
	(segment
		(start 129.653 80.175)
		(end 129.653 80.026)
		(width 0.16)
		(layer "In5.Cu")
		(net 25)
	)
	(segment
		(start 143.191718 94.989)
		(end 143.971718 94.209)
		(width 0.16)
		(layer "In5.Cu")
		(net 25)
	)
	(segment
		(start 137.05 87.089)
		(end 137.05 87.339)
		(width 0.16)
		(layer "In5.Cu")
		(net 25)
	)
	(segment
		(start 136.401 86.339)
		(end 136.401 86.589)
		(width 0.16)
		(layer "In5.Cu")
		(net 25)
	)
	(arc
		(start 137.879641 93.97931)
		(mid 137.726165 94.349834)
		(end 137.879641 94.720358)
		(width 0.16)
		(layer "In5.Cu")
		(net 25)
	)
	(arc
		(start 134.653825 82.774542)
		(mid 134.918285 82.884086)
		(end 135.182743 82.774544)
		(width 0.16)
		(layer "In5.Cu")
		(net 25)
	)
	(arc
		(start 136.401 91.471)
		(mid 136.50322 91.71778)
		(end 136.75 91.82)
		(width 0.16)
		(layer "In5.Cu")
		(net 25)
	)
	(arc
		(start 133.098901 81.679238)
		(mid 132.960069 82.014407)
		(end 133.098901 82.349576)
		(width 0.16)
		(layer "In5.Cu")
		(net 25)
	)
	(arc
		(start 136.8 87.44)
		(mid 136.517864 87.556864)
		(end 136.401 87.839)
		(width 0.16)
		(layer "In5.Cu")
		(net 25)
	)
	(arc
		(start 130.729 80.599)
		(mid 131.028813 80.474813)
		(end 131.153 80.175)
		(width 0.16)
		(layer "In5.Cu")
		(net 25)
	)
	(arc
		(start 126.659 81.498)
		(mid 127.011846 81.351846)
		(end 127.158 80.999)
		(width 0.16)
		(layer "In5.Cu")
		(net 25)
	)
	(arc
		(start 128.605 80.175)
		(mid 128.729187 80.474813)
		(end 129.029 80.599)
		(width 0.16)
		(layer "In5.Cu")
		(net 25)
	)
	(arc
		(start 124.249 79.85)
		(mid 124.355773 79.894227)
		(end 124.4 80.001)
		(width 0.16)
		(layer "In5.Cu")
		(net 25)
	)
	(arc
		(start 141.861 93.110736)
		(mid 142.038484 93.184252)
		(end 142.112 93.361736)
		(width 0.16)
		(layer "In5.Cu")
		(net 25)
	)
	(arc
		(start 136.75 92.222)
		(mid 136.50322 92.32422)
		(end 136.401 92.571)
		(width 0.16)
		(layer "In5.Cu")
		(net 25)
	)
	(arc
		(start 124.4 80.15)
		(mid 124.531509 80.467491)
		(end 124.849 80.599)
		(width 0.16)
		(layer "In5.Cu")
		(net 25)
	)
	(arc
		(start 136.95 92.171)
		(mid 136.935062 92.207062)
		(end 136.899 92.222)
		(width 0.16)
		(layer "In5.Cu")
		(net 25)
	)
	(arc
		(start 134.439573 81.820657)
		(mid 134.493315 81.798398)
		(end 134.547054 81.820658)
		(width 0.16)
		(layer "In5.Cu")
		(net 25)
	)
	(arc
		(start 135.607712 82.881316)
		(mid 135.629973 82.935058)
		(end 135.607711 82.988797)
		(width 0.16)
		(layer "In5.Cu")
		(net 25)
	)
	(arc
		(start 137.824 89.863)
		(mid 137.983806 89.929194)
		(end 138.05 90.089)
		(width 0.16)
		(layer "In5.Cu")
		(net 25)
	)
	(arc
		(start 138.05 90.089)
		(mid 137.983806 90.248806)
		(end 137.824 90.315)
		(width 0.16)
		(layer "In5.Cu")
		(net 25)
	)
	(arc
		(start 133.698527 80.972131)
		(mid 133.720788 81.025873)
		(end 133.698526 81.079612)
		(width 0.16)
		(layer "In5.Cu")
		(net 25)
	)
	(arc
		(start 136.401 89.339)
		(mid 136.554476 89.709524)
		(end 136.925 89.863)
		(width 0.16)
		(layer "In5.Cu")
		(net 25)
	)
	(arc
		(start 137.05 85.839)
		(mid 137.020418 85.910418)
		(end 136.949 85.94)
		(width 0.16)
		(layer "In5.Cu")
		(net 25)
	)
	(arc
		(start 125.959 80.599)
		(mid 126.101128 80.657872)
		(end 126.16 80.8)
		(width 0.16)
		(layer "In5.Cu")
		(net 25)
	)
	(arc
		(start 135.502354 83.094155)
		(mid 135.392812 83.358613)
		(end 135.502354 83.623071)
		(width 0.16)
		(layer "In5.Cu")
		(net 25)
	)
	(arc
		(start 142.112 94.44)
		(mid 142.272798 94.828202)
		(end 142.661 94.989)
		(width 0.16)
		(layer "In5.Cu")
		(net 25)
	)
	(arc
		(start 127.729 80.599)
		(mid 128.028813 80.474813)
		(end 128.153 80.175)
		(width 0.16)
		(layer "In5.Cu")
		(net 25)
	)
	(arc
		(start 123.499 80.599)
		(mid 123.816491 80.467491)
		(end 123.948 80.15)
		(width 0.16)
		(layer "In5.Cu")
		(net 25)
	)
	(arc
		(start 129.979 79.9)
		(mid 130.068095 79.936905)
		(end 130.105 80.026)
		(width 0.16)
		(layer "In5.Cu")
		(net 25)
	)
	(arc
		(start 130.105 80.175)
		(mid 130.229187 80.474813)
		(end 130.529 80.599)
		(width 0.16)
		(layer "In5.Cu")
		(net 25)
	)
	(arc
		(start 126.16 80.999)
		(mid 126.306154 81.351846)
		(end 126.659 81.498)
		(width 0.16)
		(layer "In5.Cu")
		(net 25)
	)
	(arc
		(start 137.985 93.554339)
		(mid 138.051194 93.714146)
		(end 137.984999 93.873952)
		(width 0.16)
		(layer "In5.Cu")
		(net 25)
	)
	(arc
		(start 128.153 80.026)
		(mid 128.189905 79.936905)
		(end 128.279 79.9)
		(width 0.16)
		(layer "In5.Cu")
		(net 25)
	)
	(arc
		(start 134.759187 82.03279)
		(mid 134.781446 82.08653)
		(end 134.759186 82.140271)
		(width 0.16)
		(layer "In5.Cu")
		(net 25)
	)
	(arc
		(start 129.229 80.599)
		(mid 129.528813 80.474813)
		(end 129.653 80.175)
		(width 0.16)
		(layer "In5.Cu")
		(net 25)
	)
	(arc
		(start 136.401 86.589)
		(mid 136.517864 86.871136)
		(end 136.8 86.988)
		(width 0.16)
		(layer "In5.Cu")
		(net 25)
	)
	(arc
		(start 123.948 80.001)
		(mid 123.992227 79.894227)
		(end 124.099 79.85)
		(width 0.16)
		(layer "In5.Cu")
		(net 25)
	)
	(arc
		(start 136.8 85.94)
		(mid 136.517864 86.056864)
		(end 136.401 86.339)
		(width 0.16)
		(layer "In5.Cu")
		(net 25)
	)
	(arc
		(start 133.169611 82.420285)
		(mid 133.504779 82.559117)
		(end 133.839948 82.420286)
		(width 0.16)
		(layer "In5.Cu")
		(net 25)
	)
	(arc
		(start 134.653827 82.245627)
		(mid 134.544285 82.510085)
		(end 134.653827 82.774543)
		(width 0.16)
		(layer "In5.Cu")
		(net 25)
	)
	(arc
		(start 136.899 91.82)
		(mid 136.935062 91.834938)
		(end 136.95 91.871)
		(width 0.16)
		(layer "In5.Cu")
		(net 25)
	)
	(arc
		(start 136.949 86.988)
		(mid 137.020418 87.017582)
		(end 137.05 87.089)
		(width 0.16)
		(layer "In5.Cu")
		(net 25)
	)
	(arc
		(start 137.665386 93.554338)
		(mid 137.825193 93.488144)
		(end 137.984999 93.554339)
		(width 0.16)
		(layer "In5.Cu")
		(net 25)
	)
	(arc
		(start 128.479 79.9)
		(mid 128.568095 79.936905)
		(end 128.605 80.026)
		(width 0.16)
		(layer "In5.Cu")
		(net 25)
	)
	(arc
		(start 135.2881 82.669185)
		(mid 135.341839 82.646923)
		(end 135.395581 82.669184)
		(width 0.16)
		(layer "In5.Cu")
		(net 25)
	)
	(arc
		(start 136.401 85.089)
		(mid 136.517864 85.371136)
		(end 136.8 85.488)
		(width 0.16)
		(layer "In5.Cu")
		(net 25)
	)
	(arc
		(start 131.479 79.9)
		(mid 131.568095 79.936905)
		(end 131.605 80.026)
		(width 0.16)
		(layer "In5.Cu")
		(net 25)
	)
	(arc
		(start 136.925 90.315)
		(mid 136.554476 90.468476)
		(end 136.401 90.839)
		(width 0.16)
		(layer "In5.Cu")
		(net 25)
	)
	(arc
		(start 141.061 94.989)
		(mid 141.449202 94.828202)
		(end 141.61 94.44)
		(width 0.16)
		(layer "In5.Cu")
		(net 25)
	)
	(arc
		(start 133.378915 80.76)
		(mid 133.432654 80.737738)
		(end 133.486396 80.759999)
		(width 0.16)
		(layer "In5.Cu")
		(net 25)
	)
	(arc
		(start 136.818979 93.659697)
		(mid 137.189503 93.813173)
		(end 137.560027 93.659697)
		(width 0.16)
		(layer "In5.Cu")
		(net 25)
	)
	(arc
		(start 132.74464 80.865357)
		(mid 133.0091 80.974901)
		(end 133.273558 80.865359)
		(width 0.16)
		(layer "In5.Cu")
		(net 25)
	)
	(arc
		(start 137.05 87.339)
		(mid 137.020418 87.410418)
		(end 136.949 87.44)
		(width 0.16)
		(layer "In5.Cu")
		(net 25)
	)
	(arc
		(start 131.605 80.175)
		(mid 131.729187 80.474813)
		(end 132.029 80.599)
		(width 0.16)
		(layer "In5.Cu")
		(net 25)
	)
	(arc
		(start 141.61 93.361736)
		(mid 141.683516 93.184252)
		(end 141.861 93.110736)
		(width 0.16)
		(layer "In5.Cu")
		(net 25)
	)
	(arc
		(start 129.653 80.026)
		(mid 129.689905 79.936905)
		(end 129.779 79.9)
		(width 0.16)
		(layer "In5.Cu")
		(net 25)
	)
	(arc
		(start 127.158 80.8)
		(mid 127.216872 80.657872)
		(end 127.359 80.599)
		(width 0.16)
		(layer "In5.Cu")
		(net 25)
	)
	(arc
		(start 131.153 80.026)
		(mid 131.189905 79.936905)
		(end 131.279 79.9)
		(width 0.16)
		(layer "In5.Cu")
		(net 25)
	)
	(arc
		(start 136.949 85.488)
		(mid 137.020418 85.517582)
		(end 137.05 85.589)
		(width 0.16)
		(layer "In5.Cu")
		(net 25)
	)
	(segment
		(start 143.766 94)
		(end 144.12 94.354)
		(width 0.125)
		(layer "B.Cu")
		(net 25)
	)
	(segment
		(start 143.15 94)
		(end 143.766 94)
		(width 0.125)
		(layer "B.Cu")
		(net 25)
	)
	(segment
		(start 76.625 103.698223)
		(end 77.67 102.653223)
		(width 0.125)
		(layer "F.Cu")
		(net 26)
	)
	(segment
		(start 76.625 104.892469)
		(end 76.625 103.698223)
		(width 0.125)
		(layer "F.Cu")
		(net 26)
	)
	(segment
		(start 76.55 104.967469)
		(end 76.625 104.892469)
		(width 0.125)
		(layer "F.Cu")
		(net 26)
	)
	(segment
		(start 77.67 102.653223)
		(end 77.67 102.41)
		(width 0.125)
		(layer "F.Cu")
		(net 26)
	)
	(via
		(at 88.643294 91.703294)
		(size 0.45)
		(drill 0.1)
		(layers "F.Cu" "B.Cu")
		(net 26)
	)
	(via
		(at 77.67 102.41)
		(size 0.45)
		(drill 0.1)
		(layers "F.Cu" "B.Cu")
		(net 26)
	)
	(segment
		(start 90.540458 92.835458)
		(end 90.540458 92.845)
		(width 0.125)
		(layer "In5.Cu")
		(net 26)
	)
	(segment
		(start 86.27417 100.93834)
		(end 85.237512 101.975)
		(width 0.125)
		(layer "In5.Cu")
		(net 26)
	)
	(segment
		(start 88.643294 91.544194)
		(end 88.782488 91.405)
		(width 0.125)
		(layer "In5.Cu")
		(net 26)
	)
	(segment
		(start 89.297512 91.405)
		(end 89.625 91.732488)
		(width 0.125)
		(layer "In5.Cu")
		(net 26)
	)
	(segment
		(start 90.195229 94.545)
		(end 88.709542 94.545)
		(width 0.125)
		(layer "In5.Cu")
		(net 26)
	)
	(segment
		(start 86.98128 99.736256)
		(end 86.910569 99.806966)
		(width 0.125)
		(layer "In5.Cu")
		(net 26)
	)
	(segment
		(start 88.835 98.377512)
		(end 87.476256 99.736256)
		(width 0.125)
		(layer "In5.Cu")
		(net 26)
	)
	(segment
		(start 90.240458 94.190229)
		(end 90.240458 94.499771)
		(width 0.125)
		(layer "In5.Cu")
		(net 26)
	)
	(segment
		(start 88.643294 91.703294)
		(end 88.643294 91.544194)
		(width 0.125)
		(layer "In5.Cu")
		(net 26)
	)
	(segment
		(start 86.981281 99.736255)
		(end 86.98128 99.736256)
		(width 0.125)
		(layer "In5.Cu")
		(net 26)
	)
	(segment
		(start 88.709542 94.145)
		(end 90.195229 94.145)
		(width 0.125)
		(layer "In5.Cu")
		(net 26)
	)
	(segment
		(start 89.8 93.040229)
		(end 89.8 93.045)
		(width 0.125)
		(layer "In5.Cu")
		(net 26)
	)
	(segment
		(start 78.267512 101.975)
		(end 77.832512 102.41)
		(width 0.125)
		(layer "In5.Cu")
		(net 26)
	)
	(segment
		(start 89.8 93.045)
		(end 88.709542 93.045)
		(width 0.125)
		(layer "In5.Cu")
		(net 26)
	)
	(segment
		(start 88.835 97.187512)
		(end 88.835 98.377512)
		(width 0.125)
		(layer "In5.Cu")
		(net 26)
	)
	(segment
		(start 86.75147 100.531755)
		(end 86.592369 100.372655)
		(width 0.125)
		(layer "In5.Cu")
		(net 26)
	)
	(segment
		(start 90.170229 92.640229)
		(end 90.345229 92.640229)
		(width 0.125)
		(layer "In5.Cu")
		(net 26)
	)
	(segment
		(start 87.069668 100.284266)
		(end 87.069668 100.284267)
		(width 0.125)
		(layer "In5.Cu")
		(net 26)
	)
	(segment
		(start 86.344881 100.372655)
		(end 86.27417 100.443365)
		(width 0.125)
		(layer "In5.Cu")
		(net 26)
	)
	(segment
		(start 89.625 95.845)
		(end 89.625 96.397512)
		(width 0.125)
		(layer "In5.Cu")
		(net 26)
	)
	(segment
		(start 89.625 96.397512)
		(end 88.835 97.187512)
		(width 0.125)
		(layer "In5.Cu")
		(net 26)
	)
	(segment
		(start 77.832512 102.41)
		(end 77.67 102.41)
		(width 0.125)
		(layer "In5.Cu")
		(net 26)
	)
	(segment
		(start 86.274169 100.93834)
		(end 86.27417 100.93834)
		(width 0.125)
		(layer "In5.Cu")
		(net 26)
	)
	(segment
		(start 90.345229 93.040229)
		(end 89.8 93.040229)
		(width 0.125)
		(layer "In5.Cu")
		(net 26)
	)
	(segment
		(start 88.782488 91.405)
		(end 89.297512 91.405)
		(width 0.125)
		(layer "In5.Cu")
		(net 26)
	)
	(segment
		(start 85.237512 101.975)
		(end 78.267512 101.975)
		(width 0.125)
		(layer "In5.Cu")
		(net 26)
	)
	(segment
		(start 87.069668 100.284267)
		(end 86.822182 100.531754)
		(width 0.125)
		(layer "In5.Cu")
		(net 26)
	)
	(segment
		(start 88.709542 95.645)
		(end 89.425 95.645)
		(width 0.125)
		(layer "In5.Cu")
		(net 26)
	)
	(segment
		(start 86.751472 100.531754)
		(end 86.75147 100.531755)
		(width 0.125)
		(layer "In5.Cu")
		(net 26)
	)
	(segment
		(start 87.034312 100.178197)
		(end 87.069669 100.213555)
		(width 0.125)
		(layer "In5.Cu")
		(net 26)
	)
	(segment
		(start 89.625 91.732488)
		(end 89.625 92.095)
		(width 0.125)
		(layer "In5.Cu")
		(net 26)
	)
	(segment
		(start 86.910569 100.054454)
		(end 87.034312 100.178197)
		(width 0.125)
		(layer "In5.Cu")
		(net 26)
	)
	(arc
		(start 87.069669 100.213555)
		(mid 87.084313 100.248911)
		(end 87.069668 100.284266)
		(width 0.125)
		(layer "In5.Cu")
		(net 26)
	)
	(arc
		(start 89.425 95.645)
		(mid 89.566421 95.703579)
		(end 89.625 95.845)
		(width 0.125)
		(layer "In5.Cu")
		(net 26)
	)
	(arc
		(start 88.709542 94.545)
		(mid 88.320633 94.706091)
		(end 88.159542 95.095)
		(width 0.125)
		(layer "In5.Cu")
		(net 26)
	)
	(arc
		(start 86.822182 100.531754)
		(mid 86.786827 100.546399)
		(end 86.751472 100.531754)
		(width 0.125)
		(layer "In5.Cu")
		(net 26)
	)
	(arc
		(start 86.27417 100.443365)
		(mid 86.222914 100.567109)
		(end 86.27417 100.690853)
		(width 0.125)
		(layer "In5.Cu")
		(net 26)
	)
	(arc
		(start 88.159542 93.595)
		(mid 88.320633 93.983909)
		(end 88.709542 94.145)
		(width 0.125)
		(layer "In5.Cu")
		(net 26)
	)
	(arc
		(start 89.625 92.095)
		(mid 89.784694 92.480535)
		(end 90.170229 92.640229)
		(width 0.125)
		(layer "In5.Cu")
		(net 26)
	)
	(arc
		(start 87.476256 99.736256)
		(mid 87.352512 99.787512)
		(end 87.228768 99.736256)
		(width 0.125)
		(layer "In5.Cu")
		(net 26)
	)
	(arc
		(start 86.910569 99.806966)
		(mid 86.859313 99.93071)
		(end 86.910569 100.054454)
		(width 0.125)
		(layer "In5.Cu")
		(net 26)
	)
	(arc
		(start 90.345229 92.640229)
		(mid 90.483277 92.69741)
		(end 90.540458 92.835458)
		(width 0.125)
		(layer "In5.Cu")
		(net 26)
	)
	(arc
		(start 90.240458 94.499771)
		(mid 90.227211 94.531753)
		(end 90.195229 94.545)
		(width 0.125)
		(layer "In5.Cu")
		(net 26)
	)
	(arc
		(start 87.228768 99.736256)
		(mid 87.105025 99.684999)
		(end 86.981281 99.736255)
		(width 0.125)
		(layer "In5.Cu")
		(net 26)
	)
	(arc
		(start 86.592369 100.372655)
		(mid 86.468625 100.321399)
		(end 86.344881 100.372655)
		(width 0.125)
		(layer "In5.Cu")
		(net 26)
	)
	(arc
		(start 88.709542 93.045)
		(mid 88.320633 93.206091)
		(end 88.159542 93.595)
		(width 0.125)
		(layer "In5.Cu")
		(net 26)
	)
	(arc
		(start 88.159542 95.095)
		(mid 88.320633 95.483909)
		(end 88.709542 95.645)
		(width 0.125)
		(layer "In5.Cu")
		(net 26)
	)
	(arc
		(start 86.27417 100.690853)
		(mid 86.325426 100.814597)
		(end 86.274169 100.93834)
		(width 0.125)
		(layer "In5.Cu")
		(net 26)
	)
	(arc
		(start 90.540458 92.845)
		(mid 90.483277 92.983048)
		(end 90.345229 93.040229)
		(width 0.125)
		(layer "In5.Cu")
		(net 26)
	)
	(arc
		(start 90.195229 94.145)
		(mid 90.227211 94.158247)
		(end 90.240458 94.190229)
		(width 0.125)
		(layer "In5.Cu")
		(net 26)
	)
	(segment
		(start 88.643294 91.473483)
		(end 88.643294 91.703294)
		(width 0.125)
		(layer "B.Cu")
		(net 26)
	)
	(segment
		(start 89.6325 91.45)
		(end 89.5075 91.325)
		(width 0.125)
		(layer "B.Cu")
		(net 26)
	)
	(segment
		(start 88.791777 91.325)
		(end 88.643294 91.473483)
		(width 0.125)
		(layer "B.Cu")
		(net 26)
	)
	(segment
		(start 89.5075 91.325)
		(end 88.791777 91.325)
		(width 0.125)
		(layer "B.Cu")
		(net 26)
	)
	(segment
		(start 76.896777 101.39)
		(end 77.17 101.39)
		(width 0.125)
		(layer "F.Cu")
		(net 27)
	)
	(segment
		(start 75.675 104.892469)
		(end 75.675 102.611777)
		(width 0.125)
		(layer "F.Cu")
		(net 27)
	)
	(segment
		(start 75.75 104.967469)
		(end 75.675 104.892469)
		(width 0.125)
		(layer "F.Cu")
		(net 27)
	)
	(segment
		(start 75.675 102.611777)
		(end 76.896777 101.39)
		(width 0.125)
		(layer "F.Cu")
		(net 27)
	)
	(via
		(at 86.873294 90.056706)
		(size 0.45)
		(drill 0.1)
		(layers "F.Cu" "B.Cu")
		(net 27)
	)
	(via
		(at 77.17 101.39)
		(size 0.45)
		(drill 0.1)
		(layers "F.Cu" "B.Cu")
		(net 27)
	)
	(segment
		(start 85.89588 95.45412)
		(end 85.72088 95.45412)
		(width 0.125)
		(layer "In5.Cu")
		(net 27)
	)
	(segment
		(start 87.185 90.527512)
		(end 87.185 92.362488)
		(width 0.125)
		(layer "In5.Cu")
		(net 27)
	)
	(segment
		(start 86.305 93.242488)
		(end 86.305 95.045)
		(width 0.125)
		(layer "In5.Cu")
		(net 27)
	)
	(segment
		(start 77.192488 101.185)
		(end 77.17 101.207488)
		(width 0.125)
		(layer "In5.Cu")
		(net 27)
	)
	(segment
		(start 77.17 101.207488)
		(end 77.17 101.39)
		(width 0.125)
		(layer "In5.Cu")
		(net 27)
	)
	(segment
		(start 87.59824 98.87)
		(end 86.555 98.87)
		(width 0.125)
		(layer "In5.Cu")
		(net 27)
	)
	(segment
		(start 85.72088 95.95412)
		(end 86.13 95.95412)
		(width 0.125)
		(layer "In5.Cu")
		(net 27)
	)
	(segment
		(start 87.185 92.362488)
		(end 86.305 93.242488)
		(width 0.125)
		(layer "In5.Cu")
		(net 27)
	)
	(segment
		(start 86.873294 90.215806)
		(end 87.185 90.527512)
		(width 0.125)
		(layer "In5.Cu")
		(net 27)
	)
	(segment
		(start 86.305 99.12)
		(end 86.305 99.612488)
		(width 0.125)
		(layer "In5.Cu")
		(net 27)
	)
	(segment
		(start 84.732488 101.185)
		(end 77.192488 101.185)
		(width 0.125)
		(layer "In5.Cu")
		(net 27)
	)
	(segment
		(start 86.873294 90.056706)
		(end 86.873294 90.215806)
		(width 0.125)
		(layer "In5.Cu")
		(net 27)
	)
	(segment
		(start 87.09824 97.17)
		(end 86.555 97.17)
		(width 0.125)
		(layer "In5.Cu")
		(net 27)
	)
	(segment
		(start 85.66176 95.51324)
		(end 85.66176 95.895)
		(width 0.125)
		(layer "In5.Cu")
		(net 27)
	)
	(segment
		(start 86.305 99.612488)
		(end 84.732488 101.185)
		(width 0.125)
		(layer "In5.Cu")
		(net 27)
	)
	(segment
		(start 86.555 97.67)
		(end 87.59824 97.67)
		(width 0.125)
		(layer "In5.Cu")
		(net 27)
	)
	(segment
		(start 86.13 95.95412)
		(end 86.13 95.97)
		(width 0.125)
		(layer "In5.Cu")
		(net 27)
	)
	(segment
		(start 86.13 95.97)
		(end 87.09824 95.97)
		(width 0.125)
		(layer "In5.Cu")
		(net 27)
	)
	(arc
		(start 85.72088 95.45412)
		(mid 85.679076 95.471436)
		(end 85.66176 95.51324)
		(width 0.125)
		(layer "In5.Cu")
		(net 27)
	)
	(arc
		(start 88.19824 98.27)
		(mid 88.022504 98.694264)
		(end 87.59824 98.87)
		(width 0.125)
		(layer "In5.Cu")
		(net 27)
	)
	(arc
		(start 86.305 97.42)
		(mid 86.378223 97.596777)
		(end 86.555 97.67)
		(width 0.125)
		(layer "In5.Cu")
		(net 27)
	)
	(arc
		(start 87.69824 96.57)
		(mid 87.522504 96.994264)
		(end 87.09824 97.17)
		(width 0.125)
		(layer "In5.Cu")
		(net 27)
	)
	(arc
		(start 86.555 98.87)
		(mid 86.378223 98.943223)
		(end 86.305 99.12)
		(width 0.125)
		(layer "In5.Cu")
		(net 27)
	)
	(arc
		(start 87.09824 95.97)
		(mid 87.522504 96.145736)
		(end 87.69824 96.57)
		(width 0.125)
		(layer "In5.Cu")
		(net 27)
	)
	(arc
		(start 87.59824 97.67)
		(mid 88.022504 97.845736)
		(end 88.19824 98.27)
		(width 0.125)
		(layer "In5.Cu")
		(net 27)
	)
	(arc
		(start 86.305 95.045)
		(mid 86.185172 95.334292)
		(end 85.89588 95.45412)
		(width 0.125)
		(layer "In5.Cu")
		(net 27)
	)
	(arc
		(start 86.555 97.17)
		(mid 86.378223 97.243223)
		(end 86.305 97.42)
		(width 0.125)
		(layer "In5.Cu")
		(net 27)
	)
	(arc
		(start 85.66176 95.895)
		(mid 85.679076 95.936804)
		(end 85.72088 95.95412)
		(width 0.125)
		(layer "In5.Cu")
		(net 27)
	)
	(segment
		(start 88.248222 90.075)
		(end 87.708222 90.615)
		(width 0.125)
		(layer "B.Cu")
		(net 27)
	)
	(segment
		(start 86.873294 90.286517)
		(end 86.873294 90.056706)
		(width 0.125)
		(layer "B.Cu")
		(net 27)
	)
	(segment
		(start 89.6325 89.95)
		(end 89.5075 90.075)
		(width 0.125)
		(layer "B.Cu")
		(net 27)
	)
	(segment
		(start 89.5075 90.075)
		(end 88.248222 90.075)
		(width 0.125)
		(layer "B.Cu")
		(net 27)
	)
	(segment
		(start 87.708222 90.615)
		(end 87.201777 90.615)
		(width 0.125)
		(layer "B.Cu")
		(net 27)
	)
	(segment
		(start 87.201777 90.615)
		(end 86.873294 90.286517)
		(width 0.125)
		(layer "B.Cu")
		(net 27)
	)
	(segment
		(start 72.677 103.823778)
		(end 72.677 103.388)
		(width 0.125)
		(layer "F.Cu")
		(net 28)
	)
	(segment
		(start 72.677 103.388)
		(end 72.491 103.202)
		(width 0.125)
		(layer "F.Cu")
		(net 28)
	)
	(segment
		(start 73.027 104.894469)
		(end 73.027 104.173778)
		(width 0.125)
		(layer "F.Cu")
		(net 28)
	)
	(segment
		(start 72.952 104.969469)
		(end 73.027 104.894469)
		(width 0.125)
		(layer "F.Cu")
		(net 28)
	)
	(segment
		(start 73.027 104.173778)
		(end 72.677 103.823778)
		(width 0.125)
		(layer "F.Cu")
		(net 28)
	)
	(via
		(at 84.723794 88.153294)
		(size 0.45)
		(drill 0.1)
		(layers "F.Cu" "B.Cu")
		(net 28)
	)
	(via
		(at 72.491 103.202)
		(size 0.45)
		(drill 0.1)
		(layers "F.Cu" "B.Cu")
		(net 28)
	)
	(segment
		(start 72.627 103.066)
		(end 72.491 103.202)
		(width 0.125)
		(layer "In5.Cu")
		(net 28)
	)
	(segment
		(start 84.723794 87.994194)
		(end 84.9255 87.792488)
		(width 0.125)
		(layer "In5.Cu")
		(net 28)
	)
	(segment
		(start 74.85 98.877512)
		(end 72.627 101.100512)
		(width 0.125)
		(layer "In5.Cu")
		(net 28)
	)
	(segment
		(start 84.9255 87.792488)
		(end 84.9255 87.237512)
		(width 0.125)
		(layer "In5.Cu")
		(net 28)
	)
	(segment
		(start 72.627 101.100512)
		(end 72.627 103.066)
		(width 0.125)
		(layer "In5.Cu")
		(net 28)
	)
	(segment
		(start 83.948012 86.865)
		(end 82.795 88.018012)
		(width 0.125)
		(layer "In5.Cu")
		(net 28)
	)
	(segment
		(start 82.795 88.018012)
		(end 82.795 96.687512)
		(width 0.125)
		(layer "In5.Cu")
		(net 28)
	)
	(segment
		(start 84.9255 87.237512)
		(end 84.552988 86.865)
		(width 0.125)
		(layer "In5.Cu")
		(net 28)
	)
	(segment
		(start 84.723794 88.153294)
		(end 84.723794 87.994194)
		(width 0.125)
		(layer "In5.Cu")
		(net 28)
	)
	(segment
		(start 84.552988 86.865)
		(end 83.948012 86.865)
		(width 0.125)
		(layer "In5.Cu")
		(net 28)
	)
	(segment
		(start 74.85 98.875)
		(end 74.85 98.877512)
		(width 0.125)
		(layer "In5.Cu")
		(net 28)
	)
	(segment
		(start 80.607512 98.875)
		(end 74.85 98.875)
		(width 0.125)
		(layer "In5.Cu")
		(net 28)
	)
	(segment
		(start 82.795 96.687512)
		(end 80.607512 98.875)
		(width 0.125)
		(layer "In5.Cu")
		(net 28)
	)
	(segment
		(start 89.633 88.45)
		(end 89.508 88.325)
		(width 0.125)
		(layer "B.Cu")
		(net 28)
	)
	(segment
		(start 89.508 88.325)
		(end 88.348722 88.325)
		(width 0.125)
		(layer "B.Cu")
		(net 28)
	)
	(segment
		(start 88.348722 88.325)
		(end 87.768722 87.745)
		(width 0.125)
		(layer "B.Cu")
		(net 28)
	)
	(segment
		(start 84.902277 87.745)
		(end 84.723794 87.923483)
		(width 0.125)
		(layer "B.Cu")
		(net 28)
	)
	(segment
		(start 87.768722 87.745)
		(end 84.902277 87.745)
		(width 0.125)
		(layer "B.Cu")
		(net 28)
	)
	(segment
		(start 84.723794 87.923483)
		(end 84.723794 88.153294)
		(width 0.125)
		(layer "B.Cu")
		(net 28)
	)
	(segment
		(start 72.927 103.720222)
		(end 72.927 103.388)
		(width 0.125)
		(layer "F.Cu")
		(net 29)
	)
	(segment
		(start 73.277 104.070222)
		(end 72.927 103.720222)
		(width 0.125)
		(layer "F.Cu")
		(net 29)
	)
	(segment
		(start 72.927 103.388)
		(end 73.113 103.202)
		(width 0.125)
		(layer "F.Cu")
		(net 29)
	)
	(segment
		(start 73.352 104.969469)
		(end 73.277 104.894469)
		(width 0.125)
		(layer "F.Cu")
		(net 29)
	)
	(segment
		(start 73.277 104.894469)
		(end 73.277 104.070222)
		(width 0.125)
		(layer "F.Cu")
		(net 29)
	)
	(via
		(at 73.113 103.202)
		(size 0.45)
		(drill 0.1)
		(layers "F.Cu" "B.Cu")
		(net 29)
	)
	(via
		(at 84.317206 87.746706)
		(size 0.45)
		(drill 0.1)
		(layers "F.Cu" "B.Cu")
		(net 29)
	)
	(segment
		(start 83.145 88.162988)
		(end 84.092988 87.215)
		(width 0.125)
		(layer "In5.Cu")
		(net 29)
	)
	(segment
		(start 84.092988 87.215)
		(end 84.408012 87.215)
		(width 0.125)
		(layer "In5.Cu")
		(net 29)
	)
	(segment
		(start 84.476306 87.746706)
		(end 84.317206 87.746706)
		(width 0.125)
		(layer "In5.Cu")
		(net 29)
	)
	(segment
		(start 72.977 103.066)
		(end 72.977 101.245488)
		(width 0.125)
		(layer "In5.Cu")
		(net 29)
	)
	(segment
		(start 73.113 103.202)
		(end 72.977 103.066)
		(width 0.125)
		(layer "In5.Cu")
		(net 29)
	)
	(segment
		(start 84.5755 87.382488)
		(end 84.5755 87.647512)
		(width 0.125)
		(layer "In5.Cu")
		(net 29)
	)
	(segment
		(start 74.305114 99.917371)
		(end 74.997488 99.225)
		(width 0.125)
		(layer "In5.Cu")
		(net 29)
	)
	(segment
		(start 73.796176 100.822647)
		(end 73.796176 100.822648)
		(width 0.125)
		(layer "In5.Cu")
		(net 29)
	)
	(segment
		(start 84.408012 87.215)
		(end 84.5755 87.382488)
		(width 0.125)
		(layer "In5.Cu")
		(net 29)
	)
	(segment
		(start 83.145 96.832488)
		(end 83.145 88.162988)
		(width 0.125)
		(layer "In5.Cu")
		(net 29)
	)
	(segment
		(start 73.796176 100.822648)
		(end 73.739428 100.7659)
		(width 0.125)
		(layer "In5.Cu")
		(net 29)
	)
	(segment
		(start 80.752488 99.225)
		(end 83.145 96.832488)
		(width 0.125)
		(layer "In5.Cu")
		(net 29)
	)
	(segment
		(start 74.361872 100.256972)
		(end 74.305114 100.200214)
		(width 0.125)
		(layer "In5.Cu")
		(net 29)
	)
	(segment
		(start 74.361872 100.539814)
		(end 74.361872 100.539815)
		(width 0.125)
		(layer "In5.Cu")
		(net 29)
	)
	(segment
		(start 74.305115 99.917371)
		(end 74.305114 99.917371)
		(width 0.125)
		(layer "In5.Cu")
		(net 29)
	)
	(segment
		(start 72.977 101.245488)
		(end 73.173744 101.048744)
		(width 0.125)
		(layer "In5.Cu")
		(net 29)
	)
	(segment
		(start 73.456586 101.048744)
		(end 73.513333 101.105491)
		(width 0.125)
		(layer "In5.Cu")
		(net 29)
	)
	(segment
		(start 74.361872 100.256971)
		(end 74.361872 100.256972)
		(width 0.125)
		(layer "In5.Cu")
		(net 29)
	)
	(segment
		(start 84.5755 87.647512)
		(end 84.476306 87.746706)
		(width 0.125)
		(layer "In5.Cu")
		(net 29)
	)
	(segment
		(start 74.997488 99.225)
		(end 80.752488 99.225)
		(width 0.125)
		(layer "In5.Cu")
		(net 29)
	)
	(segment
		(start 73.739428 100.483058)
		(end 73.739428 100.483057)
		(width 0.125)
		(layer "In5.Cu")
		(net 29)
	)
	(segment
		(start 74.022272 100.483058)
		(end 74.079029 100.539815)
		(width 0.125)
		(layer "In5.Cu")
		(net 29)
	)
	(segment
		(start 73.796175 101.105491)
		(end 73.796176 101.105491)
		(width 0.125)
		(layer "In5.Cu")
		(net 29)
	)
	(segment
		(start 73.739428 100.483057)
		(end 73.73943 100.483058)
		(width 0.125)
		(layer "In5.Cu")
		(net 29)
	)
	(arc
		(start 73.739428 100.7659)
		(mid 73.68085 100.624479)
		(end 73.739428 100.483058)
		(width 0.125)
		(layer "In5.Cu")
		(net 29)
	)
	(arc
		(start 73.73943 100.483058)
		(mid 73.880851 100.42448)
		(end 74.022272 100.483058)
		(width 0.125)
		(layer "In5.Cu")
		(net 29)
	)
	(arc
		(start 73.513333 101.105491)
		(mid 73.654754 101.164069)
		(end 73.796175 101.105491)
		(width 0.125)
		(layer "In5.Cu")
		(net 29)
	)
	(arc
		(start 74.361872 100.539815)
		(mid 74.420451 100.398393)
		(end 74.361872 100.256971)
		(width 0.125)
		(layer "In5.Cu")
		(net 29)
	)
	(arc
		(start 73.173744 101.048744)
		(mid 73.315165 100.990166)
		(end 73.456586 101.048744)
		(width 0.125)
		(layer "In5.Cu")
		(net 29)
	)
	(arc
		(start 74.305114 100.200214)
		(mid 74.246536 100.058792)
		(end 74.305115 99.917371)
		(width 0.125)
		(layer "In5.Cu")
		(net 29)
	)
	(arc
		(start 73.796176 101.105491)
		(mid 73.854755 100.964069)
		(end 73.796176 100.822647)
		(width 0.125)
		(layer "In5.Cu")
		(net 29)
	)
	(arc
		(start 74.079029 100.539815)
		(mid 74.220451 100.598393)
		(end 74.361872 100.539814)
		(width 0.125)
		(layer "In5.Cu")
		(net 29)
	)
	(segment
		(start 84.798723 87.495)
		(end 84.547017 87.746706)
		(width 0.125)
		(layer "B.Cu")
		(net 29)
	)
	(segment
		(start 89.633 87.95)
		(end 89.508 88.075)
		(width 0.125)
		(layer "B.Cu")
		(net 29)
	)
	(segment
		(start 84.547017 87.746706)
		(end 84.317206 87.746706)
		(width 0.125)
		(layer "B.Cu")
		(net 29)
	)
	(segment
		(start 87.872278 87.495)
		(end 84.798723 87.495)
		(width 0.125)
		(layer "B.Cu")
		(net 29)
	)
	(segment
		(start 88.452278 88.075)
		(end 87.872278 87.495)
		(width 0.125)
		(layer "B.Cu")
		(net 29)
	)
	(segment
		(start 89.508 88.075)
		(end 88.452278 88.075)
		(width 0.125)
		(layer "B.Cu")
		(net 29)
	)
	(segment
		(start 127.81 71.61)
		(end 127.81 72.07)
		(width 0.15)
		(layer "F.Cu")
		(net 30)
	)
	(segment
		(start 133.65 101.65)
		(end 135.42 103.42)
		(width 0.15)
		(layer "F.Cu")
		(net 30)
	)
	(segment
		(start 130.7 94.51)
		(end 130.7 99.17)
		(width 0.15)
		(layer "F.Cu")
		(net 30)
	)
	(segment
		(start 135.42 103.42)
		(end 137.93 103.42)
		(width 0.15)
		(layer "F.Cu")
		(net 30)
	)
	(segment
		(start 138.25 103.1)
		(end 138.85 103.1)
		(width 0.15)
		(layer "F.Cu")
		(net 30)
	)
	(segment
		(start 134.45 94.01)
		(end 134.36 93.92)
		(width 0.15)
		(layer "F.Cu")
		(net 30)
	)
	(segment
		(start 137.93 103.42)
		(end 138.25 103.1)
		(width 0.15)
		(layer "F.Cu")
		(net 30)
	)
	(segment
		(start 134.36 93.92)
		(end 131.29 93.92)
		(width 0.15)
		(layer "F.Cu")
		(net 30)
	)
	(segment
		(start 104.097323 70.542677)
		(end 104.48 70.16)
		(width 0.15)
		(layer "F.Cu")
		(net 30)
	)
	(segment
		(start 130.7 99.17)
		(end 131.08 99.55)
		(width 0.15)
		(layer "F.Cu")
		(net 30)
	)
	(segment
		(start 126 69.8)
		(end 127.81 71.61)
		(width 0.15)
		(layer "F.Cu")
		(net 30)
	)
	(segment
		(start 131.29 93.92)
		(end 130.7 94.51)
		(width 0.15)
		(layer "F.Cu")
		(net 30)
	)
	(segment
		(start 104.85 69.8)
		(end 126 69.8)
		(width 0.15)
		(layer "F.Cu")
		(net 30)
	)
	(segment
		(start 104.097323 72.005136)
		(end 104.097323 70.542677)
		(width 0.15)
		(layer "F.Cu")
		(net 30)
	)
	(segment
		(start 133.65 100.4)
		(end 133.65 101.65)
		(width 0.15)
		(layer "F.Cu")
		(net 30)
	)
	(segment
		(start 104.48 70.16)
		(end 104.49 70.16)
		(width 0.15)
		(layer "F.Cu")
		(net 30)
	)
	(segment
		(start 132.8 99.55)
		(end 133.65 100.4)
		(width 0.15)
		(layer "F.Cu")
		(net 30)
	)
	(segment
		(start 131.08 99.55)
		(end 132.8 99.55)
		(width 0.15)
		(layer "F.Cu")
		(net 30)
	)
	(segment
		(start 134.45 94.2)
		(end 134.45 94.01)
		(width 0.15)
		(layer "F.Cu")
		(net 30)
	)
	(segment
		(start 104.49 70.16)
		(end 104.85 69.8)
		(width 0.15)
		(layer "F.Cu")
		(net 30)
	)
	(via
		(at 127.8 72.1)
		(size 0.45)
		(drill 0.1)
		(layers "F.Cu" "B.Cu")
		(net 30)
	)
	(via
		(at 134.45 94.2)
		(size 0.45)
		(drill 0.1)
		(layers "F.Cu" "B.Cu")
		(net 30)
	)
	(segment
		(start 127.8 71.85)
		(end 127.8 72.1)
		(width 0.15)
		(layer "In3.Cu")
		(net 30)
	)
	(segment
		(start 135.89 78.56)
		(end 130.66 73.33)
		(width 0.15)
		(layer "In3.Cu")
		(net 30)
	)
	(segment
		(start 129.6 71.16)
		(end 128.49 71.16)
		(width 0.15)
		(layer "In3.Cu")
		(net 30)
	)
	(segment
		(start 128.49 71.16)
		(end 127.8 71.85)
		(width 0.15)
		(layer "In3.Cu")
		(net 30)
	)
	(segment
		(start 130.66 73.33)
		(end 130.66 72.22)
		(width 0.15)
		(layer "In3.Cu")
		(net 30)
	)
	(segment
		(start 135.89 93.18)
		(end 135.89 78.56)
		(width 0.15)
		(layer "In3.Cu")
		(net 30)
	)
	(segment
		(start 130.66 72.22)
		(end 129.6 71.16)
		(width 0.15)
		(layer "In3.Cu")
		(net 30)
	)
	(segment
		(start 134.45 94.2)
		(end 134.87 94.2)
		(width 0.15)
		(layer "In3.Cu")
		(net 30)
	)
	(segment
		(start 134.87 94.2)
		(end 135.89 93.18)
		(width 0.15)
		(layer "In3.Cu")
		(net 30)
	)
	(segment
		(start 138.85 102.55)
		(end 138.19 102.55)
		(width 0.15)
		(layer "F.Cu")
		(net 31)
	)
	(segment
		(start 131.33 94.39)
		(end 133.57 94.39)
		(width 0.15)
		(layer "F.Cu")
		(net 31)
	)
	(segment
		(start 126.125 69.525)
		(end 128.38 71.78)
		(width 0.15)
		(layer "F.Cu")
		(net 31)
	)
	(segment
		(start 104.525 69.525)
		(end 126.125 69.525)
		(width 0.15)
		(layer "F.Cu")
		(net 31)
	)
	(segment
		(start 134 100.3)
		(end 132.95 99.25)
		(width 0.15)
		(layer "F.Cu")
		(net 31)
	)
	(segment
		(start 135.2 100.3)
		(end 134 100.3)
		(width 0.15)
		(layer "F.Cu")
		(net 31)
	)
	(segment
		(start 133.57 94.39)
		(end 133.59 94.37)
		(width 0.15)
		(layer "F.Cu")
		(net 31)
	)
	(segment
		(start 103.597323 70.452677)
		(end 104.525 69.525)
		(width 0.15)
		(layer "F.Cu")
		(net 31)
	)
	(segment
		(start 135.51 103.06)
		(end 134.95 102.5)
		(width 0.15)
		(layer "F.Cu")
		(net 31)
	)
	(segment
		(start 134.95 102.5)
		(end 134.95 101.9)
		(width 0.15)
		(layer "F.Cu")
		(net 31)
	)
	(segment
		(start 138.19 102.55)
		(end 137.68 103.06)
		(width 0.15)
		(layer "F.Cu")
		(net 31)
	)
	(segment
		(start 135.6 100.7)
		(end 135.2 100.3)
		(width 0.15)
		(layer "F.Cu")
		(net 31)
	)
	(segment
		(start 135.6 101.25)
		(end 135.6 100.7)
		(width 0.15)
		(layer "F.Cu")
		(net 31)
	)
	(segment
		(start 103.597323 72.005136)
		(end 103.597323 70.452677)
		(width 0.15)
		(layer "F.Cu")
		(net 31)
	)
	(segment
		(start 137.68 103.06)
		(end 135.51 103.06)
		(width 0.15)
		(layer "F.Cu")
		(net 31)
	)
	(segment
		(start 131 98.96)
		(end 131 94.72)
		(width 0.15)
		(layer "F.Cu")
		(net 31)
	)
	(segment
		(start 132.95 99.25)
		(end 131.29 99.25)
		(width 0.15)
		(layer "F.Cu")
		(net 31)
	)
	(segment
		(start 134.95 101.9)
		(end 135.6 101.25)
		(width 0.15)
		(layer "F.Cu")
		(net 31)
	)
	(segment
		(start 128.38 71.78)
		(end 128.38 72.34)
		(width 0.15)
		(layer "F.Cu")
		(net 31)
	)
	(segment
		(start 131 94.72)
		(end 131.33 94.39)
		(width 0.15)
		(layer "F.Cu")
		(net 31)
	)
	(segment
		(start 131.29 99.25)
		(end 131 98.96)
		(width 0.15)
		(layer "F.Cu")
		(net 31)
	)
	(via
		(at 128.38 72.34)
		(size 0.45)
		(drill 0.1)
		(layers "F.Cu" "B.Cu")
		(net 31)
	)
	(via
		(at 133.59 94.37)
		(size 0.45)
		(drill 0.1)
		(layers "F.Cu" "B.Cu")
		(net 31)
	)
	(segment
		(start 128.38 71.76)
		(end 128.38 72.34)
		(width 0.15)
		(layer "In3.Cu")
		(net 31)
	)
	(segment
		(start 134.55 93.76)
		(end 135.61 92.7)
		(width 0.15)
		(layer "In3.Cu")
		(net 31)
	)
	(segment
		(start 135.61 92.7)
		(end 135.61 78.75)
		(width 0.15)
		(layer "In3.Cu")
		(net 31)
	)
	(segment
		(start 130.3 73.44)
		(end 130.3 72.44)
		(width 0.15)
		(layer "In3.Cu")
		(net 31)
	)
	(segment
		(start 129.36 71.5)
		(end 128.64 71.5)
		(width 0.15)
		(layer "In3.Cu")
		(net 31)
	)
	(segment
		(start 130.3 72.44)
		(end 129.36 71.5)
		(width 0.15)
		(layer "In3.Cu")
		(net 31)
	)
	(segment
		(start 135.61 78.75)
		(end 130.3 73.44)
		(width 0.15)
		(layer "In3.Cu")
		(net 31)
	)
	(segment
		(start 128.64 71.5)
		(end 128.38 71.76)
		(width 0.15)
		(layer "In3.Cu")
		(net 31)
	)
	(segment
		(start 133.59 94.37)
		(end 134.2 93.76)
		(width 0.15)
		(layer "In3.Cu")
		(net 31)
	)
	(segment
		(start 134.2 93.76)
		(end 134.55 93.76)
		(width 0.15)
		(layer "In3.Cu")
		(net 31)
	)
	(segment
		(start 104.37 69.25)
		(end 126.35 69.25)
		(width 0.15)
		(layer "F.Cu")
		(net 32)
	)
	(segment
		(start 103.097323 72.005136)
		(end 103.097323 70.522677)
		(width 0.15)
		(layer "F.Cu")
		(net 32)
	)
	(segment
		(start 126.35 69.25)
		(end 128.87 71.77)
		(width 0.15)
		(layer "F.Cu")
		(net 32)
	)
	(segment
		(start 133.21 93.64)
		(end 131.07 93.64)
		(width 0.15)
		(layer "F.Cu")
		(net 32)
	)
	(segment
		(start 133.35 101.8125)
		(end 136.8875 105.35)
		(width 0.15)
		(layer "F.Cu")
		(net 32)
	)
	(segment
		(start 103.097323 70.522677)
		(end 104.37 69.25)
		(width 0.15)
		(layer "F.Cu")
		(net 32)
	)
	(segment
		(start 133.62 93.48)
		(end 133.37 93.48)
		(width 0.15)
		(layer "F.Cu")
		(net 32)
	)
	(segment
		(start 136.8875 105.35)
		(end 138.8 105.35)
		(width 0.15)
		(layer "F.Cu")
		(net 32)
	)
	(segment
		(start 133.35 100.5)
		(end 133.35 101.8125)
		(width 0.15)
		(layer "F.Cu")
		(net 32)
	)
	(segment
		(start 128.87 71.77)
		(end 128.87 71.97)
		(width 0.15)
		(layer "F.Cu")
		(net 32)
	)
	(segment
		(start 130.4 99.31)
		(end 130.94 99.85)
		(width 0.15)
		(layer "F.Cu")
		(net 32)
	)
	(segment
		(start 130.94 99.85)
		(end 132.7 99.85)
		(width 0.15)
		(layer "F.Cu")
		(net 32)
	)
	(segment
		(start 132.7 99.85)
		(end 133.35 100.5)
		(width 0.15)
		(layer "F.Cu")
		(net 32)
	)
	(segment
		(start 131.07 93.64)
		(end 130.4 94.31)
		(width 0.15)
		(layer "F.Cu")
		(net 32)
	)
	(segment
		(start 130.4 94.31)
		(end 130.4 99.31)
		(width 0.15)
		(layer "F.Cu")
		(net 32)
	)
	(segment
		(start 133.37 93.48)
		(end 133.21 93.64)
		(width 0.15)
		(layer "F.Cu")
		(net 32)
	)
	(via
		(at 128.87 71.97)
		(size 0.45)
		(drill 0.1)
		(layers "F.Cu" "B.Cu")
		(net 32)
	)
	(via
		(at 133.62 93.48)
		(size 0.45)
		(drill 0.1)
		(layers "F.Cu" "B.Cu")
		(net 32)
	)
	(segment
		(start 134.64 90.86)
		(end 134.64 79.28)
		(width 0.15)
		(layer "In3.Cu")
		(net 32)
	)
	(segment
		(start 133.62 93.48)
		(end 133.62 93.47)
		(width 0.15)
		(layer "In3.Cu")
		(net 32)
	)
	(segment
		(start 133.07 92.92)
		(end 133.07 92.43)
		(width 0.15)
		(layer "In3.Cu")
		(net 32)
	)
	(segment
		(start 134.64 79.28)
		(end 128.87 73.51)
		(width 0.15)
		(layer "In3.Cu")
		(net 32)
	)
	(segment
		(start 133.07 92.43)
		(end 134.64 90.86)
		(width 0.15)
		(layer "In3.Cu")
		(net 32)
	)
	(segment
		(start 133.62 93.47)
		(end 133.07 92.92)
		(width 0.15)
		(layer "In3.Cu")
		(net 32)
	)
	(segment
		(start 128.87 73.51)
		(end 128.87 71.97)
		(width 0.15)
		(layer "In3.Cu")
		(net 32)
	)
	(segment
		(start 133.42 93.02)
		(end 133.94 93.02)
		(width 0.15)
		(layer "F.Cu")
		(net 33)
	)
	(segment
		(start 130.1 99.45)
		(end 130.1 94.18)
		(width 0.15)
		(layer "F.Cu")
		(net 33)
	)
	(segment
		(start 133.05 102)
		(end 133.05 100.65)
		(width 0.15)
		(layer "F.Cu")
		(net 33)
	)
	(segment
		(start 102.597323 72.005136)
		(end 102.597323 69.382677)
		(width 0.15)
		(layer "F.Cu")
		(net 33)
	)
	(segment
		(start 130.8 100.15)
		(end 130.1 99.45)
		(width 0.15)
		(layer "F.Cu")
		(net 33)
	)
	(segment
		(start 133.94 93.02)
		(end 134.2 93.28)
		(width 0.15)
		(layer "F.Cu")
		(net 33)
	)
	(segment
		(start 130.95 93.33)
		(end 133.11 93.33)
		(width 0.15)
		(layer "F.Cu")
		(net 33)
	)
	(segment
		(start 138.8 105.85)
		(end 136.9 105.85)
		(width 0.15)
		(layer "F.Cu")
		(net 33)
	)
	(segment
		(start 102.597323 69.382677)
		(end 102.6 69.38)
		(width 0.15)
		(layer "F.Cu")
		(net 33)
	)
	(segment
		(start 133.05 100.65)
		(end 132.55 100.15)
		(width 0.15)
		(layer "F.Cu")
		(net 33)
	)
	(segment
		(start 132.55 100.15)
		(end 130.8 100.15)
		(width 0.15)
		(layer "F.Cu")
		(net 33)
	)
	(segment
		(start 136.9 105.85)
		(end 133.05 102)
		(width 0.15)
		(layer "F.Cu")
		(net 33)
	)
	(segment
		(start 133.11 93.33)
		(end 133.42 93.02)
		(width 0.15)
		(layer "F.Cu")
		(net 33)
	)
	(segment
		(start 130.1 94.18)
		(end 130.95 93.33)
		(width 0.15)
		(layer "F.Cu")
		(net 33)
	)
	(via
		(at 102.6 69.38)
		(size 0.45)
		(drill 0.1)
		(layers "F.Cu" "B.Cu")
		(net 33)
	)
	(via
		(at 129.87 72.97)
		(size 0.45)
		(drill 0.1)
		(layers "F.Cu" "B.Cu")
		(net 33)
	)
	(via
		(at 134.2 93.28)
		(size 0.45)
		(drill 0.1)
		(layers "F.Cu" "B.Cu")
		(net 33)
	)
	(segment
		(start 135.27 78.89)
		(end 129.87 73.49)
		(width 0.15)
		(layer "In3.Cu")
		(net 33)
	)
	(segment
		(start 129.87 73.49)
		(end 129.87 72.97)
		(width 0.15)
		(layer "In3.Cu")
		(net 33)
	)
	(segment
		(start 135.27 92.21)
		(end 135.27 78.89)
		(width 0.15)
		(layer "In3.Cu")
		(net 33)
	)
	(segment
		(start 134.2 93.28)
		(end 135.27 92.21)
		(width 0.15)
		(layer "In3.Cu")
		(net 33)
	)
	(segment
		(start 102.765 69.215)
		(end 128.115 69.215)
		(width 0.13)
		(layer "B.Cu")
		(net 33)
	)
	(segment
		(start 128.115 69.215)
		(end 129.87 70.97)
		(width 0.13)
		(layer "B.Cu")
		(net 33)
	)
	(segment
		(start 129.87 70.97)
		(end 129.87 72.97)
		(width 0.13)
		(layer "B.Cu")
		(net 33)
	)
	(segment
		(start 102.765 69.215)
		(end 102.6 69.38)
		(width 0.13)
		(layer "B.Cu")
		(net 33)
	)
	(segment
		(start 132.78 93)
		(end 130.8 93)
		(width 0.15)
		(layer "F.Cu")
		(net 34)
	)
	(segment
		(start 102.097323 70.277323)
		(end 101.92 70.1)
		(width 0.15)
		(layer "F.Cu")
		(net 34)
	)
	(segment
		(start 101.92 70.1)
		(end 101.92 69.38)
		(width 0.15)
		(layer "F.Cu")
		(net 34)
	)
	(segment
		(start 102.097323 72.005136)
		(end 102.097323 70.277323)
		(width 0.15)
		(layer "F.Cu")
		(net 34)
	)
	(segment
		(start 137 106.4)
		(end 138.8 106.4)
		(width 0.15)
		(layer "F.Cu")
		(net 34)
	)
	(segment
		(start 132.75 100.75)
		(end 132.75 102.15)
		(width 0.15)
		(layer "F.Cu")
		(net 34)
	)
	(segment
		(start 130.8 93)
		(end 129.8 94)
		(width 0.15)
		(layer "F.Cu")
		(net 34)
	)
	(segment
		(start 129.8 99.65)
		(end 130.6 100.45)
		(width 0.15)
		(layer "F.Cu")
		(net 34)
	)
	(segment
		(start 132.75 102.15)
		(end 137 106.4)
		(width 0.15)
		(layer "F.Cu")
		(net 34)
	)
	(segment
		(start 133.19 92.59)
		(end 132.78 93)
		(width 0.15)
		(layer "F.Cu")
		(net 34)
	)
	(segment
		(start 130.6 100.45)
		(end 132.45 100.45)
		(width 0.15)
		(layer "F.Cu")
		(net 34)
	)
	(segment
		(start 133.54 92.59)
		(end 133.19 92.59)
		(width 0.15)
		(layer "F.Cu")
		(net 34)
	)
	(segment
		(start 132.45 100.45)
		(end 132.75 100.75)
		(width 0.15)
		(layer "F.Cu")
		(net 34)
	)
	(segment
		(start 129.8 94)
		(end 129.8 99.65)
		(width 0.15)
		(layer "F.Cu")
		(net 34)
	)
	(via
		(at 133.54 92.59)
		(size 0.45)
		(drill 0.1)
		(layers "F.Cu" "B.Cu")
		(net 34)
	)
	(via
		(at 129.43 72.52)
		(size 0.45)
		(drill 0.1)
		(layers "F.Cu" "B.Cu")
		(net 34)
	)
	(via
		(at 101.92 69.38)
		(size 0.45)
		(drill 0.1)
		(layers "F.Cu" "B.Cu")
		(net 34)
	)
	(segment
		(start 129.43 72.52)
		(end 129.43 73.58)
		(width 0.15)
		(layer "In3.Cu")
		(net 34)
	)
	(segment
		(start 133.59 92.59)
		(end 133.54 92.59)
		(width 0.15)
		(layer "In3.Cu")
		(net 34)
	)
	(segment
		(start 129.43 73.58)
		(end 134.92 79.07)
		(width 0.15)
		(layer "In3.Cu")
		(net 34)
	)
	(segment
		(start 134.92 91.26)
		(end 133.59 92.59)
		(width 0.15)
		(layer "In3.Cu")
		(net 34)
	)
	(segment
		(start 134.92 79.07)
		(end 134.92 91.26)
		(width 0.15)
		(layer "In3.Cu")
		(net 34)
	)
	(segment
		(start 104.895 69.515)
		(end 104.9425 69.4675)
		(width 0.125)
		(layer "B.Cu")
		(net 34)
	)
	(segment
		(start 104.58 69.83)
		(end 102.37 69.83)
		(width 0.15)
		(layer "B.Cu")
		(net 34)
	)
	(segment
		(start 104.58 69.83)
		(end 104.895 69.515)
		(width 0.13)
		(layer "B.Cu")
		(net 34)
	)
	(segment
		(start 102.37 69.83)
		(end 101.92 69.38)
		(width 0.15)
		(layer "B.Cu")
		(net 34)
	)
	(segment
		(start 127.9175 69.4675)
		(end 129.43 70.98)
		(width 0.125)
		(layer "B.Cu")
		(net 34)
	)
	(segment
		(start 104.9425 69.4675)
		(end 127.9175 69.4675)
		(width 0.125)
		(layer "B.Cu")
		(net 34)
	)
	(segment
		(start 129.43 70.98)
		(end 129.43 72.52)
		(width 0.125)
		(layer "B.Cu")
		(net 34)
	)
	(segment
		(start 71.775 106.992469)
		(end 70.686 106.992469)
		(width 0.125)
		(layer "F.Cu")
		(net 35)
	)
	(segment
		(start 71.85 107.067469)
		(end 71.775 106.992469)
		(width 0.125)
		(layer "F.Cu")
		(net 35)
	)
	(segment
		(start 70.686 106.992469)
		(end 70.475 107.203469)
		(width 0.125)
		(layer "F.Cu")
		(net 35)
	)
	(via
		(at 84.038649 106.588649)
		(size 0.45)
		(drill 0.1)
		(layers "F.Cu" "B.Cu")
		(net 35)
	)
	(via
		(at 70.475 107.203469)
		(size 0.45)
		(drill 0.1)
		(layers "F.Cu" "B.Cu")
		(net 35)
	)
	(segment
		(start 83.808839 106.588649)
		(end 84.038649 106.588649)
		(width 0.125)
		(layer "In5.Cu")
		(net 35)
	)
	(segment
		(start 70.475 107.203469)
		(end 70.636 107.042469)
		(width 0.125)
		(layer "In5.Cu")
		(net 35)
	)
	(segment
		(start 83.355019 107.042469)
		(end 83.808839 106.588649)
		(width 0.125)
		(layer "In5.Cu")
		(net 35)
	)
	(segment
		(start 70.636 107.042469)
		(end 83.355019 107.042469)
		(width 0.125)
		(layer "In5.Cu")
		(net 35)
	)
	(segment
		(start 84.735 105.665)
		(end 84.738388 105.661612)
		(width 0.125)
		(layer "B.Cu")
		(net 35)
	)
	(segment
		(start 84.381778 86.875)
		(end 83.005 88.251778)
		(width 0.125)
		(layer "B.Cu")
		(net 35)
	)
	(segment
		(start 84.738388 105.661612)
		(end 84.738388 105.588388)
		(width 0.125)
		(layer "B.Cu")
		(net 35)
	)
	(segment
		(start 84.735 105.665)
		(end 84.698388 105.628388)
		(width 0.125)
		(layer "B.Cu")
		(net 35)
	)
	(segment
		(start 83.005 90.465)
		(end 83.005 90.788222)
		(width 0.125)
		(layer "B.Cu")
		(net 35)
	)
	(segment
		(start 86.925 85.251778)
		(end 86.925 86.171778)
		(width 0.125)
		(layer "B.Cu")
		(net 35)
	)
	(segment
		(start 83.005 88.251778)
		(end 83.005 88.515)
		(width 0.125)
		(layer "B.Cu")
		(net 35)
	)
	(segment
		(start 83.005 90.788222)
		(end 85.345 93.128222)
		(width 0.125)
		(layer "B.Cu")
		(net 35)
	)
	(segment
		(start 84.698388 105.628388)
		(end 84.638388 105.688388)
		(width 0.125)
		(layer "B.Cu")
		(net 35)
	)
	(segment
		(start 85.345 104.981777)
		(end 84.738388 105.588388)
		(width 0.125)
		(layer "B.Cu")
		(net 35)
	)
	(segment
		(start 89.19 83.15)
		(end 89.026778 83.15)
		(width 0.125)
		(layer "B.Cu")
		(net 35)
	)
	(segment
		(start 82.364398 89.615)
		(end 83.395602 89.615)
		(width 0.125)
		(layer "B.Cu")
		(net 35)
	)
	(segment
		(start 86.925 86.171778)
		(end 86.221778 86.875)
		(width 0.125)
		(layer "B.Cu")
		(net 35)
	)
	(segment
		(start 85.107053 106.037053)
		(end 84.735 105.665)
		(width 0.125)
		(layer "B.Cu")
		(net 35)
	)
	(segment
		(start 85.345 93.128222)
		(end 85.345 104.981777)
		(width 0.125)
		(layer "B.Cu")
		(net 35)
	)
	(segment
		(start 89.026778 83.15)
		(end 86.925 85.251778)
		(width 0.125)
		(layer "B.Cu")
		(net 35)
	)
	(segment
		(start 84.038649 106.288128)
		(end 84.038649 106.588649)
		(width 0.125)
		(layer "B.Cu")
		(net 35)
	)
	(segment
		(start 84.638388 105.688388)
		(end 84.661776 105.665)
		(width 0.125)
		(layer "B.Cu")
		(net 35)
	)
	(segment
		(start 82.364398 90.015)
		(end 82.555 90.015)
		(width 0.125)
		(layer "B.Cu")
		(net 35)
	)
	(segment
		(start 84.661776 105.665)
		(end 84.735 105.665)
		(width 0.125)
		(layer "B.Cu")
		(net 35)
	)
	(segment
		(start 86.221778 86.875)
		(end 84.381778 86.875)
		(width 0.125)
		(layer "B.Cu")
		(net 35)
	)
	(segment
		(start 83.205 88.715)
		(end 83.395602 88.715)
		(width 0.125)
		(layer "B.Cu")
		(net 35)
	)
	(segment
		(start 84.638388 105.688388)
		(end 84.038649 106.288128)
		(width 0.125)
		(layer "B.Cu")
		(net 35)
	)
	(segment
		(start 84.738388 105.588388)
		(end 84.698388 105.628388)
		(width 0.125)
		(layer "B.Cu")
		(net 35)
	)
	(segment
		(start 89.54 83.5)
		(end 89.19 83.15)
		(width 0.125)
		(layer "B.Cu")
		(net 35)
	)
	(arc
		(start 83.005 88.515)
		(mid 83.063579 88.656421)
		(end 83.205 88.715)
		(width 0.125)
		(layer "B.Cu")
		(net 35)
	)
	(arc
		(start 82.555 90.015)
		(mid 82.873198 90.146802)
		(end 83.005 90.465)
		(width 0.125)
		(layer "B.Cu")
		(net 35)
	)
	(arc
		(start 82.164398 89.815)
		(mid 82.222977 89.956421)
		(end 82.364398 90.015)
		(width 0.125)
		(layer "B.Cu")
		(net 35)
	)
	(arc
		(start 82.364398 89.615)
		(mid 82.222977 89.673579)
		(end 82.164398 89.815)
		(width 0.125)
		(layer "B.Cu")
		(net 35)
	)
	(arc
		(start 83.395602 88.715)
		(mid 83.7138 88.846802)
		(end 83.845602 89.165)
		(width 0.125)
		(layer "B.Cu")
		(net 35)
	)
	(arc
		(start 83.845602 89.165)
		(mid 83.7138 89.483198)
		(end 83.395602 89.615)
		(width 0.125)
		(layer "B.Cu")
		(net 35)
	)
	(segment
		(start 70.686 106.742469)
		(end 70.475 106.531469)
		(width 0.125)
		(layer "F.Cu")
		(net 36)
	)
	(segment
		(start 71.775 106.742469)
		(end 70.686 106.742469)
		(width 0.125)
		(layer "F.Cu")
		(net 36)
	)
	(segment
		(start 71.85 106.667469)
		(end 71.775 106.742469)
		(width 0.125)
		(layer "F.Cu")
		(net 36)
	)
	(via
		(at 70.475 106.531469)
		(size 0.45)
		(drill 0.1)
		(layers "F.Cu" "B.Cu")
		(net 36)
	)
	(via
		(at 83.561351 106.111351)
		(size 0.45)
		(drill 0.1)
		(layers "F.Cu" "B.Cu")
		(net 36)
	)
	(segment
		(start 83.561351 106.341161)
		(end 83.561351 106.111351)
		(width 0.125)
		(layer "In5.Cu")
		(net 36)
	)
	(segment
		(start 70.475 106.531469)
		(end 70.636 106.692469)
		(width 0.125)
		(layer "In5.Cu")
		(net 36)
	)
	(segment
		(start 70.636 106.692469)
		(end 83.210043 106.692469)
		(width 0.125)
		(layer "In5.Cu")
		(net 36)
	)
	(segment
		(start 83.210043 106.692469)
		(end 83.561351 106.341161)
		(width 0.125)
		(layer "In5.Cu")
		(net 36)
	)
	(segment
		(start 86.118222 86.625)
		(end 84.278222 86.625)
		(width 0.125)
		(layer "B.Cu")
		(net 36)
	)
	(segment
		(start 85.095 104.878223)
		(end 83.861872 106.111351)
		(width 0.125)
		(layer "B.Cu")
		(net 36)
	)
	(segment
		(start 84.375 101.81)
		(end 85.04 101.81)
		(width 0.125)
		(layer "B.Cu")
		(net 36)
	)
	(segment
		(start 82.755 90.465)
		(end 82.755 90.891778)
		(width 0.125)
		(layer "B.Cu")
		(net 36)
	)
	(segment
		(start 83.861872 106.111351)
		(end 83.561351 106.111351)
		(width 0.125)
		(layer "B.Cu")
		(net 36)
	)
	(segment
		(start 83.205 88.965)
		(end 83.395602 88.965)
		(width 0.125)
		(layer "B.Cu")
		(net 36)
	)
	(segment
		(start 86.675 86.068222)
		(end 86.118222 86.625)
		(width 0.125)
		(layer "B.Cu")
		(net 36)
	)
	(segment
		(start 88.923222 82.9)
		(end 86.675 85.148222)
		(width 0.125)
		(layer "B.Cu")
		(net 36)
	)
	(segment
		(start 82.755 88.148222)
		(end 82.755 88.515)
		(width 0.125)
		(layer "B.Cu")
		(net 36)
	)
	(segment
		(start 85.095 101.865)
		(end 85.095 104.878223)
		(width 0.125)
		(layer "B.Cu")
		(net 36)
	)
	(segment
		(start 85.095 101.705)
		(end 85.095 101.865)
		(width 0.125)
		(layer "B.Cu")
		(net 36)
	)
	(segment
		(start 82.364398 90.265)
		(end 82.555 90.265)
		(width 0.125)
		(layer "B.Cu")
		(net 36)
	)
	(segment
		(start 85.095 101.705)
		(end 85.095 101.755)
		(width 0.125)
		(layer "B.Cu")
		(net 36)
	)
	(segment
		(start 89.19 82.9)
		(end 88.923222 82.9)
		(width 0.125)
		(layer "B.Cu")
		(net 36)
	)
	(segment
		(start 85.095 101.755)
		(end 85.04 101.81)
		(width 0.125)
		(layer "B.Cu")
		(net 36)
	)
	(segment
		(start 84.278222 86.625)
		(end 82.755 88.148222)
		(width 0.125)
		(layer "B.Cu")
		(net 36)
	)
	(segment
		(start 89.54 82.55)
		(end 89.19 82.9)
		(width 0.125)
		(layer "B.Cu")
		(net 36)
	)
	(segment
		(start 85.04 101.81)
		(end 85.095 101.865)
		(width 0.125)
		(layer "B.Cu")
		(net 36)
	)
	(segment
		(start 86.675 85.148222)
		(end 86.675 86.068222)
		(width 0.125)
		(layer "B.Cu")
		(net 36)
	)
	(segment
		(start 82.755 90.891778)
		(end 85.095 93.231778)
		(width 0.125)
		(layer "B.Cu")
		(net 36)
	)
	(segment
		(start 85.095 93.231778)
		(end 85.095 101.705)
		(width 0.125)
		(layer "B.Cu")
		(net 36)
	)
	(segment
		(start 82.364398 89.365)
		(end 83.395602 89.365)
		(width 0.125)
		(layer "B.Cu")
		(net 36)
	)
	(arc
		(start 82.755 88.515)
		(mid 82.886802 88.833198)
		(end 83.205 88.965)
		(width 0.125)
		(layer "B.Cu")
		(net 36)
	)
	(arc
		(start 82.555 90.265)
		(mid 82.696421 90.323579)
		(end 82.755 90.465)
		(width 0.125)
		(layer "B.Cu")
		(net 36)
	)
	(arc
		(start 82.364398 89.365)
		(mid 82.0462 89.496802)
		(end 81.914398 89.815)
		(width 0.125)
		(layer "B.Cu")
		(net 36)
	)
	(arc
		(start 81.914398 89.815)
		(mid 82.0462 90.133198)
		(end 82.364398 90.265)
		(width 0.125)
		(layer "B.Cu")
		(net 36)
	)
	(arc
		(start 83.595602 89.165)
		(mid 83.537023 89.306421)
		(end 83.395602 89.365)
		(width 0.125)
		(layer "B.Cu")
		(net 36)
	)
	(arc
		(start 83.395602 88.965)
		(mid 83.537023 89.023579)
		(end 83.595602 89.165)
		(width 0.125)
		(layer "B.Cu")
		(net 36)
	)
	(segment
		(start 148.85 103.42)
		(end 149.03 103.6)
		(width 0.15)
		(layer "F.Cu")
		(net 37)
	)
	(segment
		(start 100.22 108.77)
		(end 103.7 112.25)
		(width 0.15)
		(layer "F.Cu")
		(net 37)
	)
	(segment
		(start 108.1 121.5)
		(end 109.05 122.45)
		(width 0.15)
		(layer "F.Cu")
		(net 37)
	)
	(segment
		(start 112.15 122.45)
		(end 112.95 121.65)
		(width 0.15)
		(layer "F.Cu")
		(net 37)
	)
	(segment
		(start 100.347323 80.205136)
		(end 100.347323 84.102677)
		(width 0.15)
		(layer "F.Cu")
		(net 37)
	)
	(segment
		(start 98.75 85.7)
		(end 98.75 87.5)
		(width 0.15)
		(layer "F.Cu")
		(net 37)
	)
	(segment
		(start 128.86 120.6)
		(end 128.86 114.137956)
		(width 0.15)
		(layer "F.Cu")
		(net 37)
	)
	(segment
		(start 107.55 112.25)
		(end 108.1 112.8)
		(width 0.15)
		(layer "F.Cu")
		(net 37)
	)
	(segment
		(start 100.347323 84.102677)
		(end 98.75 85.7)
		(width 0.15)
		(layer "F.Cu")
		(net 37)
	)
	(segment
		(start 109.05 122.45)
		(end 112.15 122.45)
		(width 0.15)
		(layer "F.Cu")
		(net 37)
	)
	(segment
		(start 108.1 112.8)
		(end 108.1 121.5)
		(width 0.15)
		(layer "F.Cu")
		(net 37)
	)
	(segment
		(start 148.38 103.42)
		(end 148.85 103.42)
		(width 0.15)
		(layer "F.Cu")
		(net 37)
	)
	(segment
		(start 114.65 122.4)
		(end 127.06 122.4)
		(width 0.15)
		(layer "F.Cu")
		(net 37)
	)
	(segment
		(start 97.43 95.18)
		(end 100.22 97.97)
		(width 0.15)
		(layer "F.Cu")
		(net 37)
	)
	(segment
		(start 129.598458 113.399498)
		(end 130.199498 113.399498)
		(width 0.15)
		(layer "F.Cu")
		(net 37)
	)
	(segment
		(start 112.95 121.65)
		(end 113.9 121.65)
		(width 0.15)
		(layer "F.Cu")
		(net 37)
	)
	(segment
		(start 128.86 114.137956)
		(end 129.598458 113.399498)
		(width 0.15)
		(layer "F.Cu")
		(net 37)
	)
	(segment
		(start 98.75 87.5)
		(end 97.43 88.82)
		(width 0.15)
		(layer "F.Cu")
		(net 37)
	)
	(segment
		(start 103.7 112.25)
		(end 107.55 112.25)
		(width 0.15)
		(layer "F.Cu")
		(net 37)
	)
	(segment
		(start 113.9 121.65)
		(end 114.65 122.4)
		(width 0.15)
		(layer "F.Cu")
		(net 37)
	)
	(segment
		(start 100.22 97.97)
		(end 100.22 108.77)
		(width 0.15)
		(layer "F.Cu")
		(net 37)
	)
	(segment
		(start 127.06 122.4)
		(end 128.86 120.6)
		(width 0.15)
		(layer "F.Cu")
		(net 37)
	)
	(segment
		(start 97.43 88.82)
		(end 97.43 95.18)
		(width 0.15)
		(layer "F.Cu")
		(net 37)
	)
	(via
		(at 149.03 103.6)
		(size 0.45)
		(drill 0.1)
		(layers "F.Cu" "B.Cu")
		(net 37)
	)
	(via
		(at 130.199498 113.399498)
		(size 0.45)
		(drill 0.1)
		(layers "F.Cu" "B.Cu")
		(net 37)
	)
	(segment
		(start 135.78 110.12)
		(end 139.48 110.12)
		(width 0.15)
		(layer "In5.Cu")
		(net 37)
	)
	(segment
		(start 139.48 110.12)
		(end 146 103.6)
		(width 0.15)
		(layer "In5.Cu")
		(net 37)
	)
	(segment
		(start 130.199498 113.399498)
		(end 130.199498 112.700502)
		(width 0.15)
		(layer "In5.Cu")
		(net 37)
	)
	(segment
		(start 146 103.6)
		(end 149.03 103.6)
		(width 0.15)
		(layer "In5.Cu")
		(net 37)
	)
	(segment
		(start 133.5 112.4)
		(end 135.78 110.12)
		(width 0.15)
		(layer "In5.Cu")
		(net 37)
	)
	(segment
		(start 130.5 112.4)
		(end 133.5 112.4)
		(width 0.15)
		(layer "In5.Cu")
		(net 37)
	)
	(segment
		(start 130.199498 112.700502)
		(end 130.5 112.4)
		(width 0.15)
		(layer "In5.Cu")
		(net 37)
	)
	(segment
		(start 99.847323 84.202677)
		(end 98.4 85.65)
		(width 0.15)
		(layer "F.Cu")
		(net 38)
	)
	(segment
		(start 148.302 102.848)
		(end 148.898 102.848)
		(width 0.15)
		(layer "F.Cu")
		(net 38)
	)
	(segment
		(start 98.4 85.65)
		(end 98.4 87.4)
		(width 0.15)
		(layer "F.Cu")
		(net 38)
	)
	(segment
		(start 129.27 114.32829)
		(end 129.737146 113.861144)
		(width 0.15)
		(layer "F.Cu")
		(net 38)
	)
	(segment
		(start 113.1 121.95)
		(end 113.7 121.95)
		(width 0.15)
		(layer "F.Cu")
		(net 38)
	)
	(segment
		(start 112.3 122.75)
		(end 113.1 121.95)
		(width 0.15)
		(layer "F.Cu")
		(net 38)
	)
	(segment
		(start 114.45 122.7)
		(end 127.29 122.7)
		(width 0.15)
		(layer "F.Cu")
		(net 38)
	)
	(segment
		(start 148.898 102.848)
		(end 149.06 103.01)
		(width 0.15)
		(layer "F.Cu")
		(net 38)
	)
	(segment
		(start 97.12 95.27)
		(end 99.91 98.06)
		(width 0.15)
		(layer "F.Cu")
		(net 38)
	)
	(segment
		(start 107.35 112.6)
		(end 107.8 113.05)
		(width 0.15)
		(layer "F.Cu")
		(net 38)
	)
	(segment
		(start 108.85 122.75)
		(end 112.3 122.75)
		(width 0.15)
		(layer "F.Cu")
		(net 38)
	)
	(segment
		(start 99.91 108.96)
		(end 103.55 112.6)
		(width 0.15)
		(layer "F.Cu")
		(net 38)
	)
	(segment
		(start 107.8 121.7)
		(end 108.85 122.75)
		(width 0.15)
		(layer "F.Cu")
		(net 38)
	)
	(segment
		(start 97.12 88.68)
		(end 97.12 95.27)
		(width 0.15)
		(layer "F.Cu")
		(net 38)
	)
	(segment
		(start 127.29 122.7)
		(end 129.27 120.72)
		(width 0.15)
		(layer "F.Cu")
		(net 38)
	)
	(segment
		(start 103.55 112.6)
		(end 107.35 112.6)
		(width 0.15)
		(layer "F.Cu")
		(net 38)
	)
	(segment
		(start 129.27 120.72)
		(end 129.27 114.32829)
		(width 0.15)
		(layer "F.Cu")
		(net 38)
	)
	(segment
		(start 99.847323 80.205136)
		(end 99.847323 84.202677)
		(width 0.15)
		(layer "F.Cu")
		(net 38)
	)
	(segment
		(start 99.91 98.06)
		(end 99.91 108.96)
		(width 0.15)
		(layer "F.Cu")
		(net 38)
	)
	(segment
		(start 113.7 121.95)
		(end 114.45 122.7)
		(width 0.15)
		(layer "F.Cu")
		(net 38)
	)
	(segment
		(start 98.4 87.4)
		(end 97.12 88.68)
		(width 0.15)
		(layer "F.Cu")
		(net 38)
	)
	(segment
		(start 107.8 113.05)
		(end 107.8 121.7)
		(width 0.15)
		(layer "F.Cu")
		(net 38)
	)
	(via
		(at 129.737146 113.861144)
		(size 0.45)
		(drill 0.1)
		(layers "F.Cu" "B.Cu")
		(net 38)
	)
	(via
		(at 149.06 103.01)
		(size 0.45)
		(drill 0.1)
		(layers "F.Cu" "B.Cu")
		(net 38)
	)
	(segment
		(start 130.13 112.03)
		(end 133.27 112.03)
		(width 0.15)
		(layer "In5.Cu")
		(net 38)
	)
	(segment
		(start 135.66 109.64)
		(end 139.51 109.64)
		(width 0.15)
		(layer "In5.Cu")
		(net 38)
	)
	(segment
		(start 139.51 109.64)
		(end 146.14 103.01)
		(width 0.15)
		(layer "In5.Cu")
		(net 38)
	)
	(segment
		(start 129.737146 113.861144)
		(end 129.737146 112.422854)
		(width 0.15)
		(layer "In5.Cu")
		(net 38)
	)
	(segment
		(start 129.737146 112.422854)
		(end 130.13 112.03)
		(width 0.15)
		(layer "In5.Cu")
		(net 38)
	)
	(segment
		(start 146.14 103.01)
		(end 149.06 103.01)
		(width 0.15)
		(layer "In5.Cu")
		(net 38)
	)
	(segment
		(start 133.27 112.03)
		(end 135.66 109.64)
		(width 0.15)
		(layer "In5.Cu")
		(net 38)
	)
	(segment
		(start 99.63 109.13)
		(end 99.63 98.23)
		(width 0.15)
		(layer "F.Cu")
		(net 39)
	)
	(segment
		(start 148.74 103.95)
		(end 149 104.21)
		(width 0.15)
		(layer "F.Cu")
		(net 39)
	)
	(segment
		(start 107.15 112.95)
		(end 103.45 112.95)
		(width 0.15)
		(layer "F.Cu")
		(net 39)
	)
	(segment
		(start 129.74 120.81)
		(end 127.55 123)
		(width 0.15)
		(layer "F.Cu")
		(net 39)
	)
	(segment
		(start 108.7 123.05)
		(end 107.5 121.85)
		(width 0.15)
		(layer "F.Cu")
		(net 39)
	)
	(segment
		(start 96.82 95.42)
		(end 96.82 88.4675)
		(width 0.15)
		(layer "F.Cu")
		(net 39)
	)
	(segment
		(start 114 123.5)
		(end 112.8 123.5)
		(width 0.15)
		(layer "F.Cu")
		(net 39)
	)
	(segment
		(start 112.8 123.5)
		(end 112.35 123.05)
		(width 0.15)
		(layer "F.Cu")
		(net 39)
	)
	(segment
		(start 107.5 113.3)
		(end 107.15 112.95)
		(width 0.15)
		(layer "F.Cu")
		(net 39)
	)
	(segment
		(start 112.35 123.05)
		(end 108.7 123.05)
		(width 0.15)
		(layer "F.Cu")
		(net 39)
	)
	(segment
		(start 98.1 87.1875)
		(end 98.1 85.525)
		(width 0.15)
		(layer "F.Cu")
		(net 39)
	)
	(segment
		(start 98.1 85.525)
		(end 99.347323 84.277677)
		(width 0.15)
		(layer "F.Cu")
		(net 39)
	)
	(segment
		(start 99.63 98.23)
		(end 96.82 95.42)
		(width 0.15)
		(layer "F.Cu")
		(net 39)
	)
	(segment
		(start 114.5 123)
		(end 114 123.5)
		(width 0.15)
		(layer "F.Cu")
		(net 39)
	)
	(segment
		(start 129.74 114.459331)
		(end 129.74 120.81)
		(width 0.15)
		(layer "F.Cu")
		(net 39)
	)
	(segment
		(start 103.45 112.95)
		(end 99.63 109.13)
		(width 0.15)
		(layer "F.Cu")
		(net 39)
	)
	(segment
		(start 99.347323 84.277677)
		(end 99.347323 80.205136)
		(width 0.15)
		(layer "F.Cu")
		(net 39)
	)
	(segment
		(start 96.82 88.4675)
		(end 98.1 87.1875)
		(width 0.15)
		(layer "F.Cu")
		(net 39)
	)
	(segment
		(start 148.4 103.95)
		(end 148.74 103.95)
		(width 0.15)
		(layer "F.Cu")
		(net 39)
	)
	(segment
		(start 107.5 121.85)
		(end 107.5 113.3)
		(width 0.15)
		(layer "F.Cu")
		(net 39)
	)
	(segment
		(start 127.55 123)
		(end 114.5 123)
		(width 0.15)
		(layer "F.Cu")
		(net 39)
	)
	(segment
		(start 130.799749 113.399582)
		(end 129.74 114.459331)
		(width 0.15)
		(layer "F.Cu")
		(net 39)
	)
	(via
		(at 130.799749 113.399582)
		(size 0.45)
		(drill 0.1)
		(layers "F.Cu" "B.Cu")
		(net 39)
	)
	(via
		(at 149 104.21)
		(size 0.45)
		(drill 0.1)
		(layers "F.Cu" "B.Cu")
		(net 39)
	)
	(segment
		(start 130.799749 113.000251)
		(end 131.02 112.78)
		(width 0.15)
		(layer "In5.Cu")
		(net 39)
	)
	(segment
		(start 133.72 112.78)
		(end 135.82 110.68)
		(width 0.15)
		(layer "In5.Cu")
		(net 39)
	)
	(segment
		(start 135.82 110.68)
		(end 139.42 110.68)
		(width 0.15)
		(layer "In5.Cu")
		(net 39)
	)
	(segment
		(start 139.42 110.68)
		(end 145.89 104.21)
		(width 0.15)
		(layer "In5.Cu")
		(net 39)
	)
	(segment
		(start 145.89 104.21)
		(end 149 104.21)
		(width 0.15)
		(layer "In5.Cu")
		(net 39)
	)
	(segment
		(start 130.799749 113.399582)
		(end 130.799749 113.000251)
		(width 0.15)
		(layer "In5.Cu")
		(net 39)
	)
	(segment
		(start 131.02 112.78)
		(end 133.72 112.78)
		(width 0.15)
		(layer "In5.Cu")
		(net 39)
	)
	(segment
		(start 114 114.7)
		(end 113.988293 114.7)
		(width 0.155)
		(layer "F.Cu")
		(net 40)
	)
	(segment
		(start 99.097323 72.005136)
		(end 99.097323 73.317637)
		(width 0.155)
		(layer "F.Cu")
		(net 40)
	)
	(segment
		(start 114.05 117.15)
		(end 114.05 116.685)
		(width 0.13)
		(layer "F.Cu")
		(net 40)
	)
	(segment
		(start 113.099 110.996638)
		(end 113.2465 110.849138)
		(width 0.155)
		(layer "F.Cu")
		(net 40)
	)
	(segment
		(start 113.95 117.25)
		(end 114.05 117.15)
		(width 0.13)
		(layer "F.Cu")
		(net 40)
	)
	(segment
		(start 98.996823 73.418137)
		(end 98.996823 76.110397)
		(width 0.155)
		(layer "F.Cu")
		(net 40)
	)
	(segment
		(start 99.694 78.6)
		(end 99.5495 78.4555)
		(width 0.155)
		(layer "F.Cu")
		(net 40)
	)
	(segment
		(start 98.996823 76.110397)
		(end 99.5495 76.663074)
		(width 0.155)
		(layer "F.Cu")
		(net 40)
	)
	(segment
		(start 114.05 115.793749)
		(end 114.05 116.563749)
		(width 0.13)
		(layer "F.Cu")
		(net 40)
	)
	(segment
		(start 114.05 114.75)
		(end 114 114.7)
		(width 0.155)
		(layer "F.Cu")
		(net 40)
	)
	(segment
		(start 99.5495 78.4555)
		(end 99.5495 76.663074)
		(width 0.155)
		(layer "F.Cu")
		(net 40)
	)
	(segment
		(start 113.65 117.55)
		(end 113.95 117.25)
		(width 0.13)
		(layer "F.Cu")
		(net 40)
	)
	(segment
		(start 113.95 117.25)
		(end 113.9 117.3)
		(width 0.13)
		(layer "F.Cu")
		(net 40)
	)
	(segment
		(start 99.097323 73.317637)
		(end 98.996823 73.418137)
		(width 0.155)
		(layer "F.Cu")
		(net 40)
	)
	(segment
		(start 113.099 110.996638)
		(end 113.099 112.837574)
		(width 0.155)
		(layer "F.Cu")
		(net 40)
	)
	(segment
		(start 113.9 117.3)
		(end 113.8 117.3)
		(width 0.13)
		(layer "F.Cu")
		(net 40)
	)
	(segment
		(start 113.099 112.837574)
		(end 113.689155 113.427729)
		(width 0.155)
		(layer "F.Cu")
		(net 40)
	)
	(segment
		(start 114.05 115.793749)
		(end 114.05 114.75)
		(width 0.155)
		(layer "F.Cu")
		(net 40)
	)
	(segment
		(start 113.689155 113.427729)
		(end 113.689155 114.400862)
		(width 0.155)
		(layer "F.Cu")
		(net 40)
	)
	(segment
		(start 113.988293 114.7)
		(end 113.689155 114.400862)
		(width 0.155)
		(layer "F.Cu")
		(net 40)
	)
	(segment
		(start 113.65 118.2)
		(end 113.65 117.55)
		(width 0.13)
		(layer "F.Cu")
		(net 40)
	)
	(via
		(at 113.2465 110.849138)
		(size 0.45)
		(drill 0.1)
		(layers "F.Cu" "B.Cu")
		(net 40)
	)
	(via
		(at 101.094 97.2)
		(size 0.45)
		(drill 0.1)
		(layers "F.Cu" "B.Cu")
		(net 40)
	)
	(via
		(at 99.694 78.6)
		(size 0.45)
		(drill 0.1)
		(layers "F.Cu" "B.Cu")
		(net 40)
	)
	(via
		(at 113.8 117.3)
		(size 0.45)
		(drill 0.1)
		(layers "F.Cu" "B.Cu")
		(net 40)
	)
	(segment
		(start 104.281718 102.451)
		(end 106.099 104.268282)
		(width 0.16)
		(layer "In3.Cu")
		(net 40)
	)
	(segment
		(start 106.099 104.268282)
		(end 106.099 106.088282)
		(width 0.16)
		(layer "In3.Cu")
		(net 40)
	)
	(segment
		(start 113 118.7)
		(end 113 119.45)
		(width 0.13)
		(layer "In3.Cu")
		(net 40)
	)
	(segment
		(start 113.0985 110.701138)
		(end 113.2465 110.849138)
		(width 0.16)
		(layer "In3.Cu")
		(net 40)
	)
	(segment
		(start 113.0985 110.187782)
		(end 113.0985 110.701138)
		(width 0.16)
		(layer "In3.Cu")
		(net 40)
	)
	(segment
		(start 100.949 97.345)
		(end 100.949 99.658282)
		(width 0.16)
		(layer "In3.Cu")
		(net 40)
	)
	(segment
		(start 106.811718 106.801)
		(end 108.892371 106.801)
		(width 0.16)
		(layer "In3.Cu")
		(net 40)
	)
	(segment
		(start 113.8 117.3)
		(end 113.8 117.9)
		(width 0.13)
		(layer "In3.Cu")
		(net 40)
	)
	(segment
		(start 106.099 106.088282)
		(end 106.811718 106.801)
		(width 0.16)
		(layer "In3.Cu")
		(net 40)
	)
	(segment
		(start 111.508997 108.598279)
		(end 113.0985 110.187782)
		(width 0.16)
		(layer "In3.Cu")
		(net 40)
	)
	(segment
		(start 100.949 99.658282)
		(end 103.741718 102.451)
		(width 0.16)
		(layer "In3.Cu")
		(net 40)
	)
	(segment
		(start 103.741718 102.451)
		(end 104.281718 102.451)
		(width 0.16)
		(layer "In3.Cu")
		(net 40)
	)
	(segment
		(start 113.8 117.9)
		(end 113 118.7)
		(width 0.13)
		(layer "In3.Cu")
		(net 40)
	)
	(segment
		(start 101.094 97.2)
		(end 100.949 97.345)
		(width 0.16)
		(layer "In3.Cu")
		(net 40)
	)
	(segment
		(start 108.892371 106.801)
		(end 110.68965 108.598279)
		(width 0.16)
		(layer "In3.Cu")
		(net 40)
	)
	(segment
		(start 110.68965 108.598279)
		(end 111.508997 108.598279)
		(width 0.16)
		(layer "In3.Cu")
		(net 40)
	)
	(segment
		(start 102.749 87.861718)
		(end 102.749 85.513282)
		(width 0.16)
		(layer "In5.Cu")
		(net 40)
	)
	(segment
		(start 102.749 85.513282)
		(end 101.974 84.738282)
		(width 0.16)
		(layer "In5.Cu")
		(net 40)
	)
	(segment
		(start 99.549 79.013282)
		(end 99.549 78.745)
		(width 0.16)
		(layer "In5.Cu")
		(net 40)
	)
	(segment
		(start 100.649 89.961718)
		(end 102.749 87.861718)
		(width 0.16)
		(layer "In5.Cu")
		(net 40)
	)
	(segment
		(start 101.974 80.838282)
		(end 100.361718 79.226)
		(width 0.16)
		(layer "In5.Cu")
		(net 40)
	)
	(segment
		(start 100.949 97.055)
		(end 100.949 95.238282)
		(width 0.16)
		(layer "In5.Cu")
		(net 40)
	)
	(segment
		(start 99.761718 79.226)
		(end 99.549 79.013282)
		(width 0.16)
		(layer "In5.Cu")
		(net 40)
	)
	(segment
		(start 100.649 94.938282)
		(end 100.649 89.961718)
		(width 0.16)
		(layer "In5.Cu")
		(net 40)
	)
	(segment
		(start 101.094 97.2)
		(end 100.949 97.055)
		(width 0.16)
		(layer "In5.Cu")
		(net 40)
	)
	(segment
		(start 100.949 95.238282)
		(end 100.649 94.938282)
		(width 0.16)
		(layer "In5.Cu")
		(net 40)
	)
	(segment
		(start 99.549 78.745)
		(end 99.694 78.6)
		(width 0.16)
		(layer "In5.Cu")
		(net 40)
	)
	(segment
		(start 101.974 84.738282)
		(end 101.974 80.838282)
		(width 0.16)
		(layer "In5.Cu")
		(net 40)
	)
	(segment
		(start 100.361718 79.226)
		(end 99.761718 79.226)
		(width 0.16)
		(layer "In5.Cu")
		(net 40)
	)
	(segment
		(start 148.9 106.25)
		(end 148.74 106.41)
		(width 0.125)
		(layer "F.Cu")
		(net 41)
	)
	(segment
		(start 99.35 98.35)
		(end 99.35 109.3)
		(width 0.15)
		(layer "F.Cu")
		(net 41)
	)
	(segment
		(start 127.82 123.3)
		(end 130.19 120.93)
		(width 0.15)
		(layer "F.Cu")
		(net 41)
	)
	(segment
		(start 114.2 123.8)
		(end 114.7 123.3)
		(width 0.15)
		(layer "F.Cu")
		(net 41)
	)
	(segment
		(start 108.588902 123.35)
		(end 112.125 123.35)
		(width 0.15)
		(layer "F.Cu")
		(net 41)
	)
	(segment
		(start 106.95 113.3)
		(end 107.2 113.55)
		(width 0.15)
		(layer "F.Cu")
		(net 41)
	)
	(segment
		(start 108.533902 123.295)
		(end 108.588902 123.35)
		(width 0.15)
		(layer "F.Cu")
		(net 41)
	)
	(segment
		(start 112.125 123.35)
		(end 112.575 123.8)
		(width 0.15)
		(layer "F.Cu")
		(net 41)
	)
	(segment
		(start 130.19 114.609666)
		(end 131.399833 113.399833)
		(width 0.15)
		(layer "F.Cu")
		(net 41)
	)
	(segment
		(start 96.5 95.5)
		(end 99.35 98.35)
		(width 0.15)
		(layer "F.Cu")
		(net 41)
	)
	(segment
		(start 96.5 88.3)
		(end 96.5 95.5)
		(width 0.15)
		(layer "F.Cu")
		(net 41)
	)
	(segment
		(start 98.847323 84.352677)
		(end 97.825 85.375)
		(width 0.15)
		(layer "F.Cu")
		(net 41)
	)
	(segment
		(start 130.19 120.93)
		(end 130.19 114.609666)
		(width 0.15)
		(layer "F.Cu")
		(net 41)
	)
	(segment
		(start 97.825 85.375)
		(end 97.825 86.975)
		(width 0.15)
		(layer "F.Cu")
		(net 41)
	)
	(segment
		(start 99.35 109.3)
		(end 103.35 113.3)
		(width 0.15)
		(layer "F.Cu")
		(net 41)
	)
	(segment
		(start 112.575 123.8)
		(end 114.2 123.8)
		(width 0.15)
		(layer "F.Cu")
		(net 41)
	)
	(segment
		(start 107.2 121.99)
		(end 108.505 123.295)
		(width 0.15)
		(layer "F.Cu")
		(net 41)
	)
	(segment
		(start 103.35 113.3)
		(end 106.95 113.3)
		(width 0.15)
		(layer "F.Cu")
		(net 41)
	)
	(segment
		(start 148.74 106.41)
		(end 148.302 106.41)
		(width 0.125)
		(layer "F.Cu")
		(net 41)
	)
	(segment
		(start 107.2 113.55)
		(end 107.2 121.99)
		(width 0.15)
		(layer "F.Cu")
		(net 41)
	)
	(segment
		(start 98.847323 80.205136)
		(end 98.847323 84.352677)
		(width 0.15)
		(layer "F.Cu")
		(net 41)
	)
	(segment
		(start 114.7 123.3)
		(end 127.82 123.3)
		(width 0.15)
		(layer "F.Cu")
		(net 41)
	)
	(segment
		(start 108.505 123.295)
		(end 108.533902 123.295)
		(width 0.15)
		(layer "F.Cu")
		(net 41)
	)
	(segment
		(start 97.825 86.975)
		(end 96.5 88.3)
		(width 0.15)
		(layer "F.Cu")
		(net 41)
	)
	(via
		(at 148.9 106.25)
		(size 0.45)
		(drill 0.1)
		(layers "F.Cu" "B.Cu")
		(net 41)
	)
	(via
		(at 131.399833 113.399833)
		(size 0.45)
		(drill 0.1)
		(layers "F.Cu" "B.Cu")
		(net 41)
	)
	(segment
		(start 148.75 106.4)
		(end 144.2 106.4)
		(width 0.15)
		(layer "In5.Cu")
		(net 41)
	)
	(segment
		(start 144.2 106.4)
		(end 139.34 111.26)
		(width 0.15)
		(layer "In5.Cu")
		(net 41)
	)
	(segment
		(start 148.9 106.25)
		(end 148.75 106.4)
		(width 0.15)
		(layer "In5.Cu")
		(net 41)
	)
	(segment
		(start 135.84 111.26)
		(end 133.85 113.25)
		(width 0.15)
		(layer "In5.Cu")
		(net 41)
	)
	(segment
		(start 139.34 111.26)
		(end 135.84 111.26)
		(width 0.15)
		(layer "In5.Cu")
		(net 41)
	)
	(segment
		(start 133.85 113.25)
		(end 131.549666 113.25)
		(width 0.15)
		(layer "In5.Cu")
		(net 41)
	)
	(segment
		(start 131.549666 113.25)
		(end 131.399833 113.399833)
		(width 0.15)
		(layer "In5.Cu")
		(net 41)
	)
	(segment
		(start 97.55 85.15)
		(end 98.347323 84.352677)
		(width 0.15)
		(layer "F.Cu")
		(net 42)
	)
	(segment
		(start 99.07 98.52)
		(end 96.22 95.67)
		(width 0.15)
		(layer "F.Cu")
		(net 42)
	)
	(segment
		(start 130.69 115.01)
		(end 130.69 121.02)
		(width 0.15)
		(layer "F.Cu")
		(net 42)
	)
	(segment
		(start 130.69 121.02)
		(end 128.11 123.6)
		(width 0.15)
		(layer "F.Cu")
		(net 42)
	)
	(segment
		(start 114.95 123.6)
		(end 114.45 124.1)
		(width 0.15)
		(layer "F.Cu")
		(net 42)
	)
	(segment
		(start 96.22 95.67)
		(end 96.22 88.13)
		(width 0.15)
		(layer "F.Cu")
		(net 42)
	)
	(segment
		(start 103.25 113.65)
		(end 99.07 109.47)
		(width 0.15)
		(layer "F.Cu")
		(net 42)
	)
	(segment
		(start 108.419994 123.57)
		(end 108.34 123.57)
		(width 0.15)
		(layer "F.Cu")
		(net 42)
	)
	(segment
		(start 111.95 123.65)
		(end 108.499994 123.65)
		(width 0.15)
		(layer "F.Cu")
		(net 42)
	)
	(segment
		(start 97.55 86.8)
		(end 97.55 85.15)
		(width 0.15)
		(layer "F.Cu")
		(net 42)
	)
	(segment
		(start 99.07 109.47)
		(end 99.07 98.52)
		(width 0.15)
		(layer "F.Cu")
		(net 42)
	)
	(segment
		(start 108.34 123.57)
		(end 106.9 122.13)
		(width 0.15)
		(layer "F.Cu")
		(net 42)
	)
	(segment
		(start 112.4 124.1)
		(end 111.95 123.65)
		(width 0.15)
		(layer "F.Cu")
		(net 42)
	)
	(segment
		(start 132 113.7)
		(end 130.69 115.01)
		(width 0.15)
		(layer "F.Cu")
		(net 42)
	)
	(segment
		(start 108.499994 123.65)
		(end 108.419994 123.57)
		(width 0.15)
		(layer "F.Cu")
		(net 42)
	)
	(segment
		(start 148.342 106.9)
		(end 148.9 106.9)
		(width 0.125)
		(layer "F.Cu")
		(net 42)
	)
	(segment
		(start 106.9 122.13)
		(end 106.9 113.8)
		(width 0.15)
		(layer "F.Cu")
		(net 42)
	)
	(segment
		(start 148.302 106.94)
		(end 148.342 106.9)
		(width 0.125)
		(layer "F.Cu")
		(net 42)
	)
	(segment
		(start 106.75 113.65)
		(end 103.25 113.65)
		(width 0.15)
		(layer "F.Cu")
		(net 42)
	)
	(segment
		(start 114.45 124.1)
		(end 112.4 124.1)
		(width 0.15)
		(layer "F.Cu")
		(net 42)
	)
	(segment
		(start 98.347323 84.352677)
		(end 98.347323 80.205136)
		(width 0.15)
		(layer "F.Cu")
		(net 42)
	)
	(segment
		(start 96.22 88.13)
		(end 97.55 86.8)
		(width 0.15)
		(layer "F.Cu")
		(net 42)
	)
	(segment
		(start 128.11 123.6)
		(end 114.95 123.6)
		(width 0.15)
		(layer "F.Cu")
		(net 42)
	)
	(segment
		(start 106.9 113.8)
		(end 106.75 113.65)
		(width 0.15)
		(layer "F.Cu")
		(net 42)
	)
	(via
		(at 148.9 106.9)
		(size 0.45)
		(drill 0.1)
		(layers "F.Cu" "B.Cu")
		(net 42)
	)
	(via
		(at 132 113.7)
		(size 0.45)
		(drill 0.1)
		(layers "F.Cu" "B.Cu")
		(net 42)
	)
	(segment
		(start 135.93 111.77)
		(end 134 113.7)
		(width 0.15)
		(layer "In5.Cu")
		(net 42)
	)
	(segment
		(start 144.35 106.75)
		(end 139.33 111.77)
		(width 0.15)
		(layer "In5.Cu")
		(net 42)
	)
	(segment
		(start 148.75 106.75)
		(end 144.35 106.75)
		(width 0.15)
		(layer "In5.Cu")
		(net 42)
	)
	(segment
		(start 148.9 106.9)
		(end 148.75 106.75)
		(width 0.15)
		(layer "In5.Cu")
		(net 42)
	)
	(segment
		(start 134 113.7)
		(end 132 113.7)
		(width 0.15)
		(layer "In5.Cu")
		(net 42)
	)
	(segment
		(start 139.33 111.77)
		(end 135.93 111.77)
		(width 0.15)
		(layer "In5.Cu")
		(net 42)
	)
	(segment
		(start 136 95.3)
		(end 136.23 95.07)
		(width 0.125)
		(layer "F.Cu")
		(net 43)
	)
	(segment
		(start 96.75 80.302459)
		(end 96.75 82.35)
		(width 0.125)
		(layer "F.Cu")
		(net 43)
	)
	(segment
		(start 96.847323 80.205136)
		(end 96.75 80.302459)
		(width 0.125)
		(layer "F.Cu")
		(net 43)
	)
	(segment
		(start 96.3875 82.7125)
		(end 96.3875 86.681)
		(width 0.125)
		(layer "F.Cu")
		(net 43)
	)
	(segment
		(start 136.23 95.07)
		(end 136.95 95.07)
		(width 0.125)
		(layer "F.Cu")
		(net 43)
	)
	(segment
		(start 96.3875 86.681)
		(end 95.25 87.8185)
		(width 0.125)
		(layer "F.Cu")
		(net 43)
	)
	(segment
		(start 96.75 82.35)
		(end 96.3875 82.7125)
		(width 0.125)
		(layer "F.Cu")
		(net 43)
	)
	(via
		(at 95.25 87.8185)
		(size 0.45)
		(drill 0.1)
		(layers "F.Cu" "B.Cu")
		(net 43)
	)
	(via
		(at 136 95.3)
		(size 0.45)
		(drill 0.1)
		(layers "F.Cu" "B.Cu")
		(net 43)
	)
	(via
		(at 134.2255 101)
		(size 0.45)
		(drill 0.1)
		(layers "F.Cu" "B.Cu")
		(net 43)
	)
	(segment
		(start 124.15 107.9)
		(end 127 105.05)
		(width 0.125)
		(layer "In5.Cu")
		(net 43)
	)
	(segment
		(start 95.25 87.8185)
		(end 95.25 88.252561)
		(width 0.125)
		(layer "In5.Cu")
		(net 43)
	)
	(segment
		(start 94.65 100.2)
		(end 95 100.55)
		(width 0.125)
		(layer "In5.Cu")
		(net 43)
	)
	(segment
		(start 97.25 100.55)
		(end 99.6 102.9)
		(width 0.125)
		(layer "In5.Cu")
		(net 43)
	)
	(segment
		(start 134.85 103.18)
		(end 134.85 101.35)
		(width 0.125)
		(layer "In5.Cu")
		(net 43)
	)
	(segment
		(start 94.65 97.8)
		(end 94.65 100.2)
		(width 0.125)
		(layer "In5.Cu")
		(net 43)
	)
	(segment
		(start 134.5 101)
		(end 134.2255 101)
		(width 0.125)
		(layer "In5.Cu")
		(net 43)
	)
	(segment
		(start 95.25 88.252561)
		(end 95.15 88.352561)
		(width 0.125)
		(layer "In5.Cu")
		(net 43)
	)
	(segment
		(start 99.6 106.6)
		(end 100.15 107.15)
		(width 0.125)
		(layer "In5.Cu")
		(net 43)
	)
	(segment
		(start 100.15 107.15)
		(end 116.4 107.15)
		(width 0.125)
		(layer "In5.Cu")
		(net 43)
	)
	(segment
		(start 116.4 107.15)
		(end 117.15 107.9)
		(width 0.125)
		(layer "In5.Cu")
		(net 43)
	)
	(segment
		(start 127 105.05)
		(end 132.98 105.05)
		(width 0.125)
		(layer "In5.Cu")
		(net 43)
	)
	(segment
		(start 134.85 101.35)
		(end 134.5 101)
		(width 0.125)
		(layer "In5.Cu")
		(net 43)
	)
	(segment
		(start 95.15 97.3)
		(end 94.65 97.8)
		(width 0.125)
		(layer "In5.Cu")
		(net 43)
	)
	(segment
		(start 117.15 107.9)
		(end 124.15 107.9)
		(width 0.125)
		(layer "In5.Cu")
		(net 43)
	)
	(segment
		(start 95 100.55)
		(end 97.25 100.55)
		(width 0.125)
		(layer "In5.Cu")
		(net 43)
	)
	(segment
		(start 132.98 105.05)
		(end 134.85 103.18)
		(width 0.125)
		(layer "In5.Cu")
		(net 43)
	)
	(segment
		(start 99.6 102.9)
		(end 99.6 106.6)
		(width 0.125)
		(layer "In5.Cu")
		(net 43)
	)
	(segment
		(start 95.15 88.352561)
		(end 95.15 97.3)
		(width 0.125)
		(layer "In5.Cu")
		(net 43)
	)
	(segment
		(start 134.2255 98.2245)
		(end 135.05 97.4)
		(width 0.15)
		(layer "B.Cu")
		(net 43)
	)
	(segment
		(start 134.2255 101)
		(end 134.2255 98.2245)
		(width 0.15)
		(layer "B.Cu")
		(net 43)
	)
	(segment
		(start 135.05 97.4)
		(end 136.55 97.4)
		(width 0.15)
		(layer "B.Cu")
		(net 43)
	)
	(segment
		(start 136.7 97.25)
		(end 136.7 96)
		(width 0.15)
		(layer "B.Cu")
		(net 43)
	)
	(segment
		(start 136.7 96)
		(end 136 95.3)
		(width 0.15)
		(layer "B.Cu")
		(net 43)
	)
	(segment
		(start 136.55 97.4)
		(end 136.7 97.25)
		(width 0.15)
		(layer "B.Cu")
		(net 43)
	)
	(segment
		(start 106.6 114)
		(end 106.6 122.3)
		(width 0.125)
		(layer "F.Cu")
		(net 44)
	)
	(segment
		(start 132.57 119.7)
		(end 132.57 120.6775)
		(width 0.2)
		(layer "F.Cu")
		(net 44)
	)
	(segment
		(start 114.6 124.4)
		(end 115.1 123.9)
		(width 0.125)
		(layer "F.Cu")
		(net 44)
	)
	(segment
		(start 94.597323 77.202677)
		(end 94.597323 72.005136)
		(width 0.15)
		(layer "F.Cu")
		(net 44)
	)
	(segment
		(start 89.53 78.52)
		(end 93.28 78.52)
		(width 0.15)
		(layer "F.Cu")
		(net 44)
	)
	(segment
		(start 88.55 81.2215)
		(end 88.55 79.5)
		(width 0.15)
		(layer "F.Cu")
		(net 44)
	)
	(segment
		(start 128.25 123.9)
		(end 130.35 121.8)
		(width 0.125)
		(layer "F.Cu")
		(net 44)
	)
	(segment
		(start 132.6 120.7)
		(end 132.6 120.69)
		(width 0.125)
		(layer "F.Cu")
		(net 44)
	)
	(segment
		(start 88.7 81.3715)
		(end 88.55 81.2215)
		(width 0.15)
		(layer "F.Cu")
		(net 44)
	)
	(segment
		(start 99.8 110.85)
		(end 100 110.85)
		(width 0.125)
		(layer "F.Cu")
		(net 44)
	)
	(segment
		(start 106.6 122.3)
		(end 108.1325 123.8325)
		(width 0.125)
		(layer "F.Cu")
		(net 44)
	)
	(segment
		(start 130.35 121.8)
		(end 131.5 121.8)
		(width 0.125)
		(layer "F.Cu")
		(net 44)
	)
	(segment
		(start 115.1 123.9)
		(end 128.25 123.9)
		(width 0.125)
		(layer "F.Cu")
		(net 44)
	)
	(segment
		(start 103.1 113.95)
		(end 106.55 113.95)
		(width 0.125)
		(layer "F.Cu")
		(net 44)
	)
	(segment
		(start 100 110.85)
		(end 103.1 113.95)
		(width 0.125)
		(layer "F.Cu")
		(net 44)
	)
	(segment
		(start 108.428762 123.95)
		(end 111.8 123.95)
		(width 0.125)
		(layer "F.Cu")
		(net 44)
	)
	(segment
		(start 93.28 78.52)
		(end 94.597323 77.202677)
		(width 0.15)
		(layer "F.Cu")
		(net 44)
	)
	(segment
		(start 131.5 121.8)
		(end 132.6 120.7)
		(width 0.125)
		(layer "F.Cu")
		(net 44)
	)
	(segment
		(start 112.25 124.4)
		(end 114.6 124.4)
		(width 0.125)
		(layer "F.Cu")
		(net 44)
	)
	(segment
		(start 88.55 79.5)
		(end 89.53 78.52)
		(width 0.15)
		(layer "F.Cu")
		(net 44)
	)
	(segment
		(start 106.55 113.95)
		(end 106.6 114)
		(width 0.125)
		(layer "F.Cu")
		(net 44)
	)
	(segment
		(start 108.1325 123.8325)
		(end 108.311262 123.8325)
		(width 0.125)
		(layer "F.Cu")
		(net 44)
	)
	(segment
		(start 108.311262 123.8325)
		(end 108.428762 123.95)
		(width 0.125)
		(layer "F.Cu")
		(net 44)
	)
	(segment
		(start 111.8 123.95)
		(end 112.25 124.4)
		(width 0.125)
		(layer "F.Cu")
		(net 44)
	)
	(via
		(at 88.7 81.3715)
		(size 0.45)
		(drill 0.1)
		(layers "F.Cu" "B.Cu")
		(net 44)
	)
	(via
		(at 99.8 110.85)
		(size 0.45)
		(drill 0.1)
		(layers "F.Cu" "B.Cu")
		(net 44)
	)
	(via
		(at 83.475499 109.2515)
		(size 0.45)
		(drill 0.1)
		(layers "F.Cu" "B.Cu")
		(net 44)
	)
	(segment
		(start 83.475499 110.075499)
		(end 83.475499 109.2515)
		(width 0.125)
		(layer "In3.Cu")
		(net 44)
	)
	(segment
		(start 99.15 111.5)
		(end 84.9 111.5)
		(width 0.125)
		(layer "In3.Cu")
		(net 44)
	)
	(segment
		(start 99.8 110.85)
		(end 99.15 111.5)
		(width 0.125)
		(layer "In3.Cu")
		(net 44)
	)
	(segment
		(start 84.9 111.5)
		(end 83.475499 110.075499)
		(width 0.125)
		(layer "In3.Cu")
		(net 44)
	)
	(segment
		(start 83.475499 109.245499)
		(end 82.7 108.47)
		(width 0.125)
		(layer "B.Cu")
		(net 44)
	)
	(segment
		(start 81.4 87.12)
		(end 81.4 86.38)
		(width 0.125)
		(layer "B.Cu")
		(net 44)
	)
	(segment
		(start 81.62 87.87)
		(end 81.62 87.34)
		(width 0.125)
		(layer "B.Cu")
		(net 44)
	)
	(segment
		(start 81.22 92.075)
		(end 81.22 88.27)
		(width 0.125)
		(layer "B.Cu")
		(net 44)
	)
	(segment
		(start 82.865 93.72)
		(end 81.22 92.075)
		(width 0.125)
		(layer "B.Cu")
		(net 44)
	)
	(segment
		(start 82.485 96.9)
		(end 82.865 96.52)
		(width 0.125)
		(layer "B.Cu")
		(net 44)
	)
	(segment
		(start 82.7 102.65)
		(end 82.485 102.435)
		(width 0.125)
		(layer "B.Cu")
		(net 44)
	)
	(segment
		(start 81.8 85.98)
		(end 84.0915 85.98)
		(width 0.125)
		(layer "B.Cu")
		(net 44)
	)
	(segment
		(start 83.475499 109.2515)
		(end 83.475499 109.245499)
		(width 0.125)
		(layer "B.Cu")
		(net 44)
	)
	(segment
		(start 82.865 96.52)
		(end 82.865 93.72)
		(width 0.125)
		(layer "B.Cu")
		(net 44)
	)
	(segment
		(start 84.0915 85.98)
		(end 88.7 81.3715)
		(width 0.125)
		(layer "B.Cu")
		(net 44)
	)
	(segment
		(start 81.22 88.27)
		(end 81.62 87.87)
		(width 0.125)
		(layer "B.Cu")
		(net 44)
	)
	(segment
		(start 82.485 102.435)
		(end 82.485 96.9)
		(width 0.125)
		(layer "B.Cu")
		(net 44)
	)
	(segment
		(start 82.7 108.47)
		(end 82.7 102.65)
		(width 0.125)
		(layer "B.Cu")
		(net 44)
	)
	(segment
		(start 81.62 87.34)
		(end 81.4 87.12)
		(width 0.125)
		(layer "B.Cu")
		(net 44)
	)
	(segment
		(start 81.4 86.38)
		(end 81.8 85.98)
		(width 0.125)
		(layer "B.Cu")
		(net 44)
	)
	(segment
		(start 96.0755 112.9755)
		(end 95.275 112.175)
		(width 0.125)
		(layer "F.Cu")
		(net 45)
	)
	(segment
		(start 100.05 113.35)
		(end 100.05 114.165)
		(width 0.15)
		(layer "F.Cu")
		(net 45)
	)
	(segment
		(start 95.275 103.575)
		(end 94.0875 102.3875)
		(width 0.125)
		(layer "F.Cu")
		(net 45)
	)
	(segment
		(start 121.3 126.2)
		(end 124.5 126.2)
		(width 0.155)
		(layer "F.Cu")
		(net 45)
	)
	(segment
		(start 95.275 112.175)
		(end 95.275 103.575)
		(width 0.125)
		(layer "F.Cu")
		(net 45)
	)
	(segment
		(start 124.5 126.2)
		(end 124.95 126.65)
		(width 0.155)
		(layer "F.Cu")
		(net 45)
	)
	(segment
		(start 94.9 97.5)
		(end 94.9 90.09)
		(width 0.125)
		(layer "F.Cu")
		(net 45)
	)
	(segment
		(start 96.1 112.9755)
		(end 99.6755 112.9755)
		(width 0.125)
		(layer "F.Cu")
		(net 45)
	)
	(segment
		(start 94.0875 102.3875)
		(end 94.0875 98.3125)
		(width 0.125)
		(layer "F.Cu")
		(net 45)
	)
	(segment
		(start 120.85 126.65)
		(end 121.3 126.2)
		(width 0.155)
		(layer "F.Cu")
		(net 45)
	)
	(segment
		(start 120.55 127)
		(end 120.85 126.7)
		(width 0.125)
		(layer "F.Cu")
		(net 45)
	)
	(segment
		(start 99.6755 112.9755)
		(end 100.05 113.35)
		(width 0.125)
		(layer "F.Cu")
		(net 45)
	)
	(segment
		(start 96.1 112.9755)
		(end 96.0755 112.9755)
		(width 0.125)
		(layer "F.Cu")
		(net 45)
	)
	(segment
		(start 93.76 83.94)
		(end 94.347323 83.352677)
		(width 0.125)
		(layer "F.Cu")
		(net 45)
	)
	(segment
		(start 94.347323 83.352677)
		(end 94.347323 80.205136)
		(width 0.125)
		(layer "F.Cu")
		(net 45)
	)
	(segment
		(start 124.95 126.65)
		(end 124.95 126.7)
		(width 0.155)
		(layer "F.Cu")
		(net 45)
	)
	(segment
		(start 94.9 90.09)
		(end 93.76 88.95)
		(width 0.125)
		(layer "F.Cu")
		(net 45)
	)
	(segment
		(start 93.76 88.95)
		(end 93.76 83.94)
		(width 0.125)
		(layer "F.Cu")
		(net 45)
	)
	(segment
		(start 120.85 126.7)
		(end 120.85 126.65)
		(width 0.155)
		(layer "F.Cu")
		(net 45)
	)
	(segment
		(start 120.55 127.75)
		(end 120.55 127)
		(width 0.125)
		(layer "F.Cu")
		(net 45)
	)
	(segment
		(start 94.0875 98.3125)
		(end 94.9 97.5)
		(width 0.125)
		(layer "F.Cu")
		(net 45)
	)
	(via
		(at 96.1 112.9755)
		(size 0.45)
		(drill 0.1)
		(layers "F.Cu" "B.Cu")
		(net 45)
	)
	(via
		(at 120.15 121.5)
		(size 0.45)
		(drill 0.1)
		(layers "F.Cu" "B.Cu")
		(net 45)
	)
	(via
		(at 120.55 127.75)
		(size 0.45)
		(drill 0.1)
		(layers "F.Cu" "B.Cu")
		(net 45)
	)
	(segment
		(start 107.75 115.45)
		(end 108.4 116.1)
		(width 0.15)
		(layer "In3.Cu")
		(net 45)
	)
	(segment
		(start 104.05 115.45)
		(end 107.75 115.45)
		(width 0.15)
		(layer "In3.Cu")
		(net 45)
	)
	(segment
		(start 108.4 116.1)
		(end 118.5 116.1)
		(width 0.15)
		(layer "In3.Cu")
		(net 45)
	)
	(segment
		(start 96.1 112.9755)
		(end 101.5755 112.9755)
		(width 0.125)
		(layer "In3.Cu")
		(net 45)
	)
	(segment
		(start 120.15 121.5)
		(end 120.6 121.05)
		(width 0.125)
		(layer "In3.Cu")
		(net 45)
	)
	(segment
		(start 119.1 116.1)
		(end 118.5 116.1)
		(width 0.125)
		(layer "In3.Cu")
		(net 45)
	)
	(segment
		(start 120.6 117.6)
		(end 119.1 116.1)
		(width 0.125)
		(layer "In3.Cu")
		(net 45)
	)
	(segment
		(start 101.5755 112.9755)
		(end 101.875 113.275)
		(width 0.125)
		(layer "In3.Cu")
		(net 45)
	)
	(segment
		(start 101.875 113.275)
		(end 104.05 115.45)
		(width 0.15)
		(layer "In3.Cu")
		(net 45)
	)
	(segment
		(start 120.6 121.05)
		(end 120.6 117.6)
		(width 0.125)
		(layer "In3.Cu")
		(net 45)
	)
	(segment
		(start 120.15 121.5)
		(end 120.6 121.95)
		(width 0.125)
		(layer "In5.Cu")
		(net 45)
	)
	(segment
		(start 120.6 127.7)
		(end 120.55 127.75)
		(width 0.125)
		(layer "In5.Cu")
		(net 45)
	)
	(segment
		(start 120.6 121.95)
		(end 120.6 127.7)
		(width 0.125)
		(layer "In5.Cu")
		(net 45)
	)
	(segment
		(start 120.55 127.15)
		(end 120.6 127.1)
		(width 0.125)
		(layer "B.Cu")
		(net 45)
	)
	(segment
		(start 120.55 127.75)
		(end 120.55 127.15)
		(width 0.125)
		(layer "B.Cu")
		(net 45)
	)
	(segment
		(start 99.05 113.7)
		(end 99.05 114.165)
		(width 0.15)
		(layer "F.Cu")
		(net 46)
	)
	(segment
		(start 94.975 103.675)
		(end 93.8 102.5)
		(width 0.125)
		(layer "F.Cu")
		(net 46)
	)
	(segment
		(start 93.8 102.5)
		(end 93.8 98.14)
		(width 0.125)
		(layer "F.Cu")
		(net 46)
	)
	(segment
		(start 93.8 98.14)
		(end 94.625 97.315)
		(width 0.125)
		(layer "F.Cu")
		(net 46)
	)
	(segment
		(start 94.625 97.315)
		(end 94.625 90.175)
		(width 0.125)
		(layer "F.Cu")
		(net 46)
	)
	(segment
		(start 93.847323 83.472677)
		(end 93.847323 80.205136)
		(width 0.125)
		(layer "F.Cu")
		(net 46)
	)
	(segment
		(start 94.625 90.175)
		(end 93.45 89)
		(width 0.125)
		(layer "F.Cu")
		(net 46)
	)
	(segment
		(start 130.5 126.2)
		(end 130.95 126.65)
		(width 0.155)
		(layer "F.Cu")
		(net 46)
	)
	(segment
		(start 126.6 126.95)
		(end 126.85 126.7)
		(width 0.125)
		(layer "F.Cu")
		(net 46)
	)
	(segment
		(start 98.75 113.4)
		(end 99.05 113.7)
		(width 0.15)
		(layer "F.Cu")
		(net 46)
	)
	(segment
		(start 126.6 127.7)
		(end 126.6 126.95)
		(width 0.125)
		(layer "F.Cu")
		(net 46)
	)
	(segment
		(start 93.45 83.87)
		(end 93.847323 83.472677)
		(width 0.125)
		(layer "F.Cu")
		(net 46)
	)
	(segment
		(start 127.3 126.2)
		(end 130.5 126.2)
		(width 0.155)
		(layer "F.Cu")
		(net 46)
	)
	(segment
		(start 126.85 126.7)
		(end 126.85 126.65)
		(width 0.155)
		(layer "F.Cu")
		(net 46)
	)
	(segment
		(start 95.6 113.4)
		(end 98.75 113.4)
		(width 0.15)
		(layer "F.Cu")
		(net 46)
	)
	(segment
		(start 130.95 126.65)
		(end 130.95 126.7)
		(width 0.155)
		(layer "F.Cu")
		(net 46)
	)
	(segment
		(start 95.6 113.4)
		(end 94.975 112.775)
		(width 0.125)
		(layer "F.Cu")
		(net 46)
	)
	(segment
		(start 126.85 126.65)
		(end 127.3 126.2)
		(width 0.155)
		(layer "F.Cu")
		(net 46)
	)
	(segment
		(start 94.975 112.775)
		(end 94.975 103.675)
		(width 0.125)
		(layer "F.Cu")
		(net 46)
	)
	(segment
		(start 93.45 89)
		(end 93.45 83.87)
		(width 0.125)
		(layer "F.Cu")
		(net 46)
	)
	(via
		(at 95.6 113.4)
		(size 0.45)
		(drill 0.1)
		(layers "F.Cu" "B.Cu")
		(net 46)
	)
	(via
		(at 126.6 127.7)
		(size 0.45)
		(drill 0.1)
		(layers "F.Cu" "B.Cu")
		(net 46)
	)
	(via
		(at 120.15 120.8)
		(size 0.45)
		(drill 0.1)
		(layers "F.Cu" "B.Cu")
		(net 46)
	)
	(segment
		(start 120.15 120.8)
		(end 120.3 120.65)
		(width 0.125)
		(layer "In3.Cu")
		(net 46)
	)
	(segment
		(start 108.2 116.4)
		(end 118.525 116.4)
		(width 0.15)
		(layer "In3.Cu")
		(net 46)
	)
	(segment
		(start 101.65 113.55)
		(end 103.9 115.8)
		(width 0.15)
		(layer "In3.Cu")
		(net 46)
	)
	(segment
		(start 101.5 113.4)
		(end 101.65 113.55)
		(width 0.125)
		(layer "In3.Cu")
		(net 46)
	)
	(segment
		(start 103.9 115.8)
		(end 107.6 115.8)
		(width 0.15)
		(layer "In3.Cu")
		(net 46)
	)
	(segment
		(start 107.6 115.8)
		(end 108.2 116.4)
		(width 0.15)
		(layer "In3.Cu")
		(net 46)
	)
	(segment
		(start 120.3 117.7)
		(end 119 116.4)
		(width 0.125)
		(layer "In3.Cu")
		(net 46)
	)
	(segment
		(start 119 116.4)
		(end 118.525 116.4)
		(width 0.125)
		(layer "In3.Cu")
		(net 46)
	)
	(segment
		(start 120.3 120.65)
		(end 120.3 117.7)
		(width 0.125)
		(layer "In3.Cu")
		(net 46)
	)
	(segment
		(start 95.6 113.4)
		(end 101.5 113.4)
		(width 0.125)
		(layer "In3.Cu")
		(net 46)
	)
	(segment
		(start 120.9 121.55)
		(end 120.15 120.8)
		(width 0.125)
		(layer "In5.Cu")
		(net 46)
	)
	(segment
		(start 126.6 127.3)
		(end 126.45 127.15)
		(width 0.125)
		(layer "In5.Cu")
		(net 46)
	)
	(segment
		(start 121.15 127.15)
		(end 120.9 126.9)
		(width 0.125)
		(layer "In5.Cu")
		(net 46)
	)
	(segment
		(start 126.45 127.15)
		(end 121.15 127.15)
		(width 0.125)
		(layer "In5.Cu")
		(net 46)
	)
	(segment
		(start 126.6 127.7)
		(end 126.6 127.3)
		(width 0.125)
		(layer "In5.Cu")
		(net 46)
	)
	(segment
		(start 120.9 126.9)
		(end 120.9 121.55)
		(width 0.125)
		(layer "In5.Cu")
		(net 46)
	)
	(segment
		(start 126.6 127.7)
		(end 126.6 127.15)
		(width 0.125)
		(layer "B.Cu")
		(net 46)
	)
	(segment
		(start 93.496823 70.742505)
		(end 93.496823 71.179636)
		(width 0.155)
		(layer "F.Cu")
		(net 47)
	)
	(segment
		(start 93.496823 71.179636)
		(end 93.597323 71.280136)
		(width 0.155)
		(layer "F.Cu")
		(net 47)
	)
	(segment
		(start 93.25 70.03)
		(end 93.25 70.226443)
		(width 0.155)
		(layer "F.Cu")
		(net 47)
	)
	(segment
		(start 93.293934 70.332509)
		(end 93.350377 70.388952)
		(width 0.155)
		(layer "F.Cu")
		(net 47)
	)
	(via
		(at 121.862567 86.047)
		(size 0.45)
		(drill 0.1)
		(layers "F.Cu" "B.Cu")
		(net 47)
	)
	(via
		(at 93.25 70.03)
		(size 0.45)
		(drill 0.1)
		(layers "F.Cu" "B.Cu")
		(net 47)
	)
	(arc
		(start 93.496823 70.742505)
		(mid 93.458763 70.551164)
		(end 93.350377 70.388952)
		(width 0.155)
		(layer "F.Cu")
		(net 47)
	)
	(arc
		(start 93.25 70.226443)
		(mid 93.261418 70.283846)
		(end 93.293934 70.332509)
		(width 0.155)
		(layer "F.Cu")
		(net 47)
	)
	(segment
		(start 105.465795 71.573487)
		(end 105.516836 71.522446)
		(width 0.16)
		(layer "In3.Cu")
		(net 47)
	)
	(segment
		(start 105.870389 71.376)
		(end 124.304611 71.376)
		(width 0.16)
		(layer "In3.Cu")
		(net 47)
	)
	(segment
		(start 124.769 83.086693)
		(end 124.769 84.704611)
		(width 0.16)
		(layer "In3.Cu")
		(net 47)
	)
	(segment
		(start 124.622553 85.058165)
		(end 123.928164 85.752554)
		(width 0.16)
		(layer "In3.Cu")
		(net 47)
	)
	(segment
		(start 94.781693 71.676)
		(end 105.218307 71.676)
		(width 0.16)
		(layer "In3.Cu")
		(net 47)
	)
	(segment
		(start 123.574611 85.899)
		(end 122.072699 85.899)
		(width 0.16)
		(layer "In3.Cu")
		(net 47)
	)
	(segment
		(start 125.219 76.436693)
		(end 125.219 82.284611)
		(width 0.16)
		(layer "In3.Cu")
		(net 47)
	)
	(segment
		(start 124.658165 71.522447)
		(end 125.362554 72.226836)
		(width 0.16)
		(layer "In3.Cu")
		(net 47)
	)
	(segment
		(start 125.509 72.580389)
		(end 125.509 75.794611)
		(width 0.16)
		(layer "In3.Cu")
		(net 47)
	)
	(segment
		(start 125.072553 82.638165)
		(end 124.871512 82.839206)
		(width 0.16)
		(layer "In3.Cu")
		(net 47)
	)
	(segment
		(start 121.966633 85.942934)
		(end 121.862567 86.047)
		(width 0.16)
		(layer "In3.Cu")
		(net 47)
	)
	(segment
		(start 93.293934 70.333216)
		(end 94.534206 71.573488)
		(width 0.16)
		(layer "In3.Cu")
		(net 47)
	)
	(segment
		(start 125.362553 76.148165)
		(end 125.321512 76.189206)
		(width 0.16)
		(layer "In3.Cu")
		(net 47)
	)
	(segment
		(start 93.25 70.03)
		(end 93.25 70.22715)
		(width 0.16)
		(layer "In3.Cu")
		(net 47)
	)
	(arc
		(start 122.072699 85.899)
		(mid 122.015296 85.910418)
		(end 121.966633 85.942934)
		(width 0.16)
		(layer "In3.Cu")
		(net 47)
	)
	(arc
		(start 123.928164 85.752554)
		(mid 123.765952 85.86094)
		(end 123.574611 85.899)
		(width 0.16)
		(layer "In3.Cu")
		(net 47)
	)
	(arc
		(start 94.781693 71.676)
		(mid 94.647754 71.649358)
		(end 94.534206 71.573488)
		(width 0.16)
		(layer "In3.Cu")
		(net 47)
	)
	(arc
		(start 125.362554 72.226836)
		(mid 125.47094 72.389048)
		(end 125.509 72.580389)
		(width 0.16)
		(layer "In3.Cu")
		(net 47)
	)
	(arc
		(start 125.219 76.436693)
		(mid 125.245642 76.302754)
		(end 125.321512 76.189206)
		(width 0.16)
		(layer "In3.Cu")
		(net 47)
	)
	(arc
		(start 124.304611 71.376)
		(mid 124.495953 71.41406)
		(end 124.658165 71.522447)
		(width 0.16)
		(layer "In3.Cu")
		(net 47)
	)
	(arc
		(start 125.219 82.284611)
		(mid 125.18094 82.475953)
		(end 125.072553 82.638165)
		(width 0.16)
		(layer "In3.Cu")
		(net 47)
	)
	(arc
		(start 105.516836 71.522446)
		(mid 105.679048 71.41406)
		(end 105.870389 71.376)
		(width 0.16)
		(layer "In3.Cu")
		(net 47)
	)
	(arc
		(start 124.769 84.704611)
		(mid 124.73094 84.895953)
		(end 124.622553 85.058165)
		(width 0.16)
		(layer "In3.Cu")
		(net 47)
	)
	(arc
		(start 93.293934 70.333216)
		(mid 93.261418 70.284553)
		(end 93.25 70.22715)
		(width 0.16)
		(layer "In3.Cu")
		(net 47)
	)
	(arc
		(start 105.465795 71.573487)
		(mid 105.352247 71.649358)
		(end 105.218307 71.676)
		(width 0.16)
		(layer "In3.Cu")
		(net 47)
	)
	(arc
		(start 125.509 75.794611)
		(mid 125.47094 75.985953)
		(end 125.362553 76.148165)
		(width 0.16)
		(layer "In3.Cu")
		(net 47)
	)
	(arc
		(start 124.769 83.086693)
		(mid 124.795642 82.952754)
		(end 124.871512 82.839206)
		(width 0.16)
		(layer "In3.Cu")
		(net 47)
	)
	(segment
		(start 124.3 86)
		(end 123.199631 86)
		(width 0.155)
		(layer "B.Cu")
		(net 47)
	)
	(segment
		(start 122.974867 85.8995)
		(end 122.072199 85.8995)
		(width 0.155)
		(layer "B.Cu")
		(net 47)
	)
	(segment
		(start 123.093565 85.956066)
		(end 123.080933 85.943434)
		(width 0.155)
		(layer "B.Cu")
		(net 47)
	)
	(segment
		(start 121.966133 85.943434)
		(end 121.862567 86.047)
		(width 0.155)
		(layer "B.Cu")
		(net 47)
	)
	(arc
		(start 123.199631 86)
		(mid 123.142228 85.988582)
		(end 123.093565 85.956066)
		(width 0.155)
		(layer "B.Cu")
		(net 47)
	)
	(arc
		(start 122.072199 85.8995)
		(mid 122.014796 85.910918)
		(end 121.966133 85.943434)
		(width 0.155)
		(layer "B.Cu")
		(net 47)
	)
	(arc
		(start 122.974867 85.8995)
		(mid 123.03227 85.910918)
		(end 123.080933 85.943434)
		(width 0.155)
		(layer "B.Cu")
		(net 47)
	)
	(segment
		(start 93.012509 70.473934)
		(end 93.095311 70.556736)
		(width 0.155)
		(layer "F.Cu")
		(net 48)
	)
	(segment
		(start 92.8 70.43)
		(end 92.906443 70.43)
		(width 0.155)
		(layer "F.Cu")
		(net 48)
	)
	(segment
		(start 93.197823 70.804223)
		(end 93.197823 71.179636)
		(width 0.155)
		(layer "F.Cu")
		(net 48)
	)
	(segment
		(start 93.197823 71.179636)
		(end 93.097323 71.280136)
		(width 0.155)
		(layer "F.Cu")
		(net 48)
	)
	(via
		(at 92.8 70.43)
		(size 0.45)
		(drill 0.1)
		(layers "F.Cu" "B.Cu")
		(net 48)
	)
	(via
		(at 121.862567 85.453)
		(size 0.45)
		(drill 0.1)
		(layers "F.Cu" "B.Cu")
		(net 48)
	)
	(arc
		(start 93.012509 70.473934)
		(mid 92.963846 70.441418)
		(end 92.906443 70.43)
		(width 0.155)
		(layer "F.Cu")
		(net 48)
	)
	(arc
		(start 93.095311 70.556736)
		(mid 93.171181 70.670284)
		(end 93.197823 70.804223)
		(width 0.155)
		(layer "F.Cu")
		(net 48)
	)
	(segment
		(start 124.368487 84.890795)
		(end 123.760794 85.498488)
		(width 0.16)
		(layer "In3.Cu")
		(net 48)
	)
	(segment
		(start 124.490795 71.776513)
		(end 125.108488 72.394206)
		(width 0.16)
		(layer "In3.Cu")
		(net 48)
	)
	(segment
		(start 124.471 83.025389)
		(end 124.471 83.099)
		(width 0.16)
		(layer "In3.Cu")
		(net 48)
	)
	(segment
		(start 125.108487 75.980795)
		(end 125.067446 76.021836)
		(width 0.16)
		(layer "In3.Cu")
		(net 48)
	)
	(segment
		(start 93.981037 71.441755)
		(end 94.016392 71.47711)
		(width 0.16)
		(layer "In3.Cu")
		(net 48)
	)
	(segment
		(start 105.931693 71.674)
		(end 124.243307 71.674)
		(width 0.16)
		(layer "In3.Cu")
		(net 48)
	)
	(segment
		(start 124.471 83.799)
		(end 124.471 84.643307)
		(width 0.16)
		(layer "In3.Cu")
		(net 48)
	)
	(segment
		(start 94.016392 71.47711)
		(end 94.366836 71.827554)
		(width 0.16)
		(layer "In3.Cu")
		(net 48)
	)
	(segment
		(start 93.013216 70.473934)
		(end 93.344641 70.805359)
		(width 0.16)
		(layer "In3.Cu")
		(net 48)
	)
	(segment
		(start 124.258509 83.624)
		(end 124.296 83.624)
		(width 0.16)
		(layer "In3.Cu")
		(net 48)
	)
	(segment
		(start 124.818487 82.470795)
		(end 124.617446 82.671836)
		(width 0.16)
		(layer "In3.Cu")
		(net 48)
	)
	(segment
		(start 125.211 72.641693)
		(end 125.211 75.733307)
		(width 0.16)
		(layer "In3.Cu")
		(net 48)
	)
	(segment
		(start 123.513307 85.601)
		(end 122.072699 85.601)
		(width 0.16)
		(layer "In3.Cu")
		(net 48)
	)
	(segment
		(start 94.720389 71.974)
		(end 105.279611 71.974)
		(width 0.16)
		(layer "In3.Cu")
		(net 48)
	)
	(segment
		(start 92.8 70.43)
		(end 92.90715 70.43)
		(width 0.16)
		(layer "In3.Cu")
		(net 48)
	)
	(segment
		(start 93.34464 71.123558)
		(end 93.344641 71.123557)
		(width 0.16)
		(layer "In3.Cu")
		(net 48)
	)
	(segment
		(start 124.296 83.274)
		(end 124.258509 83.274)
		(width 0.16)
		(layer "In3.Cu")
		(net 48)
	)
	(segment
		(start 105.633165 71.827553)
		(end 105.684206 71.776512)
		(width 0.16)
		(layer "In3.Cu")
		(net 48)
	)
	(segment
		(start 93.66284 71.441754)
		(end 93.662839 71.441755)
		(width 0.16)
		(layer "In3.Cu")
		(net 48)
	)
	(segment
		(start 121.966633 85.557066)
		(end 121.862567 85.453)
		(width 0.16)
		(layer "In3.Cu")
		(net 48)
	)
	(segment
		(start 124.921 76.375389)
		(end 124.921 82.223307)
		(width 0.16)
		(layer "In3.Cu")
		(net 48)
	)
	(arc
		(start 124.296 83.624)
		(mid 124.419744 83.675256)
		(end 124.471 83.799)
		(width 0.16)
		(layer "In3.Cu")
		(net 48)
	)
	(arc
		(start 93.662839 71.441755)
		(mid 93.821938 71.375854)
		(end 93.981037 71.441755)
		(width 0.16)
		(layer "In3.Cu")
		(net 48)
	)
	(arc
		(start 124.368487 84.890795)
		(mid 124.444358 84.777247)
		(end 124.471 84.643307)
		(width 0.16)
		(layer "In3.Cu")
		(net 48)
	)
	(arc
		(start 123.760794 85.498488)
		(mid 123.647246 85.574358)
		(end 123.513307 85.601)
		(width 0.16)
		(layer "In3.Cu")
		(net 48)
	)
	(arc
		(start 93.344641 71.123557)
		(mid 93.27874 71.282656)
		(end 93.344641 71.441755)
		(width 0.16)
		(layer "In3.Cu")
		(net 48)
	)
	(arc
		(start 94.366836 71.827554)
		(mid 94.529048 71.93594)
		(end 94.720389 71.974)
		(width 0.16)
		(layer "In3.Cu")
		(net 48)
	)
	(arc
		(start 122.072699 85.601)
		(mid 122.015296 85.589582)
		(end 121.966633 85.557066)
		(width 0.16)
		(layer "In3.Cu")
		(net 48)
	)
	(arc
		(start 124.258509 83.274)
		(mid 124.134765 83.325256)
		(end 124.083509 83.449)
		(width 0.16)
		(layer "In3.Cu")
		(net 48)
	)
	(arc
		(start 93.344641 70.805359)
		(mid 93.410542 70.964459)
		(end 93.34464 71.123558)
		(width 0.16)
		(layer "In3.Cu")
		(net 48)
	)
	(arc
		(start 124.471 83.025389)
		(mid 124.50906 82.834048)
		(end 124.617446 82.671836)
		(width 0.16)
		(layer "In3.Cu")
		(net 48)
	)
	(arc
		(start 124.490795 71.776513)
		(mid 124.377247 71.700642)
		(end 124.243307 71.674)
		(width 0.16)
		(layer "In3.Cu")
		(net 48)
	)
	(arc
		(start 105.279611 71.974)
		(mid 105.470953 71.93594)
		(end 105.633165 71.827553)
		(width 0.16)
		(layer "In3.Cu")
		(net 48)
	)
	(arc
		(start 124.471 83.099)
		(mid 124.419744 83.222744)
		(end 124.296 83.274)
		(width 0.16)
		(layer "In3.Cu")
		(net 48)
	)
	(arc
		(start 124.083509 83.449)
		(mid 124.134765 83.572744)
		(end 124.258509 83.624)
		(width 0.16)
		(layer "In3.Cu")
		(net 48)
	)
	(arc
		(start 93.344641 71.441755)
		(mid 93.503741 71.507656)
		(end 93.66284 71.441754)
		(width 0.16)
		(layer "In3.Cu")
		(net 48)
	)
	(arc
		(start 125.108487 75.980795)
		(mid 125.184358 75.867247)
		(end 125.211 75.733307)
		(width 0.16)
		(layer "In3.Cu")
		(net 48)
	)
	(arc
		(start 93.013216 70.473934)
		(mid 92.964553 70.441418)
		(end 92.90715 70.43)
		(width 0.16)
		(layer "In3.Cu")
		(net 48)
	)
	(arc
		(start 124.818487 82.470795)
		(mid 124.894358 82.357247)
		(end 124.921 82.223307)
		(width 0.16)
		(layer "In3.Cu")
		(net 48)
	)
	(arc
		(start 105.931693 71.674)
		(mid 105.797754 71.700642)
		(end 105.684206 71.776512)
		(width 0.16)
		(layer "In3.Cu")
		(net 48)
	)
	(arc
		(start 125.108488 72.394206)
		(mid 125.184358 72.507754)
		(end 125.211 72.641693)
		(width 0.16)
		(layer "In3.Cu")
		(net 48)
	)
	(arc
		(start 125.067446 76.021836)
		(mid 124.95906 76.184048)
		(end 124.921 76.375389)
		(width 0.16)
		(layer "In3.Cu")
		(net 48)
	)
	(segment
		(start 124.3 85.5)
		(end 123.199631 85.5)
		(width 0.155)
		(layer "B.Cu")
		(net 48)
	)
	(segment
		(start 122.974867 85.6005)
		(end 122.072199 85.6005)
		(width 0.155)
		(layer "B.Cu")
		(net 48)
	)
	(segment
		(start 123.093565 85.543934)
		(end 123.080933 85.556566)
		(width 0.155)
		(layer "B.Cu")
		(net 48)
	)
	(segment
		(start 121.966133 85.556566)
		(end 121.862567 85.453)
		(width 0.155)
		(layer "B.Cu")
		(net 48)
	)
	(arc
		(start 122.974867 85.6005)
		(mid 123.03227 85.589082)
		(end 123.080933 85.556566)
		(width 0.155)
		(layer "B.Cu")
		(net 48)
	)
	(arc
		(start 123.199631 85.5)
		(mid 123.142228 85.511418)
		(end 123.093565 85.543934)
		(width 0.155)
		(layer "B.Cu")
		(net 48)
	)
	(arc
		(start 122.072199 85.6005)
		(mid 122.014796 85.589082)
		(end 121.966133 85.556566)
		(width 0.155)
		(layer "B.Cu")
		(net 48)
	)
	(segment
		(start 92.623054 76.098372)
		(end 92.163434 76.557992)
		(width 0.155)
		(layer "F.Cu")
		(net 49)
	)
	(segment
		(start 92.1195 76.664058)
		(end 92.1195 76.757368)
		(width 0.155)
		(layer "F.Cu")
		(net 49)
	)
	(segment
		(start 92.322132 76.96)
		(end 92.480868 76.96)
		(width 0.155)
		(layer "F.Cu")
		(net 49)
	)
	(segment
		(start 92.586934 76.916066)
		(end 92.6 76.903)
		(width 0.155)
		(layer "F.Cu")
		(net 49)
	)
	(segment
		(start 92.7695 75.015181)
		(end 92.7695 75.744819)
		(width 0.155)
		(layer "F.Cu")
		(net 49)
	)
	(segment
		(start 91.996823 72.830636)
		(end 91.996823 73.890422)
		(width 0.155)
		(layer "F.Cu")
		(net 49)
	)
	(segment
		(start 92.097323 72.730136)
		(end 91.996823 72.830636)
		(width 0.155)
		(layer "F.Cu")
		(net 49)
	)
	(segment
		(start 92.099336 74.13791)
		(end 92.623053 74.661627)
		(width 0.155)
		(layer "F.Cu")
		(net 49)
	)
	(segment
		(start 92.097323 72.005136)
		(end 92.097323 72.730136)
		(width 0.155)
		(layer "F.Cu")
		(net 49)
	)
	(segment
		(start 92.163434 76.863434)
		(end 92.216066 76.916066)
		(width 0.155)
		(layer "F.Cu")
		(net 49)
	)
	(via
		(at 92.6 76.903)
		(size 0.45)
		(drill 0.1)
		(layers "F.Cu" "B.Cu")
		(net 49)
	)
	(via
		(at 121.68 89.047)
		(size 0.45)
		(drill 0.1)
		(layers "F.Cu" "B.Cu")
		(net 49)
	)
	(arc
		(start 91.996823 73.890422)
		(mid 92.023465 74.024362)
		(end 92.099336 74.13791)
		(width 0.155)
		(layer "F.Cu")
		(net 49)
	)
	(arc
		(start 92.480868 76.96)
		(mid 92.538271 76.948582)
		(end 92.586934 76.916066)
		(width 0.155)
		(layer "F.Cu")
		(net 49)
	)
	(arc
		(start 92.623053 74.661627)
		(mid 92.73144 74.823839)
		(end 92.7695 75.015181)
		(width 0.155)
		(layer "F.Cu")
		(net 49)
	)
	(arc
		(start 92.7695 75.744819)
		(mid 92.73144 75.93616)
		(end 92.623054 76.098372)
		(width 0.155)
		(layer "F.Cu")
		(net 49)
	)
	(arc
		(start 92.1195 76.757368)
		(mid 92.130918 76.814771)
		(end 92.163434 76.863434)
		(width 0.155)
		(layer "F.Cu")
		(net 49)
	)
	(arc
		(start 92.216066 76.916066)
		(mid 92.264729 76.948582)
		(end 92.322132 76.96)
		(width 0.155)
		(layer "F.Cu")
		(net 49)
	)
	(arc
		(start 92.163434 76.557992)
		(mid 92.130918 76.606655)
		(end 92.1195 76.664058)
		(width 0.155)
		(layer "F.Cu")
		(net 49)
	)
	(segment
		(start 111.784611 79.491)
		(end 109.196693 79.491)
		(width 0.16)
		(layer "In3.Cu")
		(net 49)
	)
	(segment
		(start 94.989205 77.468487)
		(end 94.718164 77.197446)
		(width 0.16)
		(layer "In3.Cu")
		(net 49)
	)
	(segment
		(start 102.743307 77.571)
		(end 95.236693 77.571)
		(width 0.16)
		(layer "In3.Cu")
		(net 49)
	)
	(segment
		(start 121.68 89.047)
		(end 121.784066 88.942934)
		(width 0.16)
		(layer "In3.Cu")
		(net 49)
	)
	(segment
		(start 112.972553 80.471835)
		(end 112.138164 79.637446)
		(width 0.16)
		(layer "In3.Cu")
		(net 49)
	)
	(segment
		(start 113.119 83.188307)
		(end 113.119 80.825389)
		(width 0.16)
		(layer "In3.Cu")
		(net 49)
	)
	(segment
		(start 103.411835 77.047447)
		(end 102.990794 77.468488)
		(width 0.16)
		(layer "In3.Cu")
		(net 49)
	)
	(segment
		(start 120.57615 88.171)
		(end 118.101693 88.171)
		(width 0.16)
		(layer "In3.Cu")
		(net 49)
	)
	(segment
		(start 122.531132 87.790414)
		(end 122.299586 87.558868)
		(width 0.16)
		(layer "In3.Cu")
		(net 49)
	)
	(segment
		(start 105.990271 77.104553)
		(end 105.933164 77.047446)
		(width 0.16)
		(layer "In3.Cu")
		(net 49)
	)
	(segment
		(start 121.890132 88.899)
		(end 122.067454 88.899)
		(width 0.16)
		(layer "In3.Cu")
		(net 49)
	)
	(segment
		(start 108.599 78.893307)
		(end 108.599 78.020389)
		(width 0.16)
		(layer "In3.Cu")
		(net 49)
	)
	(segment
		(start 122.619 88.347454)
		(end 122.619 88.002546)
		(width 0.16)
		(layer "In3.Cu")
		(net 49)
	)
	(segment
		(start 122.279586 88.811132)
		(end 122.531132 88.559586)
		(width 0.16)
		(layer "In3.Cu")
		(net 49)
	)
	(segment
		(start 120.970414 87.838868)
		(end 120.682216 88.127066)
		(width 0.16)
		(layer "In3.Cu")
		(net 49)
	)
	(segment
		(start 92.748 77.051)
		(end 92.6 76.903)
		(width 0.16)
		(layer "In3.Cu")
		(net 49)
	)
	(segment
		(start 108.949205 79.388487)
		(end 108.701512 79.140794)
		(width 0.16)
		(layer "In3.Cu")
		(net 49)
	)
	(segment
		(start 108.452553 77.666835)
		(end 108.183164 77.397446)
		(width 0.16)
		(layer "In3.Cu")
		(net 49)
	)
	(segment
		(start 121.42615 87.751)
		(end 121.182546 87.751)
		(width 0.16)
		(layer "In3.Cu")
		(net 49)
	)
	(segment
		(start 117.854205 88.068487)
		(end 113.221512 83.435794)
		(width 0.16)
		(layer "In3.Cu")
		(net 49)
	)
	(segment
		(start 122.087454 87.471)
		(end 121.892546 87.471)
		(width 0.16)
		(layer "In3.Cu")
		(net 49)
	)
	(segment
		(start 94.364611 77.051)
		(end 92.748 77.051)
		(width 0.16)
		(layer "In3.Cu")
		(net 49)
	)
	(segment
		(start 107.829611 77.251)
		(end 106.343825 77.251)
		(width 0.16)
		(layer "In3.Cu")
		(net 49)
	)
	(segment
		(start 105.579611 76.901)
		(end 103.765389 76.901)
		(width 0.16)
		(layer "In3.Cu")
		(net 49)
	)
	(segment
		(start 121.680414 87.558868)
		(end 121.532216 87.707066)
		(width 0.16)
		(layer "In3.Cu")
		(net 49)
	)
	(arc
		(start 120.970414 87.838868)
		(mid 121.067741 87.773836)
		(end 121.182546 87.751)
		(width 0.16)
		(layer "In3.Cu")
		(net 49)
	)
	(arc
		(start 112.972553 80.471835)
		(mid 113.08094 80.634047)
		(end 113.119 80.825389)
		(width 0.16)
		(layer "In3.Cu")
		(net 49)
	)
	(arc
		(start 111.784611 79.491)
		(mid 111.975952 79.52906)
		(end 112.138164 79.637446)
		(width 0.16)
		(layer "In3.Cu")
		(net 49)
	)
	(arc
		(start 102.743307 77.571)
		(mid 102.877246 77.544358)
		(end 102.990794 77.468488)
		(width 0.16)
		(layer "In3.Cu")
		(net 49)
	)
	(arc
		(start 103.411835 77.047447)
		(mid 103.574047 76.93906)
		(end 103.765389 76.901)
		(width 0.16)
		(layer "In3.Cu")
		(net 49)
	)
	(arc
		(start 105.933164 77.047446)
		(mid 105.770952 76.93906)
		(end 105.579611 76.901)
		(width 0.16)
		(layer "In3.Cu")
		(net 49)
	)
	(arc
		(start 122.619 88.347454)
		(mid 122.596164 88.462259)
		(end 122.531132 88.559586)
		(width 0.16)
		(layer "In3.Cu")
		(net 49)
	)
	(arc
		(start 113.119 83.188307)
		(mid 113.145642 83.322246)
		(end 113.221512 83.435794)
		(width 0.16)
		(layer "In3.Cu")
		(net 49)
	)
	(arc
		(start 121.892546 87.471)
		(mid 121.777741 87.493836)
		(end 121.680414 87.558868)
		(width 0.16)
		(layer "In3.Cu")
		(net 49)
	)
	(arc
		(start 109.196693 79.491)
		(mid 109.062753 79.464358)
		(end 108.949205 79.388487)
		(width 0.16)
		(layer "In3.Cu")
		(net 49)
	)
	(arc
		(start 94.989205 77.468487)
		(mid 95.102753 77.544358)
		(end 95.236693 77.571)
		(width 0.16)
		(layer "In3.Cu")
		(net 49)
	)
	(arc
		(start 108.599 78.893307)
		(mid 108.625642 79.027246)
		(end 108.701512 79.140794)
		(width 0.16)
		(layer "In3.Cu")
		(net 49)
	)
	(arc
		(start 118.101693 88.171)
		(mid 117.967753 88.144358)
		(end 117.854205 88.068487)
		(width 0.16)
		(layer "In3.Cu")
		(net 49)
	)
	(arc
		(start 120.57615 88.171)
		(mid 120.633553 88.159582)
		(end 120.682216 88.127066)
		(width 0.16)
		(layer "In3.Cu")
		(net 49)
	)
	(arc
		(start 121.42615 87.751)
		(mid 121.483553 87.739582)
		(end 121.532216 87.707066)
		(width 0.16)
		(layer "In3.Cu")
		(net 49)
	)
	(arc
		(start 122.067454 88.899)
		(mid 122.182259 88.876164)
		(end 122.279586 88.811132)
		(width 0.16)
		(layer "In3.Cu")
		(net 49)
	)
	(arc
		(start 108.183164 77.397446)
		(mid 108.020952 77.28906)
		(end 107.829611 77.251)
		(width 0.16)
		(layer "In3.Cu")
		(net 49)
	)
	(arc
		(start 105.990271 77.104553)
		(mid 106.152483 77.21294)
		(end 106.343825 77.251)
		(width 0.16)
		(layer "In3.Cu")
		(net 49)
	)
	(arc
		(start 122.531132 87.790414)
		(mid 122.596164 87.887741)
		(end 122.619 88.002546)
		(width 0.16)
		(layer "In3.Cu")
		(net 49)
	)
	(arc
		(start 121.784066 88.942934)
		(mid 121.832729 88.910418)
		(end 121.890132 88.899)
		(width 0.16)
		(layer "In3.Cu")
		(net 49)
	)
	(arc
		(start 108.599 78.020389)
		(mid 108.56094 77.829047)
		(end 108.452553 77.666835)
		(width 0.16)
		(layer "In3.Cu")
		(net 49)
	)
	(arc
		(start 122.299586 87.558868)
		(mid 122.202259 87.493836)
		(end 122.087454 87.471)
		(width 0.16)
		(layer "In3.Cu")
		(net 49)
	)
	(arc
		(start 94.718164 77.197446)
		(mid 94.555952 77.08906)
		(end 94.364611 77.051)
		(width 0.16)
		(layer "In3.Cu")
		(net 49)
	)
	(segment
		(start 122.949867 88.8995)
		(end 121.889632 88.8995)
		(width 0.155)
		(layer "B.Cu")
		(net 49)
	)
	(segment
		(start 124.275 89)
		(end 123.174631 89)
		(width 0.155)
		(layer "B.Cu")
		(net 49)
	)
	(segment
		(start 123.068565 88.956066)
		(end 123.055933 88.943434)
		(width 0.155)
		(layer "B.Cu")
		(net 49)
	)
	(segment
		(start 121.783566 88.943434)
		(end 121.68 89.047)
		(width 0.155)
		(layer "B.Cu")
		(net 49)
	)
	(arc
		(start 122.949867 88.8995)
		(mid 123.00727 88.910918)
		(end 123.055933 88.943434)
		(width 0.155)
		(layer "B.Cu")
		(net 49)
	)
	(arc
		(start 121.889632 88.8995)
		(mid 121.832229 88.910918)
		(end 121.783566 88.943434)
		(width 0.155)
		(layer "B.Cu")
		(net 49)
	)
	(arc
		(start 123.174631 89)
		(mid 123.117228 88.988582)
		(end 123.068565 88.956066)
		(width 0.155)
		(layer "B.Cu")
		(net 49)
	)
	(segment
		(start 91.908368 77.028368)
		(end 92.141632 77.261632)
		(width 0.155)
		(layer "F.Cu")
		(net 50)
	)
	(segment
		(start 91.8205 76.602338)
		(end 91.8205 76.816236)
		(width 0.155)
		(layer "F.Cu")
		(net 50)
	)
	(segment
		(start 92.367988 75.930586)
		(end 91.908368 76.390206)
		(width 0.155)
		(layer "F.Cu")
		(net 50)
	)
	(segment
		(start 92.353764 77.3495)
		(end 92.390368 77.3495)
		(width 0.155)
		(layer "F.Cu")
		(net 50)
	)
	(segment
		(start 91.84427 74.305696)
		(end 92.367987 74.829413)
		(width 0.155)
		(layer "F.Cu")
		(net 50)
	)
	(segment
		(start 92.496434 77.393434)
		(end 92.6 77.497)
		(width 0.155)
		(layer "F.Cu")
		(net 50)
	)
	(segment
		(start 91.697823 72.830636)
		(end 91.697823 73.952142)
		(width 0.155)
		(layer "F.Cu")
		(net 50)
	)
	(segment
		(start 91.597323 72.730136)
		(end 91.697823 72.830636)
		(width 0.155)
		(layer "F.Cu")
		(net 50)
	)
	(segment
		(start 92.4705 75.076901)
		(end 92.4705 75.683099)
		(width 0.155)
		(layer "F.Cu")
		(net 50)
	)
	(segment
		(start 91.597323 72.005136)
		(end 91.597323 72.730136)
		(width 0.155)
		(layer "F.Cu")
		(net 50)
	)
	(via
		(at 121.68 88.453)
		(size 0.45)
		(drill 0.1)
		(layers "F.Cu" "B.Cu")
		(net 50)
	)
	(via
		(at 92.6 77.497)
		(size 0.45)
		(drill 0.1)
		(layers "F.Cu" "B.Cu")
		(net 50)
	)
	(arc
		(start 92.367987 74.829413)
		(mid 92.443858 74.942961)
		(end 92.4705 75.076901)
		(width 0.155)
		(layer "F.Cu")
		(net 50)
	)
	(arc
		(start 91.908368 76.390206)
		(mid 91.843336 76.487533)
		(end 91.8205 76.602338)
		(width 0.155)
		(layer "F.Cu")
		(net 50)
	)
	(arc
		(start 92.141632 77.261632)
		(mid 92.238959 77.326664)
		(end 92.353764 77.3495)
		(width 0.155)
		(layer "F.Cu")
		(net 50)
	)
	(arc
		(start 92.4705 75.683099)
		(mid 92.443858 75.817038)
		(end 92.367988 75.930586)
		(width 0.155)
		(layer "F.Cu")
		(net 50)
	)
	(arc
		(start 91.697823 73.952142)
		(mid 91.735883 74.143484)
		(end 91.84427 74.305696)
		(width 0.155)
		(layer "F.Cu")
		(net 50)
	)
	(arc
		(start 92.496434 77.393434)
		(mid 92.447771 77.360918)
		(end 92.390368 77.3495)
		(width 0.155)
		(layer "F.Cu")
		(net 50)
	)
	(arc
		(start 91.8205 76.816236)
		(mid 91.843336 76.931041)
		(end 91.908368 77.028368)
		(width 0.155)
		(layer "F.Cu")
		(net 50)
	)
	(segment
		(start 117.686835 88.322553)
		(end 112.967446 83.603164)
		(width 0.16)
		(layer "In3.Cu")
		(net 50)
	)
	(segment
		(start 108.301 78.954611)
		(end 108.301 78.081693)
		(width 0.16)
		(layer "In3.Cu")
		(net 50)
	)
	(segment
		(start 121.847784 87.812934)
		(end 121.699586 87.961132)
		(width 0.16)
		(layer "In3.Cu")
		(net 50)
	)
	(segment
		(start 102.804611 77.869)
		(end 95.175389 77.869)
		(width 0.16)
		(layer "In3.Cu")
		(net 50)
	)
	(segment
		(start 122.321 88.28615)
		(end 122.321 88.06385)
		(width 0.16)
		(layer "In3.Cu")
		(net 50)
	)
	(segment
		(start 119.674036 88.643964)
		(end 119.674036 88.643965)
		(width 0.16)
		(layer "In3.Cu")
		(net 50)
	)
	(segment
		(start 103.579205 77.301513)
		(end 103.158164 77.722554)
		(width 0.16)
		(layer "In3.Cu")
		(net 50)
	)
	(segment
		(start 108.198487 77.834205)
		(end 108.015794 77.651512)
		(width 0.16)
		(layer "In3.Cu")
		(net 50)
	)
	(segment
		(start 122.112216 88.557066)
		(end 122.277066 88.392216)
		(width 0.16)
		(layer "In3.Cu")
		(net 50)
	)
	(segment
		(start 105.518307 77.199)
		(end 103.826693 77.199)
		(width 0.16)
		(layer "In3.Cu")
		(net 50)
	)
	(segment
		(start 107.768307 77.549)
		(end 106.220389 77.549)
		(width 0.16)
		(layer "In3.Cu")
		(net 50)
	)
	(segment
		(start 111.723307 79.789)
		(end 109.135389 79.789)
		(width 0.16)
		(layer "In3.Cu")
		(net 50)
	)
	(segment
		(start 112.821 83.249611)
		(end 112.821 80.886693)
		(width 0.16)
		(layer "In3.Cu")
		(net 50)
	)
	(segment
		(start 119.324036 88.643965)
		(end 119.324036 88.643964)
		(width 0.16)
		(layer "In3.Cu")
		(net 50)
	)
	(segment
		(start 108.781835 79.642553)
		(end 108.447446 79.308164)
		(width 0.16)
		(layer "In3.Cu")
		(net 50)
	)
	(segment
		(start 122.02615 87.769)
		(end 121.95385 87.769)
		(width 0.16)
		(layer "In3.Cu")
		(net 50)
	)
	(segment
		(start 121.487454 88.049)
		(end 121.24385 88.049)
		(width 0.16)
		(layer "In3.Cu")
		(net 50)
	)
	(segment
		(start 105.866835 77.402553)
		(end 105.765794 77.301512)
		(width 0.16)
		(layer "In3.Cu")
		(net 50)
	)
	(segment
		(start 112.718487 80.639205)
		(end 111.970794 79.891512)
		(width 0.16)
		(layer "In3.Cu")
		(net 50)
	)
	(segment
		(start 94.821835 77.722553)
		(end 94.550794 77.451512)
		(width 0.16)
		(layer "In3.Cu")
		(net 50)
	)
	(segment
		(start 119.149072 88.469)
		(end 119.149 88.469)
		(width 0.16)
		(layer "In3.Cu")
		(net 50)
	)
	(segment
		(start 121.68 88.453)
		(end 121.784066 88.557066)
		(width 0.16)
		(layer "In3.Cu")
		(net 50)
	)
	(segment
		(start 120.637454 88.469)
		(end 119.849 88.469)
		(width 0.16)
		(layer "In3.Cu")
		(net 50)
	)
	(segment
		(start 121.137784 88.092934)
		(end 120.849586 88.381132)
		(width 0.16)
		(layer "In3.Cu")
		(net 50)
	)
	(segment
		(start 92.748 77.349)
		(end 92.6 77.497)
		(width 0.16)
		(layer "In3.Cu")
		(net 50)
	)
	(segment
		(start 119.499072 88.818929)
		(end 119.499 88.818929)
		(width 0.16)
		(layer "In3.Cu")
		(net 50)
	)
	(segment
		(start 94.303307 77.349)
		(end 92.748 77.349)
		(width 0.16)
		(layer "In3.Cu")
		(net 50)
	)
	(segment
		(start 121.890132 88.601)
		(end 122.00615 88.601)
		(width 0.16)
		(layer "In3.Cu")
		(net 50)
	)
	(segment
		(start 122.277066 87.957784)
		(end 122.132216 87.812934)
		(width 0.16)
		(layer "In3.Cu")
		(net 50)
	)
	(segment
		(start 119.149 88.469)
		(end 118.040389 88.469)
		(width 0.16)
		(layer "In3.Cu")
		(net 50)
	)
	(arc
		(start 103.826693 77.199)
		(mid 103.692753 77.225642)
		(end 103.579205 77.301513)
		(width 0.16)
		(layer "In3.Cu")
		(net 50)
	)
	(arc
		(start 122.132216 87.812934)
		(mid 122.083553 87.780418)
		(end 122.02615 87.769)
		(width 0.16)
		(layer "In3.Cu")
		(net 50)
	)
	(arc
		(start 108.198487 77.834205)
		(mid 108.274358 77.947753)
		(end 108.301 78.081693)
		(width 0.16)
		(layer "In3.Cu")
		(net 50)
	)
	(arc
		(start 121.699586 87.961132)
		(mid 121.602259 88.026164)
		(end 121.487454 88.049)
		(width 0.16)
		(layer "In3.Cu")
		(net 50)
	)
	(arc
		(start 119.499 88.818929)
		(mid 119.375282 88.767683)
		(end 119.324036 88.643965)
		(width 0.16)
		(layer "In3.Cu")
		(net 50)
	)
	(arc
		(start 121.24385 88.049)
		(mid 121.186447 88.060418)
		(end 121.137784 88.092934)
		(width 0.16)
		(layer "In3.Cu")
		(net 50)
	)
	(arc
		(start 112.821 80.886693)
		(mid 112.794358 80.752753)
		(end 112.718487 80.639205)
		(width 0.16)
		(layer "In3.Cu")
		(net 50)
	)
	(arc
		(start 111.970794 79.891512)
		(mid 111.857246 79.815642)
		(end 111.723307 79.789)
		(width 0.16)
		(layer "In3.Cu")
		(net 50)
	)
	(arc
		(start 94.821835 77.722553)
		(mid 94.984047 77.83094)
		(end 95.175389 77.869)
		(width 0.16)
		(layer "In3.Cu")
		(net 50)
	)
	(arc
		(start 121.95385 87.769)
		(mid 121.896447 87.780418)
		(end 121.847784 87.812934)
		(width 0.16)
		(layer "In3.Cu")
		(net 50)
	)
	(arc
		(start 119.674036 88.643965)
		(mid 119.62279 88.767683)
		(end 119.499072 88.818929)
		(width 0.16)
		(layer "In3.Cu")
		(net 50)
	)
	(arc
		(start 112.821 83.249611)
		(mid 112.85906 83.440952)
		(end 112.967446 83.603164)
		(width 0.16)
		(layer "In3.Cu")
		(net 50)
	)
	(arc
		(start 103.158164 77.722554)
		(mid 102.995952 77.83094)
		(end 102.804611 77.869)
		(width 0.16)
		(layer "In3.Cu")
		(net 50)
	)
	(arc
		(start 121.784066 88.557066)
		(mid 121.832729 88.589582)
		(end 121.890132 88.601)
		(width 0.16)
		(layer "In3.Cu")
		(net 50)
	)
	(arc
		(start 108.447446 79.308164)
		(mid 108.33906 79.145952)
		(end 108.301 78.954611)
		(width 0.16)
		(layer "In3.Cu")
		(net 50)
	)
	(arc
		(start 119.849 88.469)
		(mid 119.725282 88.520246)
		(end 119.674036 88.643964)
		(width 0.16)
		(layer "In3.Cu")
		(net 50)
	)
	(arc
		(start 118.040389 88.469)
		(mid 117.849047 88.43094)
		(end 117.686835 88.322553)
		(width 0.16)
		(layer "In3.Cu")
		(net 50)
	)
	(arc
		(start 122.321 88.06385)
		(mid 122.309582 88.006447)
		(end 122.277066 87.957784)
		(width 0.16)
		(layer "In3.Cu")
		(net 50)
	)
	(arc
		(start 108.781835 79.642553)
		(mid 108.944047 79.75094)
		(end 109.135389 79.789)
		(width 0.16)
		(layer "In3.Cu")
		(net 50)
	)
	(arc
		(start 94.550794 77.451512)
		(mid 94.437246 77.375642)
		(end 94.303307 77.349)
		(width 0.16)
		(layer "In3.Cu")
		(net 50)
	)
	(arc
		(start 106.220389 77.549)
		(mid 106.029047 77.51094)
		(end 105.866835 77.402553)
		(width 0.16)
		(layer "In3.Cu")
		(net 50)
	)
	(arc
		(start 122.00615 88.601)
		(mid 122.063553 88.589582)
		(end 122.112216 88.557066)
		(width 0.16)
		(layer "In3.Cu")
		(net 50)
	)
	(arc
		(start 120.849586 88.381132)
		(mid 120.752259 88.446164)
		(end 120.637454 88.469)
		(width 0.16)
		(layer "In3.Cu")
		(net 50)
	)
	(arc
		(start 122.277066 88.392216)
		(mid 122.309582 88.343553)
		(end 122.321 88.28615)
		(width 0.16)
		(layer "In3.Cu")
		(net 50)
	)
	(arc
		(start 107.768307 77.549)
		(mid 107.902246 77.575642)
		(end 108.015794 77.651512)
		(width 0.16)
		(layer "In3.Cu")
		(net 50)
	)
	(arc
		(start 119.324036 88.643964)
		(mid 119.27279 88.520246)
		(end 119.149072 88.469)
		(width 0.16)
		(layer "In3.Cu")
		(net 50)
	)
	(arc
		(start 105.518307 77.199)
		(mid 105.652246 77.225642)
		(end 105.765794 77.301512)
		(width 0.16)
		(layer "In3.Cu")
		(net 50)
	)
	(segment
		(start 124.275 88.5)
		(end 123.174631 88.5)
		(width 0.155)
		(layer "B.Cu")
		(net 50)
	)
	(segment
		(start 121.783566 88.556566)
		(end 121.68 88.453)
		(width 0.155)
		(layer "B.Cu")
		(net 50)
	)
	(segment
		(start 122.949867 88.6005)
		(end 121.889632 88.6005)
		(width 0.155)
		(layer "B.Cu")
		(net 50)
	)
	(segment
		(start 123.068565 88.543934)
		(end 123.055933 88.556566)
		(width 0.155)
		(layer "B.Cu")
		(net 50)
	)
	(arc
		(start 123.174631 88.5)
		(mid 123.117228 88.511418)
		(end 123.068565 88.543934)
		(width 0.155)
		(layer "B.Cu")
		(net 50)
	)
	(arc
		(start 121.783566 88.556566)
		(mid 121.832229 88.589082)
		(end 121.889632 88.6005)
		(width 0.155)
		(layer "B.Cu")
		(net 50)
	)
	(arc
		(start 122.949867 88.6005)
		(mid 123.00727 88.589082)
		(end 123.055933 88.556566)
		(width 0.155)
		(layer "B.Cu")
		(net 50)
	)
	(segment
		(start 87.209413 70.302013)
		(end 87.099335 70.412091)
		(width 0.155)
		(layer "F.Cu")
		(net 51)
	)
	(segment
		(start 89.4505 72.018368)
		(end 89.4505 71.306901)
		(width 0.155)
		(layer "F.Cu")
		(net 51)
	)
	(segment
		(start 86.996823 71.179636)
		(end 87.097323 71.280136)
		(width 0.155)
		(layer "F.Cu")
		(net 51)
	)
	(segment
		(start 86.996823 70.659578)
		(end 86.996823 71.179636)
		(width 0.155)
		(layer "F.Cu")
		(net 51)
	)
	(segment
		(start 89.347987 71.059413)
		(end 88.590586 70.302012)
		(width 0.155)
		(layer "F.Cu")
		(net 51)
	)
	(segment
		(start 88.343099 70.1995)
		(end 87.456901 70.1995)
		(width 0.155)
		(layer "F.Cu")
		(net 51)
	)
	(segment
		(start 89.306 72.225)
		(end 89.406566 72.124434)
		(width 0.155)
		(layer "F.Cu")
		(net 51)
	)
	(via
		(at 89.306 72.225)
		(size 0.45)
		(drill 0.1)
		(layers "F.Cu" "B.Cu")
		(net 51)
	)
	(via
		(at 121.2 92.0375)
		(size 0.45)
		(drill 0.1)
		(layers "F.Cu" "B.Cu")
		(net 51)
	)
	(arc
		(start 88.590586 70.302012)
		(mid 88.477038 70.226142)
		(end 88.343099 70.1995)
		(width 0.155)
		(layer "F.Cu")
		(net 51)
	)
	(arc
		(start 87.209413 70.302013)
		(mid 87.322961 70.226142)
		(end 87.456901 70.1995)
		(width 0.155)
		(layer "F.Cu")
		(net 51)
	)
	(arc
		(start 87.099335 70.412091)
		(mid 87.023465 70.525639)
		(end 86.996823 70.659578)
		(width 0.155)
		(layer "F.Cu")
		(net 51)
	)
	(arc
		(start 89.4505 72.018368)
		(mid 89.439082 72.075771)
		(end 89.406566 72.124434)
		(width 0.155)
		(layer "F.Cu")
		(net 51)
	)
	(arc
		(start 89.4505 71.306901)
		(mid 89.423858 71.172961)
		(end 89.347987 71.059413)
		(width 0.155)
		(layer "F.Cu")
		(net 51)
	)
	(segment
		(start 89.451 73.829)
		(end 89.451 75.893307)
		(width 0.16)
		(layer "In3.Cu")
		(net 51)
	)
	(segment
		(start 89.348488 76.140794)
		(end 88.797447 76.691835)
		(width 0.16)
		(layer "In3.Cu")
		(net 51)
	)
	(segment
		(start 106.690795 79.751513)
		(end 118.691836 91.752554)
		(width 0.16)
		(layer "In3.Cu")
		(net 51)
	)
	(segment
		(start 89.251 73.229)
		(end 89.230788 73.229)
		(width 0.16)
		(layer "In3.Cu")
		(net 51)
	)
	(segment
		(start 90.091836 79.502554)
		(end 88.797446 78.208164)
		(width 0.16)
		(layer "In3.Cu")
		(net 51)
	)
	(segment
		(start 89.451 72.37)
		(end 89.451 73.029)
		(width 0.16)
		(layer "In3.Cu")
		(net 51)
	)
	(segment
		(start 89.230788 73.629)
		(end 89.251 73.629)
		(width 0.16)
		(layer "In3.Cu")
		(net 51)
	)
	(segment
		(start 119.045389 91.899)
		(end 120.999368 91.899)
		(width 0.16)
		(layer "In3.Cu")
		(net 51)
	)
	(segment
		(start 90.445389 79.649)
		(end 106.443307 79.649)
		(width 0.16)
		(layer "In3.Cu")
		(net 51)
	)
	(segment
		(start 88.651 77.045389)
		(end 88.651 77.854611)
		(width 0.16)
		(layer "In3.Cu")
		(net 51)
	)
	(segment
		(start 121.105434 91.942934)
		(end 121.2 92.0375)
		(width 0.16)
		(layer "In3.Cu")
		(net 51)
	)
	(segment
		(start 89.306 72.225)
		(end 89.451 72.37)
		(width 0.16)
		(layer "In3.Cu")
		(net 51)
	)
	(arc
		(start 88.797447 76.691835)
		(mid 88.68906 76.854047)
		(end 88.651 77.045389)
		(width 0.16)
		(layer "In3.Cu")
		(net 51)
	)
	(arc
		(start 88.651 77.854611)
		(mid 88.68906 78.045952)
		(end 88.797446 78.208164)
		(width 0.16)
		(layer "In3.Cu")
		(net 51)
	)
	(arc
		(start 89.451 75.893307)
		(mid 89.424358 76.027246)
		(end 89.348488 76.140794)
		(width 0.16)
		(layer "In3.Cu")
		(net 51)
	)
	(arc
		(start 106.690795 79.751513)
		(mid 106.577247 79.675642)
		(end 106.443307 79.649)
		(width 0.16)
		(layer "In3.Cu")
		(net 51)
	)
	(arc
		(start 120.999368 91.899)
		(mid 121.056771 91.910418)
		(end 121.105434 91.942934)
		(width 0.16)
		(layer "In3.Cu")
		(net 51)
	)
	(arc
		(start 90.445389 79.649)
		(mid 90.254048 79.61094)
		(end 90.091836 79.502554)
		(width 0.16)
		(layer "In3.Cu")
		(net 51)
	)
	(arc
		(start 89.230788 73.229)
		(mid 89.089367 73.287579)
		(end 89.030788 73.429)
		(width 0.16)
		(layer "In3.Cu")
		(net 51)
	)
	(arc
		(start 89.451 73.029)
		(mid 89.392421 73.170421)
		(end 89.251 73.229)
		(width 0.16)
		(layer "In3.Cu")
		(net 51)
	)
	(arc
		(start 89.251 73.629)
		(mid 89.392421 73.687579)
		(end 89.451 73.829)
		(width 0.16)
		(layer "In3.Cu")
		(net 51)
	)
	(arc
		(start 89.030788 73.429)
		(mid 89.089367 73.570421)
		(end 89.230788 73.629)
		(width 0.16)
		(layer "In3.Cu")
		(net 51)
	)
	(arc
		(start 118.691836 91.752554)
		(mid 118.854048 91.86094)
		(end 119.045389 91.899)
		(width 0.16)
		(layer "In3.Cu")
		(net 51)
	)
	(segment
		(start 121.298566 91.938934)
		(end 121.2 92.0375)
		(width 0.155)
		(layer "B.Cu")
		(net 51)
	)
	(segment
		(start 124.3 92)
		(end 123.199631 92)
		(width 0.155)
		(layer "B.Cu")
		(net 51)
	)
	(segment
		(start 122.970367 91.895)
		(end 121.404632 91.895)
		(width 0.155)
		(layer "B.Cu")
		(net 51)
	)
	(segment
		(start 123.093565 91.956066)
		(end 123.076433 91.938934)
		(width 0.155)
		(layer "B.Cu")
		(net 51)
	)
	(arc
		(start 123.199631 92)
		(mid 123.142228 91.988582)
		(end 123.093565 91.956066)
		(width 0.155)
		(layer "B.Cu")
		(net 51)
	)
	(arc
		(start 121.298566 91.938934)
		(mid 121.347229 91.906418)
		(end 121.404632 91.895)
		(width 0.155)
		(layer "B.Cu")
		(net 51)
	)
	(arc
		(start 122.970367 91.895)
		(mid 123.02777 91.906418)
		(end 123.076433 91.938934)
		(width 0.155)
		(layer "B.Cu")
		(net 51)
	)
	(segment
		(start 86.697823 70.597858)
		(end 86.697823 71.179636)
		(width 0.155)
		(layer "F.Cu")
		(net 52)
	)
	(segment
		(start 86.697823 71.179636)
		(end 86.597323 71.280136)
		(width 0.155)
		(layer "F.Cu")
		(net 52)
	)
	(segment
		(start 89.7495 71.973368)
		(end 89.7495 71.245181)
		(width 0.155)
		(layer "F.Cu")
		(net 52)
	)
	(segment
		(start 88.404819 69.9005)
		(end 87.395181 69.9005)
		(width 0.155)
		(layer "F.Cu")
		(net 52)
	)
	(segment
		(start 89.603053 70.891627)
		(end 88.758372 70.046946)
		(width 0.155)
		(layer "F.Cu")
		(net 52)
	)
	(segment
		(start 89.894 72.18)
		(end 89.793434 72.079434)
		(width 0.155)
		(layer "F.Cu")
		(net 52)
	)
	(segment
		(start 87.041627 70.046947)
		(end 86.844269 70.244305)
		(width 0.155)
		(layer "F.Cu")
		(net 52)
	)
	(via
		(at 121.2 91.4625)
		(size 0.45)
		(drill 0.1)
		(layers "F.Cu" "B.Cu")
		(net 52)
	)
	(via
		(at 89.894 72.18)
		(size 0.45)
		(drill 0.1)
		(layers "F.Cu" "B.Cu")
		(net 52)
	)
	(arc
		(start 86.697823 70.597858)
		(mid 86.735883 70.406517)
		(end 86.844269 70.244305)
		(width 0.155)
		(layer "F.Cu")
		(net 52)
	)
	(arc
		(start 89.7495 71.973368)
		(mid 89.760918 72.030771)
		(end 89.793434 72.079434)
		(width 0.155)
		(layer "F.Cu")
		(net 52)
	)
	(arc
		(start 87.395181 69.9005)
		(mid 87.203839 69.93856)
		(end 87.041627 70.046947)
		(width 0.155)
		(layer "F.Cu")
		(net 52)
	)
	(arc
		(start 89.7495 71.245181)
		(mid 89.71144 71.053839)
		(end 89.603053 70.891627)
		(width 0.155)
		(layer "F.Cu")
		(net 52)
	)
	(arc
		(start 88.404819 69.9005)
		(mid 88.59616 69.93856)
		(end 88.758372 70.046946)
		(width 0.155)
		(layer "F.Cu")
		(net 52)
	)
	(segment
		(start 106.858165 79.497447)
		(end 118.859206 91.498488)
		(width 0.16)
		(layer "In3.Cu")
		(net 52)
	)
	(segment
		(start 89.749 72.325)
		(end 89.749 75.954611)
		(width 0.16)
		(layer "In3.Cu")
		(net 52)
	)
	(segment
		(start 89.051513 78.040795)
		(end 90.139206 79.128488)
		(width 0.16)
		(layer "In3.Cu")
		(net 52)
	)
	(segment
		(start 90.139206 79.128488)
		(end 90.259206 79.248488)
		(width 0.16)
		(layer "In3.Cu")
		(net 52)
	)
	(segment
		(start 90.506693 79.351)
		(end 106.504611 79.351)
		(width 0.16)
		(layer "In3.Cu")
		(net 52)
	)
	(segment
		(start 88.949 77.106693)
		(end 88.949 77.793307)
		(width 0.16)
		(layer "In3.Cu")
		(net 52)
	)
	(segment
		(start 121.105434 91.557066)
		(end 121.2 91.4625)
		(width 0.16)
		(layer "In3.Cu")
		(net 52)
	)
	(segment
		(start 89.894 72.18)
		(end 89.749 72.325)
		(width 0.16)
		(layer "In3.Cu")
		(net 52)
	)
	(segment
		(start 89.602553 76.308165)
		(end 89.051512 76.859206)
		(width 0.16)
		(layer "In3.Cu")
		(net 52)
	)
	(segment
		(start 119.106693 91.601)
		(end 120.999368 91.601)
		(width 0.16)
		(layer "In3.Cu")
		(net 52)
	)
	(arc
		(start 90.506693 79.351)
		(mid 90.372754 79.324358)
		(end 90.259206 79.248488)
		(width 0.16)
		(layer "In3.Cu")
		(net 52)
	)
	(arc
		(start 120.999368 91.601)
		(mid 121.056771 91.589582)
		(end 121.105434 91.557066)
		(width 0.16)
		(layer "In3.Cu")
		(net 52)
	)
	(arc
		(start 118.859206 91.498488)
		(mid 118.972754 91.574358)
		(end 119.106693 91.601)
		(width 0.16)
		(layer "In3.Cu")
		(net 52)
	)
	(arc
		(start 88.949 77.793307)
		(mid 88.975642 77.927247)
		(end 89.051513 78.040795)
		(width 0.16)
		(layer "In3.Cu")
		(net 52)
	)
	(arc
		(start 89.749 75.954611)
		(mid 89.71094 76.145953)
		(end 89.602553 76.308165)
		(width 0.16)
		(layer "In3.Cu")
		(net 52)
	)
	(arc
		(start 106.504611 79.351)
		(mid 106.695953 79.38906)
		(end 106.858165 79.497447)
		(width 0.16)
		(layer "In3.Cu")
		(net 52)
	)
	(arc
		(start 89.051512 76.859206)
		(mid 88.975642 76.972754)
		(end 88.949 77.106693)
		(width 0.16)
		(layer "In3.Cu")
		(net 52)
	)
	(segment
		(start 121.298566 91.561066)
		(end 121.2 91.4625)
		(width 0.155)
		(layer "B.Cu")
		(net 52)
	)
	(segment
		(start 122.970367 91.605)
		(end 121.404632 91.605)
		(width 0.155)
		(layer "B.Cu")
		(net 52)
	)
	(segment
		(start 123.093565 91.543934)
		(end 123.076433 91.561066)
		(width 0.155)
		(layer "B.Cu")
		(net 52)
	)
	(segment
		(start 124.3 91.5)
		(end 123.199631 91.5)
		(width 0.155)
		(layer "B.Cu")
		(net 52)
	)
	(arc
		(start 121.298566 91.561066)
		(mid 121.347229 91.593582)
		(end 121.404632 91.605)
		(width 0.155)
		(layer "B.Cu")
		(net 52)
	)
	(arc
		(start 122.970367 91.605)
		(mid 123.02777 91.593582)
		(end 123.076433 91.561066)
		(width 0.155)
		(layer "B.Cu")
		(net 52)
	)
	(arc
		(start 123.093565 91.543934)
		(mid 123.142228 91.511418)
		(end 123.199631 91.5)
		(width 0.155)
		(layer "B.Cu")
		(net 52)
	)
	(segment
		(start 85.454819 75.1495)
		(end 84.609632 75.1495)
		(width 0.155)
		(layer "F.Cu")
		(net 53)
	)
	(segment
		(start 84.503566 75.193434)
		(end 84.4 75.297)
		(width 0.155)
		(layer "F.Cu")
		(net 53)
	)
	(segment
		(start 86.1495 73.945181)
		(end 86.1495 74.454819)
		(width 0.155)
		(layer "F.Cu")
		(net 53)
	)
	(segment
		(start 86.003053 74.808373)
		(end 85.808372 75.003054)
		(width 0.155)
		(layer "F.Cu")
		(net 53)
	)
	(segment
		(start 85.599336 73.18791)
		(end 86.003054 73.591628)
		(width 0.155)
		(layer "F.Cu")
		(net 53)
	)
	(segment
		(start 85.496823 72.830636)
		(end 85.496823 72.940422)
		(width 0.155)
		(layer "F.Cu")
		(net 53)
	)
	(segment
		(start 85.597323 72.730136)
		(end 85.496823 72.830636)
		(width 0.155)
		(layer "F.Cu")
		(net 53)
	)
	(via
		(at 121.2 95.1)
		(size 0.45)
		(drill 0.1)
		(layers "F.Cu" "B.Cu")
		(net 53)
	)
	(via
		(at 84.4 75.297)
		(size 0.45)
		(drill 0.1)
		(layers "F.Cu" "B.Cu")
		(net 53)
	)
	(arc
		(start 85.454819 75.1495)
		(mid 85.64616 75.11144)
		(end 85.808372 75.003054)
		(width 0.155)
		(layer "F.Cu")
		(net 53)
	)
	(arc
		(start 86.1495 73.945181)
		(mid 86.11144 73.75384)
		(end 86.003054 73.591628)
		(width 0.155)
		(layer "F.Cu")
		(net 53)
	)
	(arc
		(start 84.609632 75.1495)
		(mid 84.552229 75.160918)
		(end 84.503566 75.193434)
		(width 0.155)
		(layer "F.Cu")
		(net 53)
	)
	(arc
		(start 85.599336 73.18791)
		(mid 85.523465 73.074362)
		(end 85.496823 72.940422)
		(width 0.155)
		(layer "F.Cu")
		(net 53)
	)
	(arc
		(start 86.1495 74.454819)
		(mid 86.11144 74.646161)
		(end 86.003053 74.808373)
		(width 0.155)
		(layer "F.Cu")
		(net 53)
	)
	(segment
		(start 82.195389 75.751)
		(end 83.687454 75.751)
		(width 0.16)
		(layer "In3.Cu")
		(net 53)
	)
	(segment
		(start 105.693307 80.799)
		(end 82.395389 80.799)
		(width 0.16)
		(layer "In3.Cu")
		(net 53)
	)
	(segment
		(start 120.936868 94.899)
		(end 118.895389 94.899)
		(width 0.16)
		(layer "In3.Cu")
		(net 53)
	)
	(segment
		(start 118.541835 94.752553)
		(end 117.647446 93.858164)
		(width 0.16)
		(layer "In3.Cu")
		(net 53)
	)
	(segment
		(start 82.041835 80.652553)
		(end 81.147446 79.758164)
		(width 0.16)
		(layer "In3.Cu")
		(net 53)
	)
	(segment
		(start 121.2 95.1)
		(end 121.042934 94.942934)
		(width 0.16)
		(layer "In3.Cu")
		(net 53)
	)
	(segment
		(start 83.899586 75.838868)
		(end 84.017784 75.957066)
		(width 0.16)
		(layer "In3.Cu")
		(net 53)
	)
	(segment
		(start 84.632216 75.957066)
		(end 84.807066 75.782216)
		(width 0.16)
		(layer "In3.Cu")
		(net 53)
	)
	(segment
		(start 117.501 93.504611)
		(end 117.501 92.606693)
		(width 0.16)
		(layer "In3.Cu")
		(net 53)
	)
	(segment
		(start 84.548 75.149)
		(end 84.4 75.297)
		(width 0.16)
		(layer "In3.Cu")
		(net 53)
	)
	(segment
		(start 84.851 75.67615)
		(end 84.851 75.42385)
		(width 0.16)
		(layer "In3.Cu")
		(net 53)
	)
	(segment
		(start 81.147447 76.591835)
		(end 81.841836 75.897446)
		(width 0.16)
		(layer "In3.Cu")
		(net 53)
	)
	(segment
		(start 84.807066 75.317784)
		(end 84.682216 75.192934)
		(width 0.16)
		(layer "In3.Cu")
		(net 53)
	)
	(segment
		(start 81.001 79.404611)
		(end 81.001 76.945389)
		(width 0.16)
		(layer "In3.Cu")
		(net 53)
	)
	(segment
		(start 84.57615 75.149)
		(end 84.548 75.149)
		(width 0.16)
		(layer "In3.Cu")
		(net 53)
	)
	(segment
		(start 84.12385 76.001)
		(end 84.52615 76.001)
		(width 0.16)
		(layer "In3.Cu")
		(net 53)
	)
	(segment
		(start 117.398487 92.359205)
		(end 105.940794 80.901512)
		(width 0.16)
		(layer "In3.Cu")
		(net 53)
	)
	(arc
		(start 82.195389 75.751)
		(mid 82.004048 75.78906)
		(end 81.841836 75.897446)
		(width 0.16)
		(layer "In3.Cu")
		(net 53)
	)
	(arc
		(start 83.687454 75.751)
		(mid 83.802259 75.773836)
		(end 83.899586 75.838868)
		(width 0.16)
		(layer "In3.Cu")
		(net 53)
	)
	(arc
		(start 84.851 75.42385)
		(mid 84.839582 75.366447)
		(end 84.807066 75.317784)
		(width 0.16)
		(layer "In3.Cu")
		(net 53)
	)
	(arc
		(start 84.632216 75.957066)
		(mid 84.583553 75.989582)
		(end 84.52615 76.001)
		(width 0.16)
		(layer "In3.Cu")
		(net 53)
	)
	(arc
		(start 118.895389 94.899)
		(mid 118.704047 94.86094)
		(end 118.541835 94.752553)
		(width 0.16)
		(layer "In3.Cu")
		(net 53)
	)
	(arc
		(start 84.682216 75.192934)
		(mid 84.633553 75.160418)
		(end 84.57615 75.149)
		(width 0.16)
		(layer "In3.Cu")
		(net 53)
	)
	(arc
		(start 81.147447 76.591835)
		(mid 81.03906 76.754047)
		(end 81.001 76.945389)
		(width 0.16)
		(layer "In3.Cu")
		(net 53)
	)
	(arc
		(start 117.647446 93.858164)
		(mid 117.53906 93.695952)
		(end 117.501 93.504611)
		(width 0.16)
		(layer "In3.Cu")
		(net 53)
	)
	(arc
		(start 105.693307 80.799)
		(mid 105.827246 80.825642)
		(end 105.940794 80.901512)
		(width 0.16)
		(layer "In3.Cu")
		(net 53)
	)
	(arc
		(start 82.395389 80.799)
		(mid 82.204047 80.76094)
		(end 82.041835 80.652553)
		(width 0.16)
		(layer "In3.Cu")
		(net 53)
	)
	(arc
		(start 81.147446 79.758164)
		(mid 81.03906 79.595952)
		(end 81.001 79.404611)
		(width 0.16)
		(layer "In3.Cu")
		(net 53)
	)
	(arc
		(start 84.807066 75.782216)
		(mid 84.839582 75.733553)
		(end 84.851 75.67615)
		(width 0.16)
		(layer "In3.Cu")
		(net 53)
	)
	(arc
		(start 84.017784 75.957066)
		(mid 84.066447 75.989582)
		(end 84.12385 76.001)
		(width 0.16)
		(layer "In3.Cu")
		(net 53)
	)
	(arc
		(start 117.501 92.606693)
		(mid 117.474358 92.472753)
		(end 117.398487 92.359205)
		(width 0.16)
		(layer "In3.Cu")
		(net 53)
	)
	(arc
		(start 120.936868 94.899)
		(mid 120.994271 94.910418)
		(end 121.042934 94.942934)
		(width 0.16)
		(layer "In3.Cu")
		(net 53)
	)
	(segment
		(start 124.3 95)
		(end 123.137499 95)
		(width 0.155)
		(layer "B.Cu")
		(net 53)
	)
	(segment
		(start 123.137499 95)
		(end 123.112499 94.975)
		(width 0.155)
		(layer "B.Cu")
		(net 53)
	)
	(segment
		(start 123.112499 94.975)
		(end 121.387131 94.975001)
		(width 0.155)
		(layer "B.Cu")
		(net 53)
	)
	(segment
		(start 121.281065 95.018935)
		(end 121.2 95.1)
		(width 0.155)
		(layer "B.Cu")
		(net 53)
	)
	(arc
		(start 121.387131 94.975001)
		(mid 121.329728 94.986419)
		(end 121.281065 95.018935)
		(width 0.155)
		(layer "B.Cu")
		(net 53)
	)
	(segment
		(start 85.747987 74.640587)
		(end 85.640586 74.747988)
		(width 0.155)
		(layer "F.Cu")
		(net 54)
	)
	(segment
		(start 85.197823 72.830636)
		(end 85.197823 73.002142)
		(width 0.155)
		(layer "F.Cu")
		(net 54)
	)
	(segment
		(start 85.097323 72.730136)
		(end 85.197823 72.830636)
		(width 0.155)
		(layer "F.Cu")
		(net 54)
	)
	(segment
		(start 85.8505 74.006901)
		(end 85.8505 74.393099)
		(width 0.155)
		(layer "F.Cu")
		(net 54)
	)
	(segment
		(start 85.34427 73.355696)
		(end 85.747988 73.759414)
		(width 0.155)
		(layer "F.Cu")
		(net 54)
	)
	(segment
		(start 85.393099 74.8505)
		(end 84.609632 74.8505)
		(width 0.155)
		(layer "F.Cu")
		(net 54)
	)
	(segment
		(start 84.503566 74.806566)
		(end 84.4 74.703)
		(width 0.155)
		(layer "F.Cu")
		(net 54)
	)
	(via
		(at 84.4 74.703)
		(size 0.45)
		(drill 0.1)
		(layers "F.Cu" "B.Cu")
		(net 54)
	)
	(via
		(at 121.2 94.4)
		(size 0.45)
		(drill 0.1)
		(layers "F.Cu" "B.Cu")
		(net 54)
	)
	(arc
		(start 85.640586 74.747988)
		(mid 85.527038 74.823858)
		(end 85.393099 74.8505)
		(width 0.155)
		(layer "F.Cu")
		(net 54)
	)
	(arc
		(start 84.609632 74.8505)
		(mid 84.552229 74.839082)
		(end 84.503566 74.806566)
		(width 0.155)
		(layer "F.Cu")
		(net 54)
	)
	(arc
		(start 85.197823 73.002142)
		(mid 85.235883 73.193484)
		(end 85.34427 73.355696)
		(width 0.155)
		(layer "F.Cu")
		(net 54)
	)
	(arc
		(start 85.8505 74.006901)
		(mid 85.823858 73.872962)
		(end 85.747988 73.759414)
		(width 0.155)
		(layer "F.Cu")
		(net 54)
	)
	(arc
		(start 85.747987 74.640587)
		(mid 85.823858 74.527039)
		(end 85.8505 74.393099)
		(width 0.155)
		(layer "F.Cu")
		(net 54)
	)
	(segment
		(start 121.042934 94.557066)
		(end 121.2 94.4)
		(width 0.16)
		(layer "In3.Cu")
		(net 54)
	)
	(segment
		(start 117.799 92.545389)
		(end 117.799 93.443307)
		(width 0.16)
		(layer "In3.Cu")
		(net 54)
	)
	(segment
		(start 117.901513 93.690795)
		(end 118.709206 94.498488)
		(width 0.16)
		(layer "In3.Cu")
		(net 54)
	)
	(segment
		(start 83.62615 76.049)
		(end 82.256693 76.049)
		(width 0.16)
		(layer "In3.Cu")
		(net 54)
	)
	(segment
		(start 84.587454 76.299)
		(end 84.062546 76.299)
		(width 0.16)
		(layer "In3.Cu")
		(net 54)
	)
	(segment
		(start 81.299 79.343307)
		(end 81.299 78.591)
		(width 0.16)
		(layer "In3.Cu")
		(net 54)
	)
	(segment
		(start 84.849586 74.938868)
		(end 85.061132 75.150414)
		(width 0.16)
		(layer "In3.Cu")
		(net 54)
	)
	(segment
		(start 81.499 77.991)
		(end 81.518382 77.991)
		(width 0.16)
		(layer "In3.Cu")
		(net 54)
	)
	(segment
		(start 82.009205 76.151513)
		(end 81.401512 76.759206)
		(width 0.16)
		(layer "In3.Cu")
		(net 54)
	)
	(segment
		(start 85.149 75.362546)
		(end 85.149 75.737454)
		(width 0.16)
		(layer "In3.Cu")
		(net 54)
	)
	(segment
		(start 85.061132 75.949586)
		(end 84.799586 76.211132)
		(width 0.16)
		(layer "In3.Cu")
		(net 54)
	)
	(segment
		(start 83.850414 76.211132)
		(end 83.732216 76.092934)
		(width 0.16)
		(layer "In3.Cu")
		(net 54)
	)
	(segment
		(start 81.518382 78.391)
		(end 81.499 78.391)
		(width 0.16)
		(layer "In3.Cu")
		(net 54)
	)
	(segment
		(start 81.299 77.006693)
		(end 81.299 77.791)
		(width 0.16)
		(layer "In3.Cu")
		(net 54)
	)
	(segment
		(start 106.108165 80.647447)
		(end 117.652554 92.191836)
		(width 0.16)
		(layer "In3.Cu")
		(net 54)
	)
	(segment
		(start 82.456693 80.501)
		(end 105.754611 80.501)
		(width 0.16)
		(layer "In3.Cu")
		(net 54)
	)
	(segment
		(start 118.956693 94.601)
		(end 120.936868 94.601)
		(width 0.16)
		(layer "In3.Cu")
		(net 54)
	)
	(segment
		(start 84.4 74.703)
		(end 84.504066 74.807066)
		(width 0.16)
		(layer "In3.Cu")
		(net 54)
	)
	(segment
		(start 81.401513 79.590795)
		(end 82.209206 80.398488)
		(width 0.16)
		(layer "In3.Cu")
		(net 54)
	)
	(segment
		(start 84.610132 74.851)
		(end 84.637454 74.851)
		(width 0.16)
		(layer "In3.Cu")
		(net 54)
	)
	(arc
		(start 118.709206 94.498488)
		(mid 118.822754 94.574358)
		(end 118.956693 94.601)
		(width 0.16)
		(layer "In3.Cu")
		(net 54)
	)
	(arc
		(start 81.518382 77.991)
		(mid 81.659803 78.049579)
		(end 81.718382 78.191)
		(width 0.16)
		(layer "In3.Cu")
		(net 54)
	)
	(arc
		(start 81.401512 76.759206)
		(mid 81.325642 76.872754)
		(end 81.299 77.006693)
		(width 0.16)
		(layer "In3.Cu")
		(net 54)
	)
	(arc
		(start 85.061132 75.150414)
		(mid 85.126164 75.247741)
		(end 85.149 75.362546)
		(width 0.16)
		(layer "In3.Cu")
		(net 54)
	)
	(arc
		(start 84.504066 74.807066)
		(mid 84.552729 74.839582)
		(end 84.610132 74.851)
		(width 0.16)
		(layer "In3.Cu")
		(net 54)
	)
	(arc
		(start 85.149 75.737454)
		(mid 85.126164 75.852259)
		(end 85.061132 75.949586)
		(width 0.16)
		(layer "In3.Cu")
		(net 54)
	)
	(arc
		(start 82.256693 76.049)
		(mid 82.122753 76.075642)
		(end 82.009205 76.151513)
		(width 0.16)
		(layer "In3.Cu")
		(net 54)
	)
	(arc
		(start 83.62615 76.049)
		(mid 83.683553 76.060418)
		(end 83.732216 76.092934)
		(width 0.16)
		(layer "In3.Cu")
		(net 54)
	)
	(arc
		(start 84.587454 76.299)
		(mid 84.702259 76.276164)
		(end 84.799586 76.211132)
		(width 0.16)
		(layer "In3.Cu")
		(net 54)
	)
	(arc
		(start 117.799 93.443307)
		(mid 117.825642 93.577247)
		(end 117.901513 93.690795)
		(width 0.16)
		(layer "In3.Cu")
		(net 54)
	)
	(arc
		(start 106.108165 80.647447)
		(mid 105.945953 80.53906)
		(end 105.754611 80.501)
		(width 0.16)
		(layer "In3.Cu")
		(net 54)
	)
	(arc
		(start 117.799 92.545389)
		(mid 117.76094 92.354048)
		(end 117.652554 92.191836)
		(width 0.16)
		(layer "In3.Cu")
		(net 54)
	)
	(arc
		(start 81.499 78.391)
		(mid 81.357579 78.449579)
		(end 81.299 78.591)
		(width 0.16)
		(layer "In3.Cu")
		(net 54)
	)
	(arc
		(start 84.062546 76.299)
		(mid 83.947741 76.276164)
		(end 83.850414 76.211132)
		(width 0.16)
		(layer "In3.Cu")
		(net 54)
	)
	(arc
		(start 81.401513 79.590795)
		(mid 81.325642 79.477247)
		(end 81.299 79.343307)
		(width 0.16)
		(layer "In3.Cu")
		(net 54)
	)
	(arc
		(start 81.299 77.791)
		(mid 81.357579 77.932421)
		(end 81.499 77.991)
		(width 0.16)
		(layer "In3.Cu")
		(net 54)
	)
	(arc
		(start 84.849586 74.938868)
		(mid 84.752259 74.873836)
		(end 84.637454 74.851)
		(width 0.16)
		(layer "In3.Cu")
		(net 54)
	)
	(arc
		(start 81.718382 78.191)
		(mid 81.659803 78.332421)
		(end 81.518382 78.391)
		(width 0.16)
		(layer "In3.Cu")
		(net 54)
	)
	(arc
		(start 121.042934 94.557066)
		(mid 120.994271 94.589582)
		(end 120.936868 94.601)
		(width 0.16)
		(layer "In3.Cu")
		(net 54)
	)
	(arc
		(start 82.456693 80.501)
		(mid 82.322754 80.474358)
		(end 82.209206 80.398488)
		(width 0.16)
		(layer "In3.Cu")
		(net 54)
	)
	(segment
		(start 123.112499 94.525)
		(end 121.387131 94.524999)
		(width 0.155)
		(layer "B.Cu")
		(net 54)
	)
	(segment
		(start 121.281065 94.481065)
		(end 121.2 94.4)
		(width 0.155)
		(layer "B.Cu")
		(net 54)
	)
	(segment
		(start 124.3 94.5)
		(end 123.137499 94.5)
		(width 0.155)
		(layer "B.Cu")
		(net 54)
	)
	(segment
		(start 123.137499 94.5)
		(end 123.112499 94.525)
		(width 0.155)
		(layer "B.Cu")
		(net 54)
	)
	(arc
		(start 121.387131 94.524999)
		(mid 121.329728 94.513581)
		(end 121.281065 94.481065)
		(width 0.155)
		(layer "B.Cu")
		(net 54)
	)
	(segment
		(start 84.100376 77.838951)
		(end 83.763945 77.50252)
		(width 0.155)
		(layer "F.Cu")
		(net 55)
	)
	(segment
		(start 84.246823 78.436105)
		(end 84.246823 78.192505)
		(width 0.155)
		(layer "F.Cu")
		(net 55)
	)
	(segment
		(start 83.720011 77.396454)
		(end 83.720011 77.249989)
		(width 0.155)
		(layer "F.Cu")
		(net 55)
	)
	(segment
		(start 84.347323 80.205136)
		(end 84.347323 79.480136)
		(width 0.155)
		(layer "F.Cu")
		(net 55)
	)
	(segment
		(start 84.246323 78.435605)
		(end 84.246323 78.791635)
		(width 0.155)
		(layer "F.Cu")
		(net 55)
	)
	(segment
		(start 84.347323 79.480136)
		(end 84.246823 79.379636)
		(width 0.155)
		(layer "F.Cu")
		(net 55)
	)
	(segment
		(start 84.246323 78.435605)
		(end 84.246823 78.436105)
		(width 0.155)
		(layer "F.Cu")
		(net 55)
	)
	(segment
		(start 84.246823 79.379636)
		(end 84.246823 78.79)
		(width 0.155)
		(layer "F.Cu")
		(net 55)
	)
	(via
		(at 83.720011 77.249989)
		(size 0.45)
		(drill 0.1)
		(layers "F.Cu" "B.Cu")
		(net 55)
	)
	(via
		(at 121.75 83.047)
		(size 0.45)
		(drill 0.1)
		(layers "F.Cu" "B.Cu")
		(net 55)
	)
	(arc
		(start 84.100376 77.838951)
		(mid 84.208763 78.001163)
		(end 84.246823 78.192505)
		(width 0.155)
		(layer "F.Cu")
		(net 55)
	)
	(arc
		(start 83.763945 77.50252)
		(mid 83.731429 77.453857)
		(end 83.720011 77.396454)
		(width 0.155)
		(layer "F.Cu")
		(net 55)
	)
	(segment
		(start 105.078307 73.691)
		(end 104.186693 73.691)
		(width 0.16)
		(layer "In3.Cu")
		(net 55)
	)
	(segment
		(start 90.254611 69.951)
		(end 87.345389 69.951)
		(width 0.16)
		(layer "In3.Cu")
		(net 55)
	)
	(segment
		(start 83.720011 77.397161)
		(end 83.720011 77.249989)
		(width 0.16)
		(layer "In3.Cu")
		(net 55)
	)
	(segment
		(start 84.743307 77.951)
		(end 84.356693 77.951)
		(width 0.16)
		(layer "In3.Cu")
		(net 55)
	)
	(segment
		(start 93.359205 72.848487)
		(end 90.608164 70.097446)
		(width 0.16)
		(layer "In3.Cu")
		(net 55)
	)
	(segment
		(start 122.642553 73.631835)
		(end 121.808164 72.797446)
		(width 0.16)
		(layer "In3.Cu")
		(net 55)
	)
	(segment
		(start 86.498487 71.340795)
		(end 86.447446 71.391836)
		(width 0.16)
		(layer "In3.Cu")
		(net 55)
	)
	(segment
		(start 106.116835 72.797447)
		(end 105.325794 73.588488)
		(width 0.16)
		(layer "In3.Cu")
		(net 55)
	)
	(segment
		(start 123.799 81.754611)
		(end 123.799 78.965389)
		(width 0.16)
		(layer "In3.Cu")
		(net 55)
	)
	(segment
		(start 86.301 71.745389)
		(end 86.301 76.393307)
		(width 0.16)
		(layer "In3.Cu")
		(net 55)
	)
	(segment
		(start 123.652553 78.611835)
		(end 122.891512 77.850794)
		(width 0.16)
		(layer "In3.Cu")
		(net 55)
	)
	(segment
		(start 86.198487 76.640795)
		(end 84.990794 77.848488)
		(width 0.16)
		(layer "In3.Cu")
		(net 55)
	)
	(segment
		(start 86.601 70.695389)
		(end 86.601 71.093307)
		(width 0.16)
		(layer "In3.Cu")
		(net 55)
	)
	(segment
		(start 123.008165 82.752553)
		(end 123.652554 82.108164)
		(width 0.16)
		(layer "In3.Cu")
		(net 55)
	)
	(segment
		(start 121.960132 82.899)
		(end 122.654611 82.899)
		(width 0.16)
		(layer "In3.Cu")
		(net 55)
	)
	(segment
		(start 103.939205 73.588487)
		(end 103.448164 73.097446)
		(width 0.16)
		(layer "In3.Cu")
		(net 55)
	)
	(segment
		(start 121.75 83.047)
		(end 121.854066 82.942934)
		(width 0.16)
		(layer "In3.Cu")
		(net 55)
	)
	(segment
		(start 121.454611 72.651)
		(end 106.470389 72.651)
		(width 0.16)
		(layer "In3.Cu")
		(net 55)
	)
	(segment
		(start 84.109205 77.848487)
		(end 83.763945 77.503227)
		(width 0.16)
		(layer "In3.Cu")
		(net 55)
	)
	(segment
		(start 122.789 77.603307)
		(end 122.789 73.985389)
		(width 0.16)
		(layer "In3.Cu")
		(net 55)
	)
	(segment
		(start 86.991835 70.097447)
		(end 86.747446 70.341836)
		(width 0.16)
		(layer "In3.Cu")
		(net 55)
	)
	(segment
		(start 103.094611 72.951)
		(end 93.606693 72.951)
		(width 0.16)
		(layer "In3.Cu")
		(net 55)
	)
	(arc
		(start 103.448164 73.097446)
		(mid 103.285952 72.98906)
		(end 103.094611 72.951)
		(width 0.16)
		(layer "In3.Cu")
		(net 55)
	)
	(arc
		(start 86.447446 71.391836)
		(mid 86.33906 71.554048)
		(end 86.301 71.745389)
		(width 0.16)
		(layer "In3.Cu")
		(net 55)
	)
	(arc
		(start 106.470389 72.651)
		(mid 106.279047 72.68906)
		(end 106.116835 72.797447)
		(width 0.16)
		(layer "In3.Cu")
		(net 55)
	)
	(arc
		(start 90.608164 70.097446)
		(mid 90.445952 69.98906)
		(end 90.254611 69.951)
		(width 0.16)
		(layer "In3.Cu")
		(net 55)
	)
	(arc
		(start 123.799 78.965389)
		(mid 123.76094 78.774047)
		(end 123.652553 78.611835)
		(width 0.16)
		(layer "In3.Cu")
		(net 55)
	)
	(arc
		(start 87.345389 69.951)
		(mid 87.154047 69.98906)
		(end 86.991835 70.097447)
		(width 0.16)
		(layer "In3.Cu")
		(net 55)
	)
	(arc
		(start 84.990794 77.848488)
		(mid 84.877246 77.924358)
		(end 84.743307 77.951)
		(width 0.16)
		(layer "In3.Cu")
		(net 55)
	)
	(arc
		(start 84.356693 77.951)
		(mid 84.222753 77.924358)
		(end 84.109205 77.848487)
		(width 0.16)
		(layer "In3.Cu")
		(net 55)
	)
	(arc
		(start 123.652554 82.108164)
		(mid 123.76094 81.945952)
		(end 123.799 81.754611)
		(width 0.16)
		(layer "In3.Cu")
		(net 55)
	)
	(arc
		(start 121.808164 72.797446)
		(mid 121.645952 72.68906)
		(end 121.454611 72.651)
		(width 0.16)
		(layer "In3.Cu")
		(net 55)
	)
	(arc
		(start 93.606693 72.951)
		(mid 93.472753 72.924358)
		(end 93.359205 72.848487)
		(width 0.16)
		(layer "In3.Cu")
		(net 55)
	)
	(arc
		(start 104.186693 73.691)
		(mid 104.052753 73.664358)
		(end 103.939205 73.588487)
		(width 0.16)
		(layer "In3.Cu")
		(net 55)
	)
	(arc
		(start 86.601 71.093307)
		(mid 86.574358 71.227247)
		(end 86.498487 71.340795)
		(width 0.16)
		(layer "In3.Cu")
		(net 55)
	)
	(arc
		(start 122.891512 77.850794)
		(mid 122.815642 77.737246)
		(end 122.789 77.603307)
		(width 0.16)
		(layer "In3.Cu")
		(net 55)
	)
	(arc
		(start 122.654611 82.899)
		(mid 122.845953 82.86094)
		(end 123.008165 82.752553)
		(width 0.16)
		(layer "In3.Cu")
		(net 55)
	)
	(arc
		(start 105.325794 73.588488)
		(mid 105.212246 73.664358)
		(end 105.078307 73.691)
		(width 0.16)
		(layer "In3.Cu")
		(net 55)
	)
	(arc
		(start 122.642553 73.631835)
		(mid 122.75094 73.794047)
		(end 122.789 73.985389)
		(width 0.16)
		(layer "In3.Cu")
		(net 55)
	)
	(arc
		(start 83.763945 77.503227)
		(mid 83.731429 77.454564)
		(end 83.720011 77.397161)
		(width 0.16)
		(layer "In3.Cu")
		(net 55)
	)
	(arc
		(start 86.747446 70.341836)
		(mid 86.63906 70.504048)
		(end 86.601 70.695389)
		(width 0.16)
		(layer "In3.Cu")
		(net 55)
	)
	(arc
		(start 121.854066 82.942934)
		(mid 121.902729 82.910418)
		(end 121.960132 82.899)
		(width 0.16)
		(layer "In3.Cu")
		(net 55)
	)
	(arc
		(start 86.301 76.393307)
		(mid 86.274358 76.527247)
		(end 86.198487 76.640795)
		(width 0.16)
		(layer "In3.Cu")
		(net 55)
	)
	(segment
		(start 121.853566 82.943434)
		(end 121.75 83.047)
		(width 0.155)
		(layer "B.Cu")
		(net 55)
	)
	(segment
		(start 122.974867 82.8995)
		(end 121.959632 82.8995)
		(width 0.155)
		(layer "B.Cu")
		(net 55)
	)
	(segment
		(start 123.093565 82.956066)
		(end 123.080933 82.943434)
		(width 0.155)
		(layer "B.Cu")
		(net 55)
	)
	(segment
		(start 124.3 83)
		(end 123.199631 83)
		(width 0.155)
		(layer "B.Cu")
		(net 55)
	)
	(arc
		(start 121.853566 82.943434)
		(mid 121.902229 82.910918)
		(end 121.959632 82.8995)
		(width 0.155)
		(layer "B.Cu")
		(net 55)
	)
	(arc
		(start 123.093565 82.956066)
		(mid 123.142228 82.988582)
		(end 123.199631 83)
		(width 0.155)
		(layer "B.Cu")
		(net 55)
	)
	(arc
		(start 122.974867 82.8995)
		(mid 123.03227 82.910918)
		(end 123.080933 82.943434)
		(width 0.155)
		(layer "B.Cu")
		(net 55)
	)
	(segment
		(start 83.996823 71.179636)
		(end 84.097323 71.280136)
		(width 0.155)
		(layer "F.Cu")
		(net 56)
	)
	(segment
		(start 83.603 97)
		(end 83.7505 97.1475)
		(width 0.155)
		(layer "F.Cu")
		(net 56)
	)
	(segment
		(start 83.996823 70.585398)
		(end 83.996823 71.179636)
		(width 0.155)
		(layer "F.Cu")
		(net 56)
	)
	(segment
		(start 83.72 70.15)
		(end 83.72 70.308575)
		(width 0.155)
		(layer "F.Cu")
		(net 56)
	)
	(segment
		(start 85.0005 106.238074)
		(end 83.888074 107.3505)
		(width 0.155)
		(layer "F.Cu")
		(net 56)
	)
	(segment
		(start 85.0005 99.061926)
		(end 85.0005 106.238074)
		(width 0.155)
		(layer "F.Cu")
		(net 56)
	)
	(segment
		(start 83.7505 97.1475)
		(end 83.7505 97.811926)
		(width 0.155)
		(layer "F.Cu")
		(net 56)
	)
	(segment
		(start 82.7355 107.3505)
		(end 82.385 107)
		(width 0.155)
		(layer "F.Cu")
		(net 56)
	)
	(segment
		(start 83.888074 107.3505)
		(end 82.7355 107.3505)
		(width 0.155)
		(layer "F.Cu")
		(net 56)
	)
	(segment
		(start 83.7505 97.811926)
		(end 85.0005 99.061926)
		(width 0.155)
		(layer "F.Cu")
		(net 56)
	)
	(segment
		(start 83.72 70.308575)
		(end 83.996823 70.585398)
		(width 0.155)
		(layer "F.Cu")
		(net 56)
	)
	(via
		(at 83.603 97)
		(size 0.45)
		(drill 0.1)
		(layers "F.Cu" "B.Cu")
		(net 56)
	)
	(via
		(at 83.72 70.15)
		(size 0.45)
		(drill 0.1)
		(layers "F.Cu" "B.Cu")
		(net 56)
	)
	(segment
		(start 83.751 96.852)
		(end 83.751 93.361718)
		(width 0.16)
		(layer "In3.Cu")
		(net 56)
	)
	(segment
		(start 74.501 84.111718)
		(end 73.151 82.761718)
		(width 0.16)
		(layer "In3.Cu")
		(net 56)
	)
	(segment
		(start 73.651 80.688282)
		(end 73.651 75.838282)
		(width 0.16)
		(layer "In3.Cu")
		(net 56)
	)
	(segment
		(start 83.560718 70.15)
		(end 83.72 70.15)
		(width 0.16)
		(layer "In3.Cu")
		(net 56)
	)
	(segment
		(start 74.501 85.711718)
		(end 74.501 84.111718)
		(width 0.16)
		(layer "In3.Cu")
		(net 56)
	)
	(segment
		(start 79.148282 69.641)
		(end 83.051718 69.641)
		(width 0.16)
		(layer "In3.Cu")
		(net 56)
	)
	(segment
		(start 73.151 82.761718)
		(end 73.151 81.188282)
		(width 0.16)
		(layer "In3.Cu")
		(net 56)
	)
	(segment
		(start 77.851 70.938282)
		(end 79.148282 69.641)
		(width 0.16)
		(layer "In3.Cu")
		(net 56)
	)
	(segment
		(start 77.851 71.638282)
		(end 77.851 70.938282)
		(width 0.16)
		(layer "In3.Cu")
		(net 56)
	)
	(segment
		(start 73.151 81.188282)
		(end 73.651 80.688282)
		(width 0.16)
		(layer "In3.Cu")
		(net 56)
	)
	(segment
		(start 78.838282 90.049)
		(end 74.501 85.711718)
		(width 0.16)
		(layer "In3.Cu")
		(net 56)
	)
	(segment
		(start 83.603 97)
		(end 83.751 96.852)
		(width 0.16)
		(layer "In3.Cu")
		(net 56)
	)
	(segment
		(start 83.751 93.361718)
		(end 80.438282 90.049)
		(width 0.16)
		(layer "In3.Cu")
		(net 56)
	)
	(segment
		(start 80.438282 90.049)
		(end 78.838282 90.049)
		(width 0.16)
		(layer "In3.Cu")
		(net 56)
	)
	(segment
		(start 83.051718 69.641)
		(end 83.560718 70.15)
		(width 0.16)
		(layer "In3.Cu")
		(net 56)
	)
	(segment
		(start 73.651 75.838282)
		(end 77.851 71.638282)
		(width 0.16)
		(layer "In3.Cu")
		(net 56)
	)
	(segment
		(start 83.947823 78.558541)
		(end 83.947823 78.254223)
		(width 0.155)
		(layer "F.Cu")
		(net 57)
	)
	(segment
		(start 83.948323 78.559041)
		(end 83.948323 78.791635)
		(width 0.155)
		(layer "F.Cu")
		(net 57)
	)
	(segment
		(start 83.947823 79.379636)
		(end 83.947823 78.79)
		(width 0.155)
		(layer "F.Cu")
		(net 57)
	)
	(segment
		(start 83.84531 78.006735)
		(end 83.55252 77.713945)
		(width 0.155)
		(layer "F.Cu")
		(net 57)
	)
	(segment
		(start 83.847323 79.480136)
		(end 83.947823 79.379636)
		(width 0.155)
		(layer "F.Cu")
		(net 57)
	)
	(segment
		(start 83.847323 80.205136)
		(end 83.847323 79.480136)
		(width 0.155)
		(layer "F.Cu")
		(net 57)
	)
	(segment
		(start 83.948323 78.559041)
		(end 83.947823 78.558541)
		(width 0.155)
		(layer "F.Cu")
		(net 57)
	)
	(segment
		(start 83.446454 77.670011)
		(end 83.299989 77.670011)
		(width 0.155)
		(layer "F.Cu")
		(net 57)
	)
	(via
		(at 121.75 82.453)
		(size 0.45)
		(drill 0.1)
		(layers "F.Cu" "B.Cu")
		(net 57)
	)
	(via
		(at 83.299989 77.670011)
		(size 0.45)
		(drill 0.1)
		(layers "F.Cu" "B.Cu")
		(net 57)
	)
	(arc
		(start 83.55252 77.713945)
		(mid 83.503857 77.681429)
		(end 83.446454 77.670011)
		(width 0.155)
		(layer "F.Cu")
		(net 57)
	)
	(arc
		(start 83.947823 78.254223)
		(mid 83.921181 78.120283)
		(end 83.84531 78.006735)
		(width 0.155)
		(layer "F.Cu")
		(net 57)
	)
	(segment
		(start 103.771836 73.842554)
		(end 103.280795 73.351513)
		(width 0.16)
		(layer "In3.Cu")
		(net 57)
	)
	(segment
		(start 93.191836 73.102554)
		(end 90.440795 70.351513)
		(width 0.16)
		(layer "In3.Cu")
		(net 57)
	)
	(segment
		(start 85.674476 77.895948)
		(end 85.674476 77.895947)
		(width 0.16)
		(layer "In3.Cu")
		(net 57)
	)
	(segment
		(start 86.226729 77.316829)
		(end 86.240162 77.330262)
		(width 0.16)
		(layer "In3.Cu")
		(net 57)
	)
	(segment
		(start 83.941836 78.102554)
		(end 83.553227 77.713945)
		(width 0.16)
		(layer "In3.Cu")
		(net 57)
	)
	(segment
		(start 83.447161 77.670011)
		(end 83.299989 77.670011)
		(width 0.16)
		(layer "In3.Cu")
		(net 57)
	)
	(segment
		(start 87.159206 70.351512)
		(end 87.001513 70.509205)
		(width 0.16)
		(layer "In3.Cu")
		(net 57)
	)
	(segment
		(start 86.240162 77.330262)
		(end 86.240162 77.330261)
		(width 0.16)
		(layer "In3.Cu")
		(net 57)
	)
	(segment
		(start 122.491 77.664611)
		(end 122.491 74.3)
		(width 0.16)
		(layer "In3.Cu")
		(net 57)
	)
	(segment
		(start 85.957319 77.613105)
		(end 85.943887 77.599673)
		(width 0.16)
		(layer "In3.Cu")
		(net 57)
	)
	(segment
		(start 121.393307 72.949)
		(end 106.531693 72.949)
		(width 0.16)
		(layer "In3.Cu")
		(net 57)
	)
	(segment
		(start 86.452552 76.808165)
		(end 86.226729 77.033986)
		(width 0.16)
		(layer "In3.Cu")
		(net 57)
	)
	(segment
		(start 122.840794 82.498488)
		(end 123.398487 81.940795)
		(width 0.16)
		(layer "In3.Cu")
		(net 57)
	)
	(segment
		(start 85.095359 78.165359)
		(end 85.011718 78.249)
		(width 0.16)
		(layer "In3.Cu")
		(net 57)
	)
	(segment
		(start 103.033307 73.249)
		(end 93.545389 73.249)
		(width 0.16)
		(layer "In3.Cu")
		(net 57)
	)
	(segment
		(start 121.960132 82.601)
		(end 122.593307 82.601)
		(width 0.16)
		(layer "In3.Cu")
		(net 57)
	)
	(segment
		(start 122.491 74.3)
		(end 122.491 74.046693)
		(width 0.16)
		(layer "In3.Cu")
		(net 57)
	)
	(segment
		(start 85.661043 77.882515)
		(end 85.674476 77.895948)
		(width 0.16)
		(layer "In3.Cu")
		(net 57)
	)
	(segment
		(start 85.661043 77.599672)
		(end 85.661042 77.599672)
		(width 0.16)
		(layer "In3.Cu")
		(net 57)
	)
	(segment
		(start 86.599 71.806693)
		(end 86.599 76.45461)
		(width 0.16)
		(layer "In3.Cu")
		(net 57)
	)
	(segment
		(start 122.388487 73.799205)
		(end 121.640794 73.051512)
		(width 0.16)
		(layer "In3.Cu")
		(net 57)
	)
	(segment
		(start 85.391633 78.178791)
		(end 85.378201 78.165359)
		(width 0.16)
		(layer "In3.Cu")
		(net 57)
	)
	(segment
		(start 86.226729 77.033986)
		(end 86.226728 77.033986)
		(width 0.16)
		(layer "In3.Cu")
		(net 57)
	)
	(segment
		(start 86.752554 71.508164)
		(end 86.701513 71.559205)
		(width 0.16)
		(layer "In3.Cu")
		(net 57)
	)
	(segment
		(start 86.899 70.756693)
		(end 86.899 71.154611)
		(width 0.16)
		(layer "In3.Cu")
		(net 57)
	)
	(segment
		(start 123.501 81.693307)
		(end 123.501 79.026693)
		(width 0.16)
		(layer "In3.Cu")
		(net 57)
	)
	(segment
		(start 85.674476 78.178791)
		(end 85.674476 78.178792)
		(width 0.16)
		(layer "In3.Cu")
		(net 57)
	)
	(segment
		(start 85.011718 78.249)
		(end 84.295389 78.249)
		(width 0.16)
		(layer "In3.Cu")
		(net 57)
	)
	(segment
		(start 90.193307 70.249)
		(end 87.406693 70.249)
		(width 0.16)
		(layer "In3.Cu")
		(net 57)
	)
	(segment
		(start 86.240162 77.613105)
		(end 86.240162 77.613106)
		(width 0.16)
		(layer "In3.Cu")
		(net 57)
	)
	(segment
		(start 123.398488 78.779206)
		(end 122.637447 78.018165)
		(width 0.16)
		(layer "In3.Cu")
		(net 57)
	)
	(segment
		(start 85.661045 77.599673)
		(end 85.661043 77.599672)
		(width 0.16)
		(layer "In3.Cu")
		(net 57)
	)
	(segment
		(start 106.284206 73.051512)
		(end 105.493165 73.842553)
		(width 0.16)
		(layer "In3.Cu")
		(net 57)
	)
	(segment
		(start 105.139611 73.989)
		(end 104.125389 73.989)
		(width 0.16)
		(layer "In3.Cu")
		(net 57)
	)
	(segment
		(start 121.75 82.453)
		(end 121.854066 82.557066)
		(width 0.16)
		(layer "In3.Cu")
		(net 57)
	)
	(arc
		(start 103.280795 73.351513)
		(mid 103.167247 73.275642)
		(end 103.033307 73.249)
		(width 0.16)
		(layer "In3.Cu")
		(net 57)
	)
	(arc
		(start 86.701513 71.559205)
		(mid 86.625642 71.672753)
		(end 86.599 71.806693)
		(width 0.16)
		(layer "In3.Cu")
		(net 57)
	)
	(arc
		(start 86.240162 77.330261)
		(mid 86.298741 77.471683)
		(end 86.240162 77.613105)
		(width 0.16)
		(layer "In3.Cu")
		(net 57)
	)
	(arc
		(start 90.440795 70.351513)
		(mid 90.327247 70.275642)
		(end 90.193307 70.249)
		(width 0.16)
		(layer "In3.Cu")
		(net 57)
	)
	(arc
		(start 121.640794 73.051512)
		(mid 121.527246 72.975642)
		(end 121.393307 72.949)
		(width 0.16)
		(layer "In3.Cu")
		(net 57)
	)
	(arc
		(start 123.501 79.026693)
		(mid 123.474358 78.892754)
		(end 123.398488 78.779206)
		(width 0.16)
		(layer "In3.Cu")
		(net 57)
	)
	(arc
		(start 123.398487 81.940795)
		(mid 123.474358 81.827247)
		(end 123.501 81.693307)
		(width 0.16)
		(layer "In3.Cu")
		(net 57)
	)
	(arc
		(start 121.854066 82.557066)
		(mid 121.902729 82.589582)
		(end 121.960132 82.601)
		(width 0.16)
		(layer "In3.Cu")
		(net 57)
	)
	(arc
		(start 86.240162 77.613106)
		(mid 86.09874 77.671684)
		(end 85.957319 77.613105)
		(width 0.16)
		(layer "In3.Cu")
		(net 57)
	)
	(arc
		(start 93.545389 73.249)
		(mid 93.354048 73.21094)
		(end 93.191836 73.102554)
		(width 0.16)
		(layer "In3.Cu")
		(net 57)
	)
	(arc
		(start 85.378201 78.165359)
		(mid 85.23678 78.106781)
		(end 85.095359 78.165359)
		(width 0.16)
		(layer "In3.Cu")
		(net 57)
	)
	(arc
		(start 86.599 76.45461)
		(mid 86.560939 76.645953)
		(end 86.452552 76.808165)
		(width 0.16)
		(layer "In3.Cu")
		(net 57)
	)
	(arc
		(start 122.637447 78.018165)
		(mid 122.52906 77.855953)
		(end 122.491 77.664611)
		(width 0.16)
		(layer "In3.Cu")
		(net 57)
	)
	(arc
		(start 122.593307 82.601)
		(mid 122.727246 82.574358)
		(end 122.840794 82.498488)
		(width 0.16)
		(layer "In3.Cu")
		(net 57)
	)
	(arc
		(start 104.125389 73.989)
		(mid 103.934048 73.95094)
		(end 103.771836 73.842554)
		(width 0.16)
		(layer "In3.Cu")
		(net 57)
	)
	(arc
		(start 86.226728 77.033986)
		(mid 86.16815 77.175408)
		(end 86.226729 77.316829)
		(width 0.16)
		(layer "In3.Cu")
		(net 57)
	)
	(arc
		(start 105.493165 73.842553)
		(mid 105.330953 73.95094)
		(end 105.139611 73.989)
		(width 0.16)
		(layer "In3.Cu")
		(net 57)
	)
	(arc
		(start 85.661042 77.599672)
		(mid 85.602464 77.741094)
		(end 85.661043 77.882515)
		(width 0.16)
		(layer "In3.Cu")
		(net 57)
	)
	(arc
		(start 86.899 71.154611)
		(mid 86.86094 71.345952)
		(end 86.752554 71.508164)
		(width 0.16)
		(layer "In3.Cu")
		(net 57)
	)
	(arc
		(start 122.491 74.046693)
		(mid 122.464358 73.912753)
		(end 122.388487 73.799205)
		(width 0.16)
		(layer "In3.Cu")
		(net 57)
	)
	(arc
		(start 85.943887 77.599673)
		(mid 85.802466 77.541095)
		(end 85.661045 77.599673)
		(width 0.16)
		(layer "In3.Cu")
		(net 57)
	)
	(arc
		(start 106.531693 72.949)
		(mid 106.397754 72.975642)
		(end 106.284206 73.051512)
		(width 0.16)
		(layer "In3.Cu")
		(net 57)
	)
	(arc
		(start 85.674476 77.895947)
		(mid 85.733055 78.037369)
		(end 85.674476 78.178791)
		(width 0.16)
		(layer "In3.Cu")
		(net 57)
	)
	(arc
		(start 85.674476 78.178792)
		(mid 85.533054 78.23737)
		(end 85.391633 78.178791)
		(width 0.16)
		(layer "In3.Cu")
		(net 57)
	)
	(arc
		(start 87.001513 70.509205)
		(mid 86.925642 70.622753)
		(end 86.899 70.756693)
		(width 0.16)
		(layer "In3.Cu")
		(net 57)
	)
	(arc
		(start 83.553227 77.713945)
		(mid 83.504564 77.681429)
		(end 83.447161 77.670011)
		(width 0.16)
		(layer "In3.Cu")
		(net 57)
	)
	(arc
		(start 84.295389 78.249)
		(mid 84.104048 78.21094)
		(end 83.941836 78.102554)
		(width 0.16)
		(layer "In3.Cu")
		(net 57)
	)
	(arc
		(start 87.406693 70.249)
		(mid 87.272754 70.275642)
		(end 87.159206 70.351512)
		(width 0.16)
		(layer "In3.Cu")
		(net 57)
	)
	(segment
		(start 124.3 82.5)
		(end 123.199631 82.5)
		(width 0.155)
		(layer "B.Cu")
		(net 57)
	)
	(segment
		(start 123.093565 82.543934)
		(end 123.080933 82.556566)
		(width 0.155)
		(layer "B.Cu")
		(net 57)
	)
	(segment
		(start 121.853566 82.556566)
		(end 121.75 82.453)
		(width 0.155)
		(layer "B.Cu")
		(net 57)
	)
	(segment
		(start 122.974867 82.6005)
		(end 121.959632 82.6005)
		(width 0.155)
		(layer "B.Cu")
		(net 57)
	)
	(arc
		(start 123.199631 82.5)
		(mid 123.142228 82.511418)
		(end 123.093565 82.543934)
		(width 0.155)
		(layer "B.Cu")
		(net 57)
	)
	(arc
		(start 123.080933 82.556566)
		(mid 123.03227 82.589082)
		(end 122.974867 82.6005)
		(width 0.155)
		(layer "B.Cu")
		(net 57)
	)
	(arc
		(start 121.853566 82.556566)
		(mid 121.902229 82.589082)
		(end 121.959632 82.6005)
		(width 0.155)
		(layer "B.Cu")
		(net 57)
	)
	(segment
		(start 83.518575 70.53)
		(end 83.697823 70.709248)
		(width 0.155)
		(layer "F.Cu")
		(net 58)
	)
	(segment
		(start 83.697823 70.709248)
		(end 83.697823 71.179636)
		(width 0.155)
		(layer "F.Cu")
		(net 58)
	)
	(segment
		(start 84.0495 97.688074)
		(end 85.2995 98.938074)
		(width 0.155)
		(layer "F.Cu")
		(net 58)
	)
	(segment
		(start 82.7355 107.6495)
		(end 82.385 108)
		(width 0.155)
		(layer "F.Cu")
		(net 58)
	)
	(segment
		(start 83.28 70.53)
		(end 83.518575 70.53)
		(width 0.155)
		(layer "F.Cu")
		(net 58)
	)
	(segment
		(start 84.011926 107.6495)
		(end 82.7355 107.6495)
		(width 0.155)
		(layer "F.Cu")
		(net 58)
	)
	(segment
		(start 85.2995 106.361926)
		(end 84.011926 107.6495)
		(width 0.155)
		(layer "F.Cu")
		(net 58)
	)
	(segment
		(start 84.0495 97.1475)
		(end 84.0495 97.688074)
		(width 0.155)
		(layer "F.Cu")
		(net 58)
	)
	(segment
		(start 84.197 97)
		(end 84.0495 97.1475)
		(width 0.155)
		(layer "F.Cu")
		(net 58)
	)
	(segment
		(start 83.697823 71.179636)
		(end 83.597323 71.280136)
		(width 0.155)
		(layer "F.Cu")
		(net 58)
	)
	(segment
		(start 85.2995 98.938074)
		(end 85.2995 106.361926)
		(width 0.155)
		(layer "F.Cu")
		(net 58)
	)
	(via
		(at 84.197 97)
		(size 0.45)
		(drill 0.1)
		(layers "F.Cu" "B.Cu")
		(net 58)
	)
	(via
		(at 83.28 70.53)
		(size 0.45)
		(drill 0.1)
		(layers "F.Cu" "B.Cu")
		(net 58)
	)
	(segment
		(start 78.807873 70.650335)
		(end 78.824321 70.666783)
		(width 0.16)
		(layer "In3.Cu")
		(net 58)
	)
	(segment
		(start 84.197 97)
		(end 84.049 96.852)
		(width 0.16)
		(layer "In3.Cu")
		(net 58)
	)
	(segment
		(start 78.824321 70.666783)
		(end 78.824321 70.666784)
		(width 0.16)
		(layer "In3.Cu")
		(net 58)
	)
	(segment
		(start 73.949 80.811718)
		(end 73.949 75.961718)
		(width 0.16)
		(layer "In3.Cu")
		(net 58)
	)
	(segment
		(start 74.799 85.588282)
		(end 74.799 83.988282)
		(width 0.16)
		(layer "In3.Cu")
		(net 58)
	)
	(segment
		(start 83.28 70.290718)
		(end 83.28 70.53)
		(width 0.16)
		(layer "In3.Cu")
		(net 58)
	)
	(segment
		(start 79.071807 70.666784)
		(end 79.071807 70.666783)
		(width 0.16)
		(layer "In3.Cu")
		(net 58)
	)
	(segment
		(start 80.561718 89.751)
		(end 78.961718 89.751)
		(width 0.16)
		(layer "In3.Cu")
		(net 58)
	)
	(segment
		(start 79.055359 70.155359)
		(end 79.271718 69.939)
		(width 0.16)
		(layer "In3.Cu")
		(net 58)
	)
	(segment
		(start 78.149 71.761718)
		(end 78.149 71.061718)
		(width 0.16)
		(layer "In3.Cu")
		(net 58)
	)
	(segment
		(start 74.799 83.988282)
		(end 73.449 82.638282)
		(width 0.16)
		(layer "In3.Cu")
		(net 58)
	)
	(segment
		(start 82.928282 69.939)
		(end 83.28 70.290718)
		(width 0.16)
		(layer "In3.Cu")
		(net 58)
	)
	(segment
		(start 84.049 93.238282)
		(end 80.561718 89.751)
		(width 0.16)
		(layer "In3.Cu")
		(net 58)
	)
	(segment
		(start 78.149 71.061718)
		(end 78.560386 70.650336)
		(width 0.16)
		(layer "In3.Cu")
		(net 58)
	)
	(segment
		(start 78.961718 89.751)
		(end 74.799 85.588282)
		(width 0.16)
		(layer "In3.Cu")
		(net 58)
	)
	(segment
		(start 73.949 75.961718)
		(end 78.149 71.761718)
		(width 0.16)
		(layer "In3.Cu")
		(net 58)
	)
	(segment
		(start 73.449 81.311718)
		(end 73.949 80.811718)
		(width 0.16)
		(layer "In3.Cu")
		(net 58)
	)
	(segment
		(start 84.049 96.852)
		(end 84.049 93.238282)
		(width 0.16)
		(layer "In3.Cu")
		(net 58)
	)
	(segment
		(start 79.071808 70.419296)
		(end 79.055359 70.402847)
		(width 0.16)
		(layer "In3.Cu")
		(net 58)
	)
	(segment
		(start 79.271718 69.939)
		(end 82.928282 69.939)
		(width 0.16)
		(layer "In3.Cu")
		(net 58)
	)
	(segment
		(start 73.449 82.638282)
		(end 73.449 81.311718)
		(width 0.16)
		(layer "In3.Cu")
		(net 58)
	)
	(arc
		(start 78.560386 70.650336)
		(mid 78.684129 70.599079)
		(end 78.807873 70.650335)
		(width 0.16)
		(layer "In3.Cu")
		(net 58)
	)
	(arc
		(start 79.071807 70.666783)
		(mid 79.123064 70.54304)
		(end 79.071808 70.419296)
		(width 0.16)
		(layer "In3.Cu")
		(net 58)
	)
	(arc
		(start 78.824321 70.666784)
		(mid 78.948065 70.718039)
		(end 79.071807 70.666784)
		(width 0.16)
		(layer "In3.Cu")
		(net 58)
	)
	(arc
		(start 79.055359 70.402847)
		(mid 79.004103 70.279103)
		(end 79.055359 70.155359)
		(width 0.16)
		(layer "In3.Cu")
		(net 58)
	)
	(segment
		(start 83.598 99.462039)
		(end 83.598 104.437038)
		(width 0.16)
		(layer "F.Cu")
		(net 59)
	)
	(segment
		(start 83.925 98.95)
		(end 83.925 99.135039)
		(width 0.16)
		(layer "F.Cu")
		(net 59)
	)
	(segment
		(start 83.598 104.437038)
		(end 83.087038 104.948)
		(width 0.16)
		(layer "F.Cu")
		(net 59)
	)
	(segment
		(start 82.847323 80.205136)
		(end 82.847323 78.892635)
		(width 0.155)
		(layer "F.Cu")
		(net 59)
	)
	(segment
		(start 83.087038 104.948)
		(end 82.733 104.948)
		(width 0.16)
		(layer "F.Cu")
		(net 59)
	)
	(segment
		(start 83.925 99.135039)
		(end 83.598 99.462039)
		(width 0.16)
		(layer "F.Cu")
		(net 59)
	)
	(segment
		(start 82.746823 78.792135)
		(end 82.746823 78.475397)
		(width 0.155)
		(layer "F.Cu")
		(net 59)
	)
	(segment
		(start 81.671926 77.4005)
		(end 76.3975 77.4005)
		(width 0.155)
		(layer "F.Cu")
		(net 59)
	)
	(segment
		(start 82.746823 78.475397)
		(end 81.671926 77.4005)
		(width 0.155)
		(layer "F.Cu")
		(net 59)
	)
	(segment
		(start 76.3975 77.4005)
		(end 76.25 77.253)
		(width 0.155)
		(layer "F.Cu")
		(net 59)
	)
	(segment
		(start 82.847323 78.892635)
		(end 82.746823 78.792135)
		(width 0.155)
		(layer "F.Cu")
		(net 59)
	)
	(segment
		(start 82.733 104.948)
		(end 82.385 104.6)
		(width 0.16)
		(layer "F.Cu")
		(net 59)
	)
	(via
		(at 83.925 98.95)
		(size 0.45)
		(drill 0.1)
		(layers "F.Cu" "B.Cu")
		(net 59)
	)
	(via
		(at 76.25 77.253)
		(size 0.45)
		(drill 0.1)
		(layers "F.Cu" "B.Cu")
		(net 59)
	)
	(segment
		(start 74.801 77.888282)
		(end 74.801 82.611718)
		(width 0.16)
		(layer "In3.Cu")
		(net 59)
	)
	(segment
		(start 75.288282 77.401)
		(end 74.801 77.888282)
		(width 0.16)
		(layer "In3.Cu")
		(net 59)
	)
	(segment
		(start 76.25 77.253)
		(end 76.102 77.401)
		(width 0.16)
		(layer "In3.Cu")
		(net 59)
	)
	(segment
		(start 85.551 93.361718)
		(end 85.551 97.543282)
		(width 0.16)
		(layer "In3.Cu")
		(net 59)
	)
	(segment
		(start 84.144282 98.95)
		(end 83.925 98.95)
		(width 0.16)
		(layer "In3.Cu")
		(net 59)
	)
	(segment
		(start 85.551 97.543282)
		(end 84.144282 98.95)
		(width 0.16)
		(layer "In3.Cu")
		(net 59)
	)
	(segment
		(start 74.801 82.611718)
		(end 85.551 93.361718)
		(width 0.16)
		(layer "In3.Cu")
		(net 59)
	)
	(segment
		(start 76.102 77.401)
		(end 75.288282 77.401)
		(width 0.16)
		(layer "In3.Cu")
		(net 59)
	)
	(segment
		(start 80.357447 76.158165)
		(end 80.421836 76.222554)
		(width 0.155)
		(layer "F.Cu")
		(net 60)
	)
	(segment
		(start 120.75789 97.653535)
		(end 120.75789 97.85789)
		(width 0.155)
		(layer "F.Cu")
		(net 60)
	)
	(segment
		(start 122.009412 96.402013)
		(end 121.730712 96.680713)
		(width 0.155)
		(layer "F.Cu")
		(net 60)
	)
	(segment
		(start 82.599336 73.28791)
		(end 82.753054 73.441628)
		(width 0.155)
		(layer "F.Cu")
		(net 60)
	)
	(segment
		(start 82.597323 72.730136)
		(end 82.496823 72.830636)
		(width 0.155)
		(layer "F.Cu")
		(net 60)
	)
	(segment
		(start 123.875 96.4)
		(end 123.7745 96.2995)
		(width 0.155)
		(layer "F.Cu")
		(net 60)
	)
	(segment
		(start 80.775389 76.369)
		(end 81.814611 76.369)
		(width 0.155)
		(layer "F.Cu")
		(net 60)
	)
	(segment
		(start 80.45211 75.00211)
		(end 80.45211 75.14504)
		(width 0.155)
		(layer "F.Cu")
		(net 60)
	)
	(segment
		(start 121.497367 97.068511)
		(end 121.497367 97.06851)
		(width 0.155)
		(layer "F.Cu")
		(net 60)
	)
	(segment
		(start 80.408176 75.251106)
		(end 80.357446 75.301836)
		(width 0.155)
		(layer "F.Cu")
		(net 60)
	)
	(segment
		(start 80.211 75.655389)
		(end 80.211 75.804611)
		(width 0.155)
		(layer "F.Cu")
		(net 60)
	)
	(segment
		(start 82.168165 76.222553)
		(end 82.753054 75.637664)
		(width 0.155)
		(layer "F.Cu")
		(net 60)
	)
	(segment
		(start 121.730712 96.989615)
		(end 121.651817 97.068511)
		(width 0.155)
		(layer "F.Cu")
		(net 60)
	)
	(segment
		(start 121.342916 97.068511)
		(end 121.342917 97.06851)
		(width 0.155)
		(layer "F.Cu")
		(net 60)
	)
	(segment
		(start 82.496823 72.830636)
		(end 82.496823 73.040422)
		(width 0.155)
		(layer "F.Cu")
		(net 60)
	)
	(segment
		(start 121.342917 97.06851)
		(end 120.75789 97.653535)
		(width 0.155)
		(layer "F.Cu")
		(net 60)
	)
	(segment
		(start 123.7745 96.2995)
		(end 122.2569 96.2995)
		(width 0.155)
		(layer "F.Cu")
		(net 60)
	)
	(segment
		(start 121.730712 96.835165)
		(end 121.730711 96.835165)
		(width 0.155)
		(layer "F.Cu")
		(net 60)
	)
	(segment
		(start 124.5 96.4)
		(end 123.875 96.4)
		(width 0.155)
		(layer "F.Cu")
		(net 60)
	)
	(segment
		(start 121.730712 96.989616)
		(end 121.730712 96.989615)
		(width 0.155)
		(layer "F.Cu")
		(net 60)
	)
	(segment
		(start 82.8995 73.795181)
		(end 82.8995 75.284111)
		(width 0.155)
		(layer "F.Cu")
		(net 60)
	)
	(via
		(at 120.75789 97.85789)
		(size 0.45)
		(drill 0.1)
		(layers "F.Cu" "B.Cu")
		(net 60)
	)
	(via
		(at 80.45211 75.00211)
		(size 0.45)
		(drill 0.1)
		(layers "F.Cu" "B.Cu")
		(net 60)
	)
	(arc
		(start 80.45211 75.14504)
		(mid 80.440692 75.202443)
		(end 80.408176 75.251106)
		(width 0.155)
		(layer "F.Cu")
		(net 60)
	)
	(arc
		(start 121.651817 97.068511)
		(mid 121.574593 97.100498)
		(end 121.497367 97.068511)
		(width 0.155)
		(layer "F.Cu")
		(net 60)
	)
	(arc
		(start 82.753054 73.441628)
		(mid 82.86144 73.60384)
		(end 82.8995 73.795181)
		(width 0.155)
		(layer "F.Cu")
		(net 60)
	)
	(arc
		(start 81.814611 76.369)
		(mid 82.005953 76.33094)
		(end 82.168165 76.222553)
		(width 0.155)
		(layer "F.Cu")
		(net 60)
	)
	(arc
		(start 80.357446 75.301836)
		(mid 80.24906 75.464048)
		(end 80.211 75.655389)
		(width 0.155)
		(layer "F.Cu")
		(net 60)
	)
	(arc
		(start 82.599336 73.28791)
		(mid 82.523465 73.174362)
		(end 82.496823 73.040422)
		(width 0.155)
		(layer "F.Cu")
		(net 60)
	)
	(arc
		(start 80.421836 76.222554)
		(mid 80.584048 76.33094)
		(end 80.775389 76.369)
		(width 0.155)
		(layer "F.Cu")
		(net 60)
	)
	(arc
		(start 121.497367 97.06851)
		(mid 121.42014 97.036524)
		(end 121.342916 97.068511)
		(width 0.155)
		(layer "F.Cu")
		(net 60)
	)
	(arc
		(start 82.753054 75.637664)
		(mid 82.86144 75.475452)
		(end 82.8995 75.284111)
		(width 0.155)
		(layer "F.Cu")
		(net 60)
	)
	(arc
		(start 80.357447 76.158165)
		(mid 80.24906 75.995953)
		(end 80.211 75.804611)
		(width 0.155)
		(layer "F.Cu")
		(net 60)
	)
	(arc
		(start 121.730711 96.835165)
		(mid 121.7627 96.912389)
		(end 121.730712 96.989616)
		(width 0.155)
		(layer "F.Cu")
		(net 60)
	)
	(arc
		(start 122.2569 96.2995)
		(mid 122.12296 96.326142)
		(end 122.009412 96.402013)
		(width 0.155)
		(layer "F.Cu")
		(net 60)
	)
	(arc
		(start 121.730712 96.680713)
		(mid 121.698724 96.757939)
		(end 121.730712 96.835165)
		(width 0.155)
		(layer "F.Cu")
		(net 60)
	)
	(segment
		(start 115.801 96.204611)
		(end 115.801 92.756693)
		(width 0.16)
		(layer "In3.Cu")
		(net 60)
	)
	(segment
		(start 120.508894 97.901824)
		(end 119.908164 98.502554)
		(width 0.16)
		(layer "In3.Cu")
		(net 60)
	)
	(segment
		(start 79.171 79.424611)
		(end 79.171 76.695389)
		(width 0.16)
		(layer "In3.Cu")
		(net 60)
	)
	(segment
		(start 80.45211 75.14504)
		(end 80.45211 75.00211)
		(width 0.16)
		(layer "In3.Cu")
		(net 60)
	)
	(segment
		(start 120.75789 97.85789)
		(end 120.61496 97.85789)
		(width 0.16)
		(layer "In3.Cu")
		(net 60)
	)
	(segment
		(start 117.891835 98.502553)
		(end 115.947446 96.558164)
		(width 0.16)
		(layer "In3.Cu")
		(net 60)
	)
	(segment
		(start 105.143307 82.099)
		(end 81.845389 82.099)
		(width 0.16)
		(layer "In3.Cu")
		(net 60)
	)
	(segment
		(start 119.554611 98.649)
		(end 118.245389 98.649)
		(width 0.16)
		(layer "In3.Cu")
		(net 60)
	)
	(segment
		(start 79.317447 76.341835)
		(end 80.408176 75.251106)
		(width 0.16)
		(layer "In3.Cu")
		(net 60)
	)
	(segment
		(start 115.698487 92.509205)
		(end 105.390794 82.201512)
		(width 0.16)
		(layer "In3.Cu")
		(net 60)
	)
	(segment
		(start 81.491835 81.952553)
		(end 79.317446 79.778164)
		(width 0.16)
		(layer "In3.Cu")
		(net 60)
	)
	(arc
		(start 118.245389 98.649)
		(mid 118.054047 98.61094)
		(end 117.891835 98.502553)
		(width 0.16)
		(layer "In3.Cu")
		(net 60)
	)
	(arc
		(start 80.408176 75.251106)
		(mid 80.440692 75.202443)
		(end 80.45211 75.14504)
		(width 0.16)
		(layer "In3.Cu")
		(net 60)
	)
	(arc
		(start 120.508894 97.901824)
		(mid 120.557557 97.869308)
		(end 120.61496 97.85789)
		(width 0.16)
		(layer "In3.Cu")
		(net 60)
	)
	(arc
		(start 119.908164 98.502554)
		(mid 119.745952 98.61094)
		(end 119.554611 98.649)
		(width 0.16)
		(layer "In3.Cu")
		(net 60)
	)
	(arc
		(start 81.845389 82.099)
		(mid 81.654047 82.06094)
		(end 81.491835 81.952553)
		(width 0.16)
		(layer "In3.Cu")
		(net 60)
	)
	(arc
		(start 105.390794 82.201512)
		(mid 105.277246 82.125642)
		(end 105.143307 82.099)
		(width 0.16)
		(layer "In3.Cu")
		(net 60)
	)
	(arc
		(start 79.317446 79.778164)
		(mid 79.20906 79.615952)
		(end 79.171 79.424611)
		(width 0.16)
		(layer "In3.Cu")
		(net 60)
	)
	(arc
		(start 115.947446 96.558164)
		(mid 115.83906 96.395952)
		(end 115.801 96.204611)
		(width 0.16)
		(layer "In3.Cu")
		(net 60)
	)
	(arc
		(start 115.801 92.756693)
		(mid 115.774358 92.622753)
		(end 115.698487 92.509205)
		(width 0.16)
		(layer "In3.Cu")
		(net 60)
	)
	(arc
		(start 79.317447 76.341835)
		(mid 79.20906 76.504047)
		(end 79.171 76.695389)
		(width 0.16)
		(layer "In3.Cu")
		(net 60)
	)
	(segment
		(start 82.097323 72.730136)
		(end 82.197823 72.830636)
		(width 0.155)
		(layer "F.Cu")
		(net 61)
	)
	(segment
		(start 82.6005 73.856901)
		(end 82.6005 75.223807)
		(width 0.155)
		(layer "F.Cu")
		(net 61)
	)
	(segment
		(start 80.86789 75.41789)
		(end 80.72496 75.41789)
		(width 0.155)
		(layer "F.Cu")
		(net 61)
	)
	(segment
		(start 82.34427 73.455696)
		(end 82.497988 73.609414)
		(width 0.155)
		(layer "F.Cu")
		(net 61)
	)
	(segment
		(start 80.618894 75.461824)
		(end 80.611512 75.469206)
		(width 0.155)
		(layer "F.Cu")
		(net 61)
	)
	(segment
		(start 80.509 75.716693)
		(end 80.509 75.743307)
		(width 0.155)
		(layer "F.Cu")
		(net 61)
	)
	(segment
		(start 123.875 95.9)
		(end 123.7745 96.0005)
		(width 0.155)
		(layer "F.Cu")
		(net 61)
	)
	(segment
		(start 80.611513 75.990795)
		(end 80.647784 76.027066)
		(width 0.155)
		(layer "F.Cu")
		(net 61)
	)
	(segment
		(start 124.5 95.9)
		(end 123.875 95.9)
		(width 0.155)
		(layer "F.Cu")
		(net 61)
	)
	(segment
		(start 121.841628 96.146947)
		(end 120.546465 97.44211)
		(width 0.155)
		(layer "F.Cu")
		(net 61)
	)
	(segment
		(start 80.75385 76.071)
		(end 81.753307 76.071)
		(width 0.155)
		(layer "F.Cu")
		(net 61)
	)
	(segment
		(start 82.197823 72.830636)
		(end 82.197823 73.102142)
		(width 0.155)
		(layer "F.Cu")
		(net 61)
	)
	(segment
		(start 82.000795 75.968487)
		(end 82.497988 75.471294)
		(width 0.155)
		(layer "F.Cu")
		(net 61)
	)
	(segment
		(start 123.7745 96.0005)
		(end 122.195182 96.0005)
		(width 0.155)
		(layer "F.Cu")
		(net 61)
	)
	(segment
		(start 120.546465 97.44211)
		(end 120.34211 97.44211)
		(width 0.155)
		(layer "F.Cu")
		(net 61)
	)
	(via
		(at 80.86789 75.41789)
		(size 0.45)
		(drill 0.1)
		(layers "F.Cu" "B.Cu")
		(net 61)
	)
	(via
		(at 120.34211 97.44211)
		(size 0.45)
		(drill 0.1)
		(layers "F.Cu" "B.Cu")
		(net 61)
	)
	(arc
		(start 80.509 75.743307)
		(mid 80.535642 75.877247)
		(end 80.611513 75.990795)
		(width 0.155)
		(layer "F.Cu")
		(net 61)
	)
	(arc
		(start 82.34427 73.455696)
		(mid 82.235883 73.293484)
		(end 82.197823 73.102142)
		(width 0.155)
		(layer "F.Cu")
		(net 61)
	)
	(arc
		(start 80.611512 75.469206)
		(mid 80.535642 75.582754)
		(end 80.509 75.716693)
		(width 0.155)
		(layer "F.Cu")
		(net 61)
	)
	(arc
		(start 82.497988 75.471294)
		(mid 82.573858 75.357746)
		(end 82.6005 75.223807)
		(width 0.155)
		(layer "F.Cu")
		(net 61)
	)
	(arc
		(start 80.647784 76.027066)
		(mid 80.696447 76.059582)
		(end 80.75385 76.071)
		(width 0.155)
		(layer "F.Cu")
		(net 61)
	)
	(arc
		(start 121.841628 96.146947)
		(mid 122.00384 96.03856)
		(end 122.195182 96.0005)
		(width 0.155)
		(layer "F.Cu")
		(net 61)
	)
	(arc
		(start 82.6005 73.856901)
		(mid 82.573858 73.722962)
		(end 82.497988 73.609414)
		(width 0.155)
		(layer "F.Cu")
		(net 61)
	)
	(arc
		(start 81.753307 76.071)
		(mid 81.887247 76.044358)
		(end 82.000795 75.968487)
		(width 0.155)
		(layer "F.Cu")
		(net 61)
	)
	(arc
		(start 80.72496 75.41789)
		(mid 80.667557 75.429308)
		(end 80.618894 75.461824)
		(width 0.155)
		(layer "F.Cu")
		(net 61)
	)
	(segment
		(start 79.70928 77.781279)
		(end 79.709279 77.781279)
		(width 0.16)
		(layer "In3.Cu")
		(net 61)
	)
	(segment
		(start 116.099 92.695389)
		(end 116.099 96.143307)
		(width 0.16)
		(layer "In3.Cu")
		(net 61)
	)
	(segment
		(start 79.709279 77.181279)
		(end 79.70928 77.181279)
		(width 0.16)
		(layer "In3.Cu")
		(net 61)
	)
	(segment
		(start 116.799268 96.59964)
		(end 116.799267 96.599641)
		(width 0.16)
		(layer "In3.Cu")
		(net 61)
	)
	(segment
		(start 80.618894 75.461824)
		(end 79.571513 76.509205)
		(width 0.16)
		(layer "In3.Cu")
		(net 61)
	)
	(segment
		(start 118.306693 98.351)
		(end 119.493307 98.351)
		(width 0.16)
		(layer "In3.Cu")
		(net 61)
	)
	(segment
		(start 79.949559 77.421558)
		(end 79.949559 77.541)
		(width 0.16)
		(layer "In3.Cu")
		(net 61)
	)
	(segment
		(start 80.86789 75.41789)
		(end 80.72496 75.41789)
		(width 0.16)
		(layer "In3.Cu")
		(net 61)
	)
	(segment
		(start 79.469 79.171558)
		(end 79.469 79.341)
		(width 0.16)
		(layer "In3.Cu")
		(net 61)
	)
	(segment
		(start 116.201513 96.390795)
		(end 116.410359 96.599641)
		(width 0.16)
		(layer "In3.Cu")
		(net 61)
	)
	(segment
		(start 120.34211 97.58504)
		(end 120.34211 97.44211)
		(width 0.16)
		(layer "In3.Cu")
		(net 61)
	)
	(segment
		(start 117.329597 96.847127)
		(end 117.188176 96.988549)
		(width 0.16)
		(layer "In3.Cu")
		(net 61)
	)
	(segment
		(start 79.571513 79.610795)
		(end 81.659206 81.698488)
		(width 0.16)
		(layer "In3.Cu")
		(net 61)
	)
	(segment
		(start 81.906693 81.801)
		(end 105.204611 81.801)
		(width 0.16)
		(layer "In3.Cu")
		(net 61)
	)
	(segment
		(start 105.558165 81.947447)
		(end 115.952554 92.341836)
		(width 0.16)
		(layer "In3.Cu")
		(net 61)
	)
	(segment
		(start 117.329596 96.847128)
		(end 117.329597 96.847127)
		(width 0.16)
		(layer "In3.Cu")
		(net 61)
	)
	(segment
		(start 79.684279 78.356279)
		(end 79.68428 78.356279)
		(width 0.16)
		(layer "In3.Cu")
		(net 61)
	)
	(segment
		(start 79.469 78.021558)
		(end 79.469 78.141)
		(width 0.16)
		(layer "In3.Cu")
		(net 61)
	)
	(segment
		(start 117.329598 96.458221)
		(end 117.329597 96.458219)
		(width 0.16)
		(layer "In3.Cu")
		(net 61)
	)
	(segment
		(start 116.799267 96.599641)
		(end 116.940689 96.45822)
		(width 0.16)
		(layer "In3.Cu")
		(net 61)
	)
	(segment
		(start 117.188175 97.377457)
		(end 118.059206 98.248488)
		(width 0.16)
		(layer "In3.Cu")
		(net 61)
	)
	(segment
		(start 79.469 79.341)
		(end 79.469 79.363307)
		(width 0.16)
		(layer "In3.Cu")
		(net 61)
	)
	(segment
		(start 79.68428 78.956279)
		(end 79.684279 78.956279)
		(width 0.16)
		(layer "In3.Cu")
		(net 61)
	)
	(segment
		(start 79.899559 78.571558)
		(end 79.899559 78.741)
		(width 0.16)
		(layer "In3.Cu")
		(net 61)
	)
	(segment
		(start 119.740795 98.248487)
		(end 120.298176 97.691106)
		(width 0.16)
		(layer "In3.Cu")
		(net 61)
	)
	(segment
		(start 117.188177 97.377458)
		(end 117.188175 97.377457)
		(width 0.16)
		(layer "In3.Cu")
		(net 61)
	)
	(segment
		(start 79.469 76.756693)
		(end 79.469 76.941)
		(width 0.16)
		(layer "In3.Cu")
		(net 61)
	)
	(arc
		(start 79.709279 77.781279)
		(mid 79.539376 77.851655)
		(end 79.469 78.021558)
		(width 0.16)
		(layer "In3.Cu")
		(net 61)
	)
	(arc
		(start 79.571513 76.509205)
		(mid 79.495642 76.622753)
		(end 79.469 76.756693)
		(width 0.16)
		(layer "In3.Cu")
		(net 61)
	)
	(arc
		(start 80.618894 75.461824)
		(mid 80.667557 75.429308)
		(end 80.72496 75.41789)
		(width 0.16)
		(layer "In3.Cu")
		(net 61)
	)
	(arc
		(start 79.68428 78.356279)
		(mid 79.836505 78.419333)
		(end 79.899559 78.571558)
		(width 0.16)
		(layer "In3.Cu")
		(net 61)
	)
	(arc
		(start 79.899559 78.741)
		(mid 79.836505 78.893225)
		(end 79.68428 78.956279)
		(width 0.16)
		(layer "In3.Cu")
		(net 61)
	)
	(arc
		(start 120.298176 97.691106)
		(mid 120.330692 97.642443)
		(end 120.34211 97.58504)
		(width 0.16)
		(layer "In3.Cu")
		(net 61)
	)
	(arc
		(start 118.059206 98.248488)
		(mid 118.172754 98.324358)
		(end 118.306693 98.351)
		(width 0.16)
		(layer "In3.Cu")
		(net 61)
	)
	(arc
		(start 79.469 79.363307)
		(mid 79.495642 79.497247)
		(end 79.571513 79.610795)
		(width 0.16)
		(layer "In3.Cu")
		(net 61)
	)
	(arc
		(start 116.410359 96.599641)
		(mid 116.604814 96.680186)
		(end 116.799268 96.59964)
		(width 0.16)
		(layer "In3.Cu")
		(net 61)
	)
	(arc
		(start 79.684279 78.956279)
		(mid 79.532054 79.019333)
		(end 79.469 79.171558)
		(width 0.16)
		(layer "In3.Cu")
		(net 61)
	)
	(arc
		(start 79.70928 77.181279)
		(mid 79.879183 77.251655)
		(end 79.949559 77.421558)
		(width 0.16)
		(layer "In3.Cu")
		(net 61)
	)
	(arc
		(start 116.099 96.143307)
		(mid 116.125642 96.277247)
		(end 116.201513 96.390795)
		(width 0.16)
		(layer "In3.Cu")
		(net 61)
	)
	(arc
		(start 116.940689 96.45822)
		(mid 117.135144 96.377675)
		(end 117.329598 96.458221)
		(width 0.16)
		(layer "In3.Cu")
		(net 61)
	)
	(arc
		(start 115.952554 92.341836)
		(mid 116.06094 92.504048)
		(end 116.099 92.695389)
		(width 0.16)
		(layer "In3.Cu")
		(net 61)
	)
	(arc
		(start 117.188176 96.988549)
		(mid 117.107631 97.183004)
		(end 117.188177 97.377458)
		(width 0.16)
		(layer "In3.Cu")
		(net 61)
	)
	(arc
		(start 105.204611 81.801)
		(mid 105.395953 81.83906)
		(end 105.558165 81.947447)
		(width 0.16)
		(layer "In3.Cu")
		(net 61)
	)
	(arc
		(start 79.469 76.941)
		(mid 79.539376 77.110903)
		(end 79.709279 77.181279)
		(width 0.16)
		(layer "In3.Cu")
		(net 61)
	)
	(arc
		(start 79.469 78.141)
		(mid 79.532054 78.293225)
		(end 79.684279 78.356279)
		(width 0.16)
		(layer "In3.Cu")
		(net 61)
	)
	(arc
		(start 81.659206 81.698488)
		(mid 81.772754 81.774358)
		(end 81.906693 81.801)
		(width 0.16)
		(layer "In3.Cu")
		(net 61)
	)
	(arc
		(start 79.949559 77.541)
		(mid 79.879183 77.710903)
		(end 79.70928 77.781279)
		(width 0.16)
		(layer "In3.Cu")
		(net 61)
	)
	(arc
		(start 117.329597 96.458219)
		(mid 117.410142 96.652674)
		(end 117.329596 96.847128)
		(width 0.16)
		(layer "In3.Cu")
		(net 61)
	)
	(arc
		(start 119.493307 98.351)
		(mid 119.627247 98.324358)
		(end 119.740795 98.248487)
		(width 0.16)
		(layer "In3.Cu")
		(net 61)
	)
	(segment
		(start 78.4195 75.184819)
		(end 78.4195 74.876901)
		(width 0.155)
		(layer "F.Cu")
		(net 62)
	)
	(segment
		(start 121.590088 99.221336)
		(end 122.909412 97.902013)
		(width 0.155)
		(layer "F.Cu")
		(net 62)
	)
	(segment
		(start 76.34211 75.80789)
		(end 76.484333 75.80789)
		(width 0.155)
		(layer "F.Cu")
		(net 62)
	)
	(segment
		(start 76.590399 75.851824)
		(end 76.741629 76.003054)
		(width 0.155)
		(layer "F.Cu")
		(net 62)
	)
	(segment
		(start 79.266901 74.0295)
		(end 80.384819 74.0295)
		(width 0.155)
		(layer "F.Cu")
		(net 62)
	)
	(segment
		(start 80.738373 73.883053)
		(end 80.850377 73.771049)
		(width 0.155)
		(layer "F.Cu")
		(net 62)
	)
	(segment
		(start 124.5 97.9)
		(end 123.875 97.9)
		(width 0.155)
		(layer "F.Cu")
		(net 62)
	)
	(segment
		(start 77.808373 76.003053)
		(end 78.273054 75.538372)
		(width 0.155)
		(layer "F.Cu")
		(net 62)
	)
	(segment
		(start 123.7745 97.7995)
		(end 123.1569 97.7995)
		(width 0.155)
		(layer "F.Cu")
		(net 62)
	)
	(segment
		(start 121.590088 99.221336)
		(end 121.590088 99.429933)
		(width 0.155)
		(layer "F.Cu")
		(net 62)
	)
	(segment
		(start 78.522013 74.629413)
		(end 79.019414 74.132012)
		(width 0.155)
		(layer "F.Cu")
		(net 62)
	)
	(segment
		(start 77.095182 76.1495)
		(end 77.454819 76.1495)
		(width 0.155)
		(layer "F.Cu")
		(net 62)
	)
	(segment
		(start 80.996823 73.417496)
		(end 80.996823 72.830636)
		(width 0.155)
		(layer "F.Cu")
		(net 62)
	)
	(segment
		(start 123.875 97.9)
		(end 123.7745 97.7995)
		(width 0.155)
		(layer "F.Cu")
		(net 62)
	)
	(segment
		(start 80.996823 72.830636)
		(end 81.097323 72.730136)
		(width 0.155)
		(layer "F.Cu")
		(net 62)
	)
	(via
		(at 121.590088 99.429933)
		(size 0.45)
		(drill 0.1)
		(layers "F.Cu" "B.Cu")
		(net 62)
	)
	(via
		(at 76.34211 75.80789)
		(size 0.45)
		(drill 0.1)
		(layers "F.Cu" "B.Cu")
		(net 62)
	)
	(arc
		(start 79.266901 74.0295)
		(mid 79.132962 74.056142)
		(end 79.019414 74.132012)
		(width 0.155)
		(layer "F.Cu")
		(net 62)
	)
	(arc
		(start 80.850377 73.771049)
		(mid 80.958763 73.608837)
		(end 80.996823 73.417496)
		(width 0.155)
		(layer "F.Cu")
		(net 62)
	)
	(arc
		(start 77.808373 76.003053)
		(mid 77.646161 76.11144)
		(end 77.454819 76.1495)
		(width 0.155)
		(layer "F.Cu")
		(net 62)
	)
	(arc
		(start 78.4195 75.184819)
		(mid 78.38144 75.37616)
		(end 78.273054 75.538372)
		(width 0.155)
		(layer "F.Cu")
		(net 62)
	)
	(arc
		(start 76.741629 76.003054)
		(mid 76.903841 76.11144)
		(end 77.095182 76.1495)
		(width 0.155)
		(layer "F.Cu")
		(net 62)
	)
	(arc
		(start 78.4195 74.876901)
		(mid 78.446142 74.742961)
		(end 78.522013 74.629413)
		(width 0.155)
		(layer "F.Cu")
		(net 62)
	)
	(arc
		(start 76.484333 75.80789)
		(mid 76.541736 75.819308)
		(end 76.590399 75.851824)
		(width 0.155)
		(layer "F.Cu")
		(net 62)
	)
	(arc
		(start 80.384819 74.0295)
		(mid 80.576161 73.99144)
		(end 80.738373 73.883053)
		(width 0.155)
		(layer "F.Cu")
		(net 62)
	)
	(arc
		(start 122.909412 97.902013)
		(mid 123.02296 97.826142)
		(end 123.1569 97.7995)
		(width 0.155)
		(layer "F.Cu")
		(net 62)
	)
	(segment
		(start 120.604611 99.999)
		(end 117.695389 99.999)
		(width 0.16)
		(layer "In3.Cu")
		(net 62)
	)
	(segment
		(start 120.958164 99.852553)
		(end 121.380784 99.429933)
		(width 0.16)
		(layer "In3.Cu")
		(net 62)
	)
	(segment
		(start 79.795389 83.499)
		(end 104.343307 83.499)
		(width 0.16)
		(layer "In3.Cu")
		(net 62)
	)
	(segment
		(start 114.198487 93.209205)
		(end 104.590794 83.601512)
		(width 0.16)
		(layer "In3.Cu")
		(net 62)
	)
	(segment
		(start 120.604611 99.999)
		(end 120.60461 99.999)
		(width 0.16)
		(layer "In3.Cu")
		(net 62)
	)
	(segment
		(start 117.341835 99.852553)
		(end 114.447446 96.958164)
		(width 0.16)
		(layer "In3.Cu")
		(net 62)
	)
	(segment
		(start 121.380784 99.429933)
		(end 121.590088 99.429933)
		(width 0.16)
		(layer "In3.Cu")
		(net 62)
	)
	(segment
		(start 79.441835 83.352553)
		(end 77.397446 81.308164)
		(width 0.16)
		(layer "In3.Cu")
		(net 62)
	)
	(segment
		(start 114.301 96.604611)
		(end 114.301 93.456693)
		(width 0.16)
		(layer "In3.Cu")
		(net 62)
	)
	(segment
		(start 76.48504 75.80789)
		(end 76.34211 75.80789)
		(width 0.16)
		(layer "In3.Cu")
		(net 62)
	)
	(segment
		(start 77.251 80.954611)
		(end 77.251 76.656693)
		(width 0.16)
		(layer "In3.Cu")
		(net 62)
	)
	(segment
		(start 77.148487 76.409205)
		(end 76.591106 75.851824)
		(width 0.16)
		(layer "In3.Cu")
		(net 62)
	)
	(arc
		(start 114.301 93.456693)
		(mid 114.274358 93.322753)
		(end 114.198487 93.209205)
		(width 0.16)
		(layer "In3.Cu")
		(net 62)
	)
	(arc
		(start 117.695389 99.999)
		(mid 117.504047 99.96094)
		(end 117.341835 99.852553)
		(width 0.16)
		(layer "In3.Cu")
		(net 62)
	)
	(arc
		(start 120.958164 99.852553)
		(mid 120.795952 99.96094)
		(end 120.60461 99.999)
		(width 0.16)
		(layer "In3.Cu")
		(net 62)
	)
	(arc
		(start 77.251 80.954611)
		(mid 77.28906 81.145952)
		(end 77.397446 81.308164)
		(width 0.16)
		(layer "In3.Cu")
		(net 62)
	)
	(arc
		(start 114.447446 96.958164)
		(mid 114.33906 96.795952)
		(end 114.301 96.604611)
		(width 0.16)
		(layer "In3.Cu")
		(net 62)
	)
	(arc
		(start 77.251 76.656693)
		(mid 77.224358 76.522753)
		(end 77.148487 76.409205)
		(width 0.16)
		(layer "In3.Cu")
		(net 62)
	)
	(arc
		(start 76.591106 75.851824)
		(mid 76.542443 75.819308)
		(end 76.48504 75.80789)
		(width 0.16)
		(layer "In3.Cu")
		(net 62)
	)
	(arc
		(start 104.590794 83.601512)
		(mid 104.477246 83.525642)
		(end 104.343307 83.499)
		(width 0.16)
		(layer "In3.Cu")
		(net 62)
	)
	(arc
		(start 79.441835 83.352553)
		(mid 79.604047 83.46094)
		(end 79.795389 83.499)
		(width 0.16)
		(layer "In3.Cu")
		(net 62)
	)
	(segment
		(start 80.697823 73.355776)
		(end 80.697823 72.830636)
		(width 0.155)
		(layer "F.Cu")
		(net 63)
	)
	(segment
		(start 78.266947 74.461627)
		(end 78.851628 73.876946)
		(width 0.155)
		(layer "F.Cu")
		(net 63)
	)
	(segment
		(start 76.801824 75.640399)
		(end 76.909413 75.747988)
		(width 0.155)
		(layer "F.Cu")
		(net 63)
	)
	(segment
		(start 121.378663 99.009911)
		(end 122.741628 97.646947)
		(width 0.155)
		(layer "F.Cu")
		(net 63)
	)
	(segment
		(start 77.640587 75.747987)
		(end 78.017988 75.370586)
		(width 0.155)
		(layer "F.Cu")
		(net 63)
	)
	(segment
		(start 76.75789 75.39211)
		(end 76.75789 75.534333)
		(width 0.155)
		(layer "F.Cu")
		(net 63)
	)
	(segment
		(start 77.1569 75.8505)
		(end 77.393099 75.8505)
		(width 0.155)
		(layer "F.Cu")
		(net 63)
	)
	(segment
		(start 78.1205 75.123099)
		(end 78.1205 74.815181)
		(width 0.155)
		(layer "F.Cu")
		(net 63)
	)
	(segment
		(start 124.5 97.4)
		(end 123.875 97.4)
		(width 0.155)
		(layer "F.Cu")
		(net 63)
	)
	(segment
		(start 79.205181 73.7305)
		(end 80.323099 73.7305)
		(width 0.155)
		(layer "F.Cu")
		(net 63)
	)
	(segment
		(start 121.378663 99.009911)
		(end 121.170066 99.009911)
		(width 0.155)
		(layer "F.Cu")
		(net 63)
	)
	(segment
		(start 80.570587 73.627987)
		(end 80.595311 73.603263)
		(width 0.155)
		(layer "F.Cu")
		(net 63)
	)
	(segment
		(start 123.7745 97.5005)
		(end 123.095182 97.5005)
		(width 0.155)
		(layer "F.Cu")
		(net 63)
	)
	(segment
		(start 80.697823 72.830636)
		(end 80.597323 72.730136)
		(width 0.155)
		(layer "F.Cu")
		(net 63)
	)
	(segment
		(start 123.875 97.4)
		(end 123.7745 97.5005)
		(width 0.155)
		(layer "F.Cu")
		(net 63)
	)
	(via
		(at 76.75789 75.39211)
		(size 0.45)
		(drill 0.1)
		(layers "F.Cu" "B.Cu")
		(net 63)
	)
	(via
		(at 121.170066 99.009911)
		(size 0.45)
		(drill 0.1)
		(layers "F.Cu" "B.Cu")
		(net 63)
	)
	(arc
		(start 78.266947 74.461627)
		(mid 78.15856 74.623839)
		(end 78.1205 74.815181)
		(width 0.155)
		(layer "F.Cu")
		(net 63)
	)
	(arc
		(start 80.323099 73.7305)
		(mid 80.457039 73.703858)
		(end 80.570587 73.627987)
		(width 0.155)
		(layer "F.Cu")
		(net 63)
	)
	(arc
		(start 76.801824 75.640399)
		(mid 76.769308 75.591736)
		(end 76.75789 75.534333)
		(width 0.155)
		(layer "F.Cu")
		(net 63)
	)
	(arc
		(start 80.697823 73.355776)
		(mid 80.671181 73.489715)
		(end 80.595311 73.603263)
		(width 0.155)
		(layer "F.Cu")
		(net 63)
	)
	(arc
		(start 122.741628 97.646947)
		(mid 122.90384 97.53856)
		(end 123.095182 97.5005)
		(width 0.155)
		(layer "F.Cu")
		(net 63)
	)
	(arc
		(start 78.851628 73.876946)
		(mid 79.01384 73.76856)
		(end 79.205181 73.7305)
		(width 0.155)
		(layer "F.Cu")
		(net 63)
	)
	(arc
		(start 76.909413 75.747988)
		(mid 77.022961 75.823858)
		(end 77.1569 75.8505)
		(width 0.155)
		(layer "F.Cu")
		(net 63)
	)
	(arc
		(start 78.017988 75.370586)
		(mid 78.093858 75.257038)
		(end 78.1205 75.123099)
		(width 0.155)
		(layer "F.Cu")
		(net 63)
	)
	(arc
		(start 77.640587 75.747987)
		(mid 77.527039 75.823858)
		(end 77.393099 75.8505)
		(width 0.155)
		(layer "F.Cu")
		(net 63)
	)
	(segment
		(start 78.471044 81.677483)
		(end 78.493292 81.655234)
		(width 0.16)
		(layer "In3.Cu")
		(net 63)
	)
	(segment
		(start 121.170066 99.009911)
		(end 121.170066 99.219215)
		(width 0.16)
		(layer "In3.Cu")
		(net 63)
	)
	(segment
		(start 78.471043 81.960325)
		(end 78.471043 81.960326)
		(width 0.16)
		(layer "In3.Cu")
		(net 63)
	)
	(segment
		(start 114.452554 93.041836)
		(end 104.758165 83.347447)
		(width 0.16)
		(layer "In3.Cu")
		(net 63)
	)
	(segment
		(start 104.404611 83.201)
		(end 79.918825 83.201)
		(width 0.16)
		(layer "In3.Cu")
		(net 63)
	)
	(segment
		(start 117.509206 99.598488)
		(end 114.701513 96.790795)
		(width 0.16)
		(layer "In3.Cu")
		(net 63)
	)
	(segment
		(start 77.549 80.831175)
		(end 77.549 76.595389)
		(width 0.16)
		(layer "In3.Cu")
		(net 63)
	)
	(segment
		(start 121.170066 99.219215)
		(end 120.834727 99.554554)
		(width 0.16)
		(layer "In3.Cu")
		(net 63)
	)
	(segment
		(start 114.599 96.543307)
		(end 114.599 93.395389)
		(width 0.16)
		(layer "In3.Cu")
		(net 63)
	)
	(segment
		(start 78.493293 81.372391)
		(end 78.493294 81.372391)
		(width 0.16)
		(layer "In3.Cu")
		(net 63)
	)
	(segment
		(start 78.210451 81.372392)
		(end 78.188202 81.39464)
		(width 0.16)
		(layer "In3.Cu")
		(net 63)
	)
	(segment
		(start 77.905359 81.394641)
		(end 77.695447 81.184729)
		(width 0.16)
		(layer "In3.Cu")
		(net 63)
	)
	(segment
		(start 76.75789 75.53504)
		(end 76.75789 75.39211)
		(width 0.16)
		(layer "In3.Cu")
		(net 63)
	)
	(segment
		(start 77.402554 76.241836)
		(end 76.801824 75.641106)
		(width 0.16)
		(layer "In3.Cu")
		(net 63)
	)
	(segment
		(start 120.481174 99.701)
		(end 117.756693 99.701)
		(width 0.16)
		(layer "In3.Cu")
		(net 63)
	)
	(segment
		(start 79.565272 83.054554)
		(end 78.471043 81.960325)
		(width 0.16)
		(layer "In3.Cu")
		(net 63)
	)
	(arc
		(start 78.188202 81.39464)
		(mid 78.046781 81.453219)
		(end 77.905359 81.394641)
		(width 0.16)
		(layer "In3.Cu")
		(net 63)
	)
	(arc
		(start 79.918825 83.201)
		(mid 79.727484 83.16294)
		(end 79.565272 83.054554)
		(width 0.16)
		(layer "In3.Cu")
		(net 63)
	)
	(arc
		(start 76.801824 75.641106)
		(mid 76.769308 75.592443)
		(end 76.75789 75.53504)
		(width 0.16)
		(layer "In3.Cu")
		(net 63)
	)
	(arc
		(start 78.471043 81.960326)
		(mid 78.412465 81.818904)
		(end 78.471044 81.677483)
		(width 0.16)
		(layer "In3.Cu")
		(net 63)
	)
	(arc
		(start 117.756693 99.701)
		(mid 117.622754 99.674358)
		(end 117.509206 99.598488)
		(width 0.16)
		(layer "In3.Cu")
		(net 63)
	)
	(arc
		(start 104.758165 83.347447)
		(mid 104.595953 83.23906)
		(end 104.404611 83.201)
		(width 0.16)
		(layer "In3.Cu")
		(net 63)
	)
	(arc
		(start 78.493292 81.655234)
		(mid 78.551871 81.513813)
		(end 78.493293 81.372391)
		(width 0.16)
		(layer "In3.Cu")
		(net 63)
	)
	(arc
		(start 77.549 76.595389)
		(mid 77.51094 76.404048)
		(end 77.402554 76.241836)
		(width 0.16)
		(layer "In3.Cu")
		(net 63)
	)
	(arc
		(start 78.493294 81.372391)
		(mid 78.351872 81.313813)
		(end 78.210451 81.372392)
		(width 0.16)
		(layer "In3.Cu")
		(net 63)
	)
	(arc
		(start 114.701513 96.790795)
		(mid 114.625642 96.677247)
		(end 114.599 96.543307)
		(width 0.16)
		(layer "In3.Cu")
		(net 63)
	)
	(arc
		(start 114.599 93.395389)
		(mid 114.56094 93.204048)
		(end 114.452554 93.041836)
		(width 0.16)
		(layer "In3.Cu")
		(net 63)
	)
	(arc
		(start 77.695447 81.184729)
		(mid 77.58706 81.022517)
		(end 77.549 80.831175)
		(width 0.16)
		(layer "In3.Cu")
		(net 63)
	)
	(arc
		(start 120.834727 99.554554)
		(mid 120.672515 99.66294)
		(end 120.481174 99.701)
		(width 0.16)
		(layer "In3.Cu")
		(net 63)
	)
	(segment
		(start 121.74 100.86)
		(end 123.7 98.9)
		(width 0.125)
		(layer "F.Cu")
		(net 64)
	)
	(segment
		(start 78.847323 81.347323)
		(end 78.847323 80.205136)
		(width 0.15)
		(layer "F.Cu")
		(net 64)
	)
	(segment
		(start 123.678015 108.931323)
		(end 123.531323 108.931323)
		(width 0.125)
		(layer "F.Cu")
		(net 64)
	)
	(segment
		(start 125.88 98.6)
		(end 125.58 98.9)
		(width 0.15)
		(layer "F.Cu")
		(net 64)
	)
	(segment
		(start 79.7 82.2)
		(end 78.847323 81.347323)
		(width 0.15)
		(layer "F.Cu")
		(net 64)
	)
	(segment
		(start 121.74 107.14)
		(end 121.74 100.86)
		(width 0.125)
		(layer "F.Cu")
		(net 64)
	)
	(segment
		(start 125.58 98.9)
		(end 124.5 98.9)
		(width 0.15)
		(layer "F.Cu")
		(net 64)
	)
	(segment
		(start 79.8 82.2)
		(end 79.7 82.2)
		(width 0.15)
		(layer "F.Cu")
		(net 64)
	)
	(segment
		(start 126.57 98.6)
		(end 125.88 98.6)
		(width 0.15)
		(layer "F.Cu")
		(net 64)
	)
	(segment
		(start 123.531323 108.931323)
		(end 121.74 107.14)
		(width 0.125)
		(layer "F.Cu")
		(net 64)
	)
	(segment
		(start 123.7 98.9)
		(end 124.5 98.9)
		(width 0.125)
		(layer "F.Cu")
		(net 64)
	)
	(via
		(at 79.8 82.2)
		(size 0.45)
		(drill 0.1)
		(layers "F.Cu" "B.Cu")
		(net 64)
	)
	(via
		(at 123.678015 108.931323)
		(size 0.45)
		(drill 0.1)
		(layers "F.Cu" "B.Cu")
		(net 64)
	)
	(segment
		(start 123.546692 108.8)
		(end 123 108.8)
		(width 0.125)
		(layer "In5.Cu")
		(net 64)
	)
	(segment
		(start 92.85 83.403555)
		(end 92.096445 82.65)
		(width 0.125)
		(layer "In5.Cu")
		(net 64)
	)
	(segment
		(start 92.85 97.52)
		(end 92.85 83.403555)
		(width 0.125)
		(layer "In5.Cu")
		(net 64)
	)
	(segment
		(start 122.55 109.25)
		(end 99.67 109.25)
		(width 0.125)
		(layer "In5.Cu")
		(net 64)
	)
	(segment
		(start 93.64 103.22)
		(end 93.64 98.31)
		(width 0.125)
		(layer "In5.Cu")
		(net 64)
	)
	(segment
		(start 99.67 109.25)
		(end 93.64 103.22)
		(width 0.125)
		(layer "In5.Cu")
		(net 64)
	)
	(segment
		(start 93.64 98.31)
		(end 92.85 97.52)
		(width 0.125)
		(layer "In5.Cu")
		(net 64)
	)
	(segment
		(start 80.25 82.65)
		(end 79.8 82.2)
		(width 0.125)
		(layer "In5.Cu")
		(net 64)
	)
	(segment
		(start 123.678015 108.931323)
		(end 123.546692 108.8)
		(width 0.125)
		(layer "In5.Cu")
		(net 64)
	)
	(segment
		(start 92.096445 82.65)
		(end 80.25 82.65)
		(width 0.125)
		(layer "In5.Cu")
		(net 64)
	)
	(segment
		(start 123 108.8)
		(end 122.55 109.25)
		(width 0.125)
		(layer "In5.Cu")
		(net 64)
	)
	(segment
		(start 123.2 109.05)
		(end 123.2 109.25)
		(width 0.125)
		(layer "F.Cu")
		(net 65)
	)
	(segment
		(start 121.405 101.505)
		(end 121.405 107.255)
		(width 0.125)
		(layer "F.Cu")
		(net 65)
	)
	(segment
		(start 115.7 98.4)
		(end 115.7 98.2)
		(width 0.15)
		(layer "F.Cu")
		(net 65)
	)
	(segment
		(start 115.95 98.65)
		(end 115.7 98.4)
		(width 0.15)
		(layer "F.Cu")
		(net 65)
	)
	(segment
		(start 77 69.45)
		(end 77 70.2)
		(width 0.15)
		(layer "F.Cu")
		(net 65)
	)
	(segment
		(start 117 98.65)
		(end 115.95 98.65)
		(width 0.15)
		(layer "F.Cu")
		(net 65)
	)
	(segment
		(start 77.45 70.65)
		(end 78.35 70.65)
		(width 0.15)
		(layer "F.Cu")
		(net 65)
	)
	(segment
		(start 121.405 107.255)
		(end 123.2 109.05)
		(width 0.125)
		(layer "F.Cu")
		(net 65)
	)
	(segment
		(start 117 98.65)
		(end 118.55 98.65)
		(width 0.125)
		(layer "F.Cu")
		(net 65)
	)
	(segment
		(start 115.5 98)
		(end 115.085 98)
		(width 0.15)
		(layer "F.Cu")
		(net 65)
	)
	(segment
		(start 118.55 98.65)
		(end 121.405 101.505)
		(width 0.125)
		(layer "F.Cu")
		(net 65)
	)
	(segment
		(start 78.35 70.65)
		(end 78.597323 70.897323)
		(width 0.15)
		(layer "F.Cu")
		(net 65)
	)
	(segment
		(start 115.7 98.2)
		(end 115.5 98)
		(width 0.15)
		(layer "F.Cu")
		(net 65)
	)
	(segment
		(start 77 70.2)
		(end 77.45 70.65)
		(width 0.15)
		(layer "F.Cu")
		(net 65)
	)
	(segment
		(start 78.597323 70.897323)
		(end 78.597323 72.005136)
		(width 0.15)
		(layer "F.Cu")
		(net 65)
	)
	(via
		(at 123.2 109.25)
		(size 0.45)
		(drill 0.1)
		(layers "F.Cu" "B.Cu")
		(net 65)
	)
	(via
		(at 77 69.45)
		(size 0.45)
		(drill 0.1)
		(layers "F.Cu" "B.Cu")
		(net 65)
	)
	(segment
		(start 79.3 80.2)
		(end 79.3 82.4)
		(width 0.125)
		(layer "In5.Cu")
		(net 65)
	)
	(segment
		(start 75.75 73.5)
		(end 75.1 74.15)
		(width 0.125)
		(layer "In5.Cu")
		(net 65)
	)
	(segment
		(start 91.992892 82.9)
		(end 92.6 83.507108)
		(width 0.125)
		(layer "In5.Cu")
		(net 65)
	)
	(segment
		(start 92.6 83.507108)
		(end 92.6 97.646447)
		(width 0.125)
		(layer "In5.Cu")
		(net 65)
	)
	(segment
		(start 75.75 71.65)
		(end 75.75 73.5)
		(width 0.125)
		(layer "In5.Cu")
		(net 65)
	)
	(segment
		(start 122.9 109.55)
		(end 123.2 109.25)
		(width 0.125)
		(layer "In5.Cu")
		(net 65)
	)
	(segment
		(start 78.4 79.3)
		(end 79.3 80.2)
		(width 0.125)
		(layer "In5.Cu")
		(net 65)
	)
	(segment
		(start 92.6 97.646447)
		(end 93.39 98.436447)
		(width 0.125)
		(layer "In5.Cu")
		(net 65)
	)
	(segment
		(start 75.1 74.15)
		(end 75.1 75.941697)
		(width 0.125)
		(layer "In5.Cu")
		(net 65)
	)
	(segment
		(start 76.1 79.3)
		(end 78.4 79.3)
		(width 0.125)
		(layer "In5.Cu")
		(net 65)
	)
	(segment
		(start 93.39 103.44)
		(end 99.5 109.55)
		(width 0.125)
		(layer "In5.Cu")
		(net 65)
	)
	(segment
		(start 77 69.45)
		(end 76.9 69.55)
		(width 0.125)
		(layer "In5.Cu")
		(net 65)
	)
	(segment
		(start 76.9 70.5)
		(end 75.75 71.65)
		(width 0.125)
		(layer "In5.Cu")
		(net 65)
	)
	(segment
		(start 99.5 109.55)
		(end 122.9 109.55)
		(width 0.125)
		(layer "In5.Cu")
		(net 65)
	)
	(segment
		(start 93.39 98.436447)
		(end 93.39 103.44)
		(width 0.125)
		(layer "In5.Cu")
		(net 65)
	)
	(segment
		(start 76.9 69.55)
		(end 76.9 70.5)
		(width 0.125)
		(layer "In5.Cu")
		(net 65)
	)
	(segment
		(start 75.128954 78.328954)
		(end 76.1 79.3)
		(width 0.125)
		(layer "In5.Cu")
		(net 65)
	)
	(segment
		(start 79.8 82.9)
		(end 91.992892 82.9)
		(width 0.125)
		(layer "In5.Cu")
		(net 65)
	)
	(segment
		(start 75.128954 75.970651)
		(end 75.128954 78.328954)
		(width 0.125)
		(layer "In5.Cu")
		(net 65)
	)
	(segment
		(start 75.1 75.941697)
		(end 75.128954 75.970651)
		(width 0.125)
		(layer "In5.Cu")
		(net 65)
	)
	(segment
		(start 79.3 82.4)
		(end 79.8 82.9)
		(width 0.125)
		(layer "In5.Cu")
		(net 65)
	)
	(segment
		(start 78.7985 81.803132)
		(end 78.270823 81.275455)
		(width 0.125)
		(layer "F.Cu")
		(net 66)
	)
	(segment
		(start 78.170368 83.1)
		(end 78.7985 82.471868)
		(width 0.125)
		(layer "F.Cu")
		(net 66)
	)
	(segment
		(start 76.96 82.71)
		(end 77.35 83.1)
		(width 0.125)
		(layer "F.Cu")
		(net 66)
	)
	(segment
		(start 78.270823 81.275455)
		(end 78.270823 81.006636)
		(width 0.125)
		(layer "F.Cu")
		(net 66)
	)
	(segment
		(start 76.96 82.69)
		(end 76.96 82.71)
		(width 0.125)
		(layer "F.Cu")
		(net 66)
	)
	(segment
		(start 77.35 83.1)
		(end 78.170368 83.1)
		(width 0.125)
		(layer "F.Cu")
		(net 66)
	)
	(segment
		(start 78.7985 82.471868)
		(end 78.7985 81.803132)
		(width 0.125)
		(layer "F.Cu")
		(net 66)
	)
	(via
		(at 76.96 82.69)
		(size 0.45)
		(drill 0.1)
		(layers "F.Cu" "B.Cu")
		(net 66)
	)
	(segment
		(start 77.2 83.827512)
		(end 77.2 82.93)
		(width 0.125)
		(layer "In5.Cu")
		(net 66)
	)
	(segment
		(start 46.075 89.427512)
		(end 46.075 87.752512)
		(width 0.125)
		(layer "In5.Cu")
		(net 66)
	)
	(segment
		(start 44.075 91.427512)
		(end 46.075 89.427512)
		(width 0.125)
		(layer "In5.Cu")
		(net 66)
	)
	(segment
		(start 33.3 111.202512)
		(end 34.272488 112.175)
		(width 0.125)
		(layer "In5.Cu")
		(net 66)
	)
	(segment
		(start 46.075 87.752512)
		(end 53.277512 80.55)
		(width 0.125)
		(layer "In5.Cu")
		(net 66)
	)
	(segment
		(start 38.883556 112.562936)
		(end 38.883556 112.695)
		(width 0.125)
		(layer "In5.Cu")
		(net 66)
	)
	(segment
		(start 72.797488 80.55)
		(end 73.375 81.127512)
		(width 0.125)
		(layer "In5.Cu")
		(net 66)
	)
	(segment
		(start 34.272488 112.175)
		(end 35.572488 112.175)
		(width 0.125)
		(layer "In5.Cu")
		(net 66)
	)
	(segment
		(start 39.795 109.542488)
		(end 39.795 105.567512)
		(width 0.125)
		(layer "In5.Cu")
		(net 66)
	)
	(segment
		(start 33.3 110.772488)
		(end 33.3 111.202512)
		(width 0.125)
		(layer "In5.Cu")
		(net 66)
	)
	(segment
		(start 73.375 81.577512)
		(end 75.997488 84.2)
		(width 0.125)
		(layer "In5.Cu")
		(net 66)
	)
	(segment
		(start 76.827512 84.2)
		(end 77.2 83.827512)
		(width 0.125)
		(layer "In5.Cu")
		(net 66)
	)
	(segment
		(start 39.063556 112.875)
		(end 39.153556 112.875)
		(width 0.125)
		(layer "In5.Cu")
		(net 66)
	)
	(segment
		(start 36.272488 112.875)
		(end 38.253556 112.875)
		(width 0.125)
		(layer "In5.Cu")
		(net 66)
	)
	(segment
		(start 44.075 101.287512)
		(end 44.075 91.427512)
		(width 0.125)
		(layer "In5.Cu")
		(net 66)
	)
	(segment
		(start 77.2 82.93)
		(end 76.96 82.69)
		(width 0.125)
		(layer "In5.Cu")
		(net 66)
	)
	(segment
		(start 35.572488 112.175)
		(end 36.272488 112.875)
		(width 0.125)
		(layer "In5.Cu")
		(net 66)
	)
	(segment
		(start 73.375 81.127512)
		(end 73.375 81.577512)
		(width 0.125)
		(layer "In5.Cu")
		(net 66)
	)
	(segment
		(start 40.327512 112.875)
		(end 40.875 112.327512)
		(width 0.125)
		(layer "In5.Cu")
		(net 66)
	)
	(segment
		(start 39.795 105.567512)
		(end 44.075 101.287512)
		(width 0.125)
		(layer "In5.Cu")
		(net 66)
	)
	(segment
		(start 40.875 112.327512)
		(end 40.875 111.76581)
		(width 0.125)
		(layer "In5.Cu")
		(net 66)
	)
	(segment
		(start 75.997488 84.2)
		(end 76.827512 84.2)
		(width 0.125)
		(layer "In5.Cu")
		(net 66)
	)
	(segment
		(start 40.875 111.76581)
		(end 40.875 110.622488)
		(width 0.125)
		(layer "In5.Cu")
		(net 66)
	)
	(segment
		(start 33.947488 110.125)
		(end 33.3 110.772488)
		(width 0.125)
		(layer "In5.Cu")
		(net 66)
	)
	(segment
		(start 34.705 110.555)
		(end 34.275 110.125)
		(width 0.125)
		(layer "In5.Cu")
		(net 66)
	)
	(segment
		(start 38.613556 112.382936)
		(end 38.703556 112.382936)
		(width 0.125)
		(layer "In5.Cu")
		(net 66)
	)
	(segment
		(start 34.275 110.125)
		(end 33.947488 110.125)
		(width 0.125)
		(layer "In5.Cu")
		(net 66)
	)
	(segment
		(start 38.433556 112.695)
		(end 38.433556 112.562936)
		(width 0.125)
		(layer "In5.Cu")
		(net 66)
	)
	(segment
		(start 39.153556 112.875)
		(end 40.327512 112.875)
		(width 0.125)
		(layer "In5.Cu")
		(net 66)
	)
	(segment
		(start 40.875 110.622488)
		(end 39.795 109.542488)
		(width 0.125)
		(layer "In5.Cu")
		(net 66)
	)
	(segment
		(start 53.277512 80.55)
		(end 72.797488 80.55)
		(width 0.125)
		(layer "In5.Cu")
		(net 66)
	)
	(arc
		(start 38.253556 112.875)
		(mid 38.380835 112.822279)
		(end 38.433556 112.695)
		(width 0.125)
		(layer "In5.Cu")
		(net 66)
	)
	(arc
		(start 38.433556 112.562936)
		(mid 38.486277 112.435657)
		(end 38.613556 112.382936)
		(width 0.125)
		(layer "In5.Cu")
		(net 66)
	)
	(arc
		(start 38.883556 112.695)
		(mid 38.936277 112.822279)
		(end 39.063556 112.875)
		(width 0.125)
		(layer "In5.Cu")
		(net 66)
	)
	(arc
		(start 38.703556 112.382936)
		(mid 38.830835 112.435657)
		(end 38.883556 112.562936)
		(width 0.125)
		(layer "In5.Cu")
		(net 66)
	)
	(segment
		(start 78 82.775)
		(end 78.4515 82.3235)
		(width 0.125)
		(layer "F.Cu")
		(net 67)
	)
	(segment
		(start 77.55 82.66)
		(end 77.665 82.775)
		(width 0.125)
		(layer "F.Cu")
		(net 67)
	)
	(segment
		(start 77.923823 81.419191)
		(end 77.923823 81.006636)
		(width 0.125)
		(layer "F.Cu")
		(net 67)
	)
	(segment
		(start 78.4515 81.946868)
		(end 77.923823 81.419191)
		(width 0.125)
		(layer "F.Cu")
		(net 67)
	)
	(segment
		(start 77.665 82.775)
		(end 78 82.775)
		(width 0.125)
		(layer "F.Cu")
		(net 67)
	)
	(segment
		(start 78.4515 82.3235)
		(end 78.4515 81.946868)
		(width 0.125)
		(layer "F.Cu")
		(net 67)
	)
	(via
		(at 77.55 82.66)
		(size 0.45)
		(drill 0.1)
		(layers "F.Cu" "B.Cu")
		(net 67)
	)
	(segment
		(start 44.425 101.432488)
		(end 44.425 91.572488)
		(width 0.125)
		(layer "In5.Cu")
		(net 67)
	)
	(segment
		(start 46.425 89.572488)
		(end 46.425 87.897488)
		(width 0.125)
		(layer "In5.Cu")
		(net 67)
	)
	(segment
		(start 40.145 105.712488)
		(end 44.425 101.432488)
		(width 0.125)
		(layer "In5.Cu")
		(net 67)
	)
	(segment
		(start 73.025 81.722488)
		(end 75.852512 84.55)
		(width 0.125)
		(layer "In5.Cu")
		(net 67)
	)
	(segment
		(start 40.145 109.397512)
		(end 40.145 105.712488)
		(width 0.125)
		(layer "In5.Cu")
		(net 67)
	)
	(segment
		(start 32.95 110.627512)
		(end 32.95 111.347488)
		(width 0.125)
		(layer "In5.Cu")
		(net 67)
	)
	(segment
		(start 72.652512 80.9)
		(end 73.025 81.272488)
		(width 0.125)
		(layer "In5.Cu")
		(net 67)
	)
	(segment
		(start 77.55 83.972488)
		(end 77.55 82.66)
		(width 0.125)
		(layer "In5.Cu")
		(net 67)
	)
	(segment
		(start 46.425 87.897488)
		(end 53.422488 80.9)
		(width 0.125)
		(layer "In5.Cu")
		(net 67)
	)
	(segment
		(start 76.972488 84.55)
		(end 77.55 83.972488)
		(width 0.125)
		(layer "In5.Cu")
		(net 67)
	)
	(segment
		(start 34.127512 112.525)
		(end 35.427512 112.525)
		(width 0.125)
		(layer "In5.Cu")
		(net 67)
	)
	(segment
		(start 33.435 108.616397)
		(end 33.9 109.081397)
		(width 0.125)
		(layer "In5.Cu")
		(net 67)
	)
	(segment
		(start 40.472488 113.225)
		(end 41.225 112.472488)
		(width 0.125)
		(layer "In5.Cu")
		(net 67)
	)
	(segment
		(start 44.425 91.572488)
		(end 46.425 89.572488)
		(width 0.125)
		(layer "In5.Cu")
		(net 67)
	)
	(segment
		(start 33.9 109.081397)
		(end 33.9 109.677512)
		(width 0.125)
		(layer "In5.Cu")
		(net 67)
	)
	(segment
		(start 32.95 111.347488)
		(end 34.127512 112.525)
		(width 0.125)
		(layer "In5.Cu")
		(net 67)
	)
	(segment
		(start 41.225 112.472488)
		(end 41.225 110.477512)
		(width 0.125)
		(layer "In5.Cu")
		(net 67)
	)
	(segment
		(start 36.127512 113.225)
		(end 40.472488 113.225)
		(width 0.125)
		(layer "In5.Cu")
		(net 67)
	)
	(segment
		(start 73.025 81.272488)
		(end 73.025 81.722488)
		(width 0.125)
		(layer "In5.Cu")
		(net 67)
	)
	(segment
		(start 75.852512 84.55)
		(end 76.972488 84.55)
		(width 0.125)
		(layer "In5.Cu")
		(net 67)
	)
	(segment
		(start 41.225 110.477512)
		(end 40.145 109.397512)
		(width 0.125)
		(layer "In5.Cu")
		(net 67)
	)
	(segment
		(start 53.422488 80.9)
		(end 72.652512 80.9)
		(width 0.125)
		(layer "In5.Cu")
		(net 67)
	)
	(segment
		(start 33.9 109.677512)
		(end 32.95 110.627512)
		(width 0.125)
		(layer "In5.Cu")
		(net 67)
	)
	(segment
		(start 35.427512 112.525)
		(end 36.127512 113.225)
		(width 0.125)
		(layer "In5.Cu")
		(net 67)
	)
	(segment
		(start 76.770823 81.645823)
		(end 76.770823 81.006636)
		(width 0.125)
		(layer "F.Cu")
		(net 68)
	)
	(segment
		(start 76.85 81.725)
		(end 76.770823 81.645823)
		(width 0.125)
		(layer "F.Cu")
		(net 68)
	)
	(via
		(at 76.85 81.725)
		(size 0.45)
		(drill 0.1)
		(layers "F.Cu" "B.Cu")
		(net 68)
	)
	(segment
		(start 40.150347 94.776513)
		(end 40.150346 94.776512)
		(width 0.125)
		(layer "In5.Cu")
		(net 68)
	)
	(segment
		(start 36.797488 109.7)
		(end 36.322488 110.175)
		(width 0.125)
		(layer "In5.Cu")
		(net 68)
	)
	(segment
		(start 40.487707 91.330851)
		(end 40.487709 91.33085)
		(width 0.125)
		(layer "In5.Cu")
		(net 68)
	)
	(segment
		(start 36.322488 110.175)
		(end 35.377512 110.175)
		(width 0.125)
		(layer "In5.Cu")
		(net 68)
	)
	(segment
		(start 41.442305 91.33085)
		(end 41.442303 91.330851)
		(width 0.125)
		(layer "In5.Cu")
		(net 68)
	)
	(segment
		(start 37.6 109.7)
		(end 36.797488 109.7)
		(width 0.125)
		(layer "In5.Cu")
		(net 68)
	)
	(segment
		(start 49.977512 79.575)
		(end 73.172488 79.575)
		(width 0.125)
		(layer "In5.Cu")
		(net 68)
	)
	(segment
		(start 40.487708 92.285446)
		(end 41.564568 93.362305)
		(width 0.125)
		(layer "In5.Cu")
		(net 68)
	)
	(segment
		(start 76.799835 81.674835)
		(end 76.85 81.725)
		(width 0.125)
		(layer "In5.Cu")
		(net 68)
	)
	(segment
		(start 40.028079 92.745052)
		(end 40.028077 92.745053)
		(width 0.125)
		(layer "In5.Cu")
		(net 68)
	)
	(segment
		(start 44.925 84.627512)
		(end 49.977512 79.575)
		(width 0.125)
		(layer "In5.Cu")
		(net 68)
	)
	(segment
		(start 34.625 109.422488)
		(end 34.625 107.552512)
		(width 0.125)
		(layer "In5.Cu")
		(net 68)
	)
	(segment
		(start 40.150347 95.236133)
		(end 40.150346 95.236133)
		(width 0.125)
		(layer "In5.Cu")
		(net 68)
	)
	(segment
		(start 74.497488 80.9)
		(end 76.25 80.9)
		(width 0.125)
		(layer "In5.Cu")
		(net 68)
	)
	(segment
		(start 37.177512 106.5)
		(end 37.875 105.802512)
		(width 0.125)
		(layer "In5.Cu")
		(net 68)
	)
	(segment
		(start 76.799835 81.449835)
		(end 76.799835 81.674835)
		(width 0.125)
		(layer "In5.Cu")
		(net 68)
	)
	(segment
		(start 42.086794 91.515721)
		(end 44.925 88.677512)
		(width 0.125)
		(layer "In5.Cu")
		(net 68)
	)
	(segment
		(start 73.172488 79.575)
		(end 74.497488 80.9)
		(width 0.125)
		(layer "In5.Cu")
		(net 68)
	)
	(segment
		(start 39.784 111.155397)
		(end 37.6 109.7)
		(width 0.125)
		(layer "In5.Cu")
		(net 68)
	)
	(segment
		(start 39.073481 92.745053)
		(end 39.073483 92.745052)
		(width 0.125)
		(layer "In5.Cu")
		(net 68)
	)
	(segment
		(start 40.150346 94.776512)
		(end 39.073482 93.699648)
		(width 0.125)
		(layer "In5.Cu")
		(net 68)
	)
	(segment
		(start 41.442303 91.330851)
		(end 41.627174 91.515722)
		(width 0.125)
		(layer "In5.Cu")
		(net 68)
	)
	(segment
		(start 40.028077 92.745053)
		(end 41.104948 93.821925)
		(width 0.125)
		(layer "In5.Cu")
		(net 68)
	)
	(segment
		(start 39.50585 95.051256)
		(end 39.690727 95.236133)
		(width 0.125)
		(layer "In5.Cu")
		(net 68)
	)
	(segment
		(start 35.377512 110.175)
		(end 34.625 109.422488)
		(width 0.125)
		(layer "In5.Cu")
		(net 68)
	)
	(segment
		(start 35.677512 106.5)
		(end 37.177512 106.5)
		(width 0.125)
		(layer "In5.Cu")
		(net 68)
	)
	(segment
		(start 76.25 80.9)
		(end 76.799835 81.449835)
		(width 0.125)
		(layer "In5.Cu")
		(net 68)
	)
	(segment
		(start 44.925 88.677512)
		(end 44.925 84.627512)
		(width 0.125)
		(layer "In5.Cu")
		(net 68)
	)
	(segment
		(start 37.875 95.727512)
		(end 38.551256 95.051256)
		(width 0.125)
		(layer "In5.Cu")
		(net 68)
	)
	(segment
		(start 37.875 105.802512)
		(end 37.875 95.727512)
		(width 0.125)
		(layer "In5.Cu")
		(net 68)
	)
	(segment
		(start 42.086793 91.515721)
		(end 42.086794 91.515721)
		(width 0.125)
		(layer "In5.Cu")
		(net 68)
	)
	(segment
		(start 34.625 107.552512)
		(end 35.677512 106.5)
		(width 0.125)
		(layer "In5.Cu")
		(net 68)
	)
	(segment
		(start 40.150346 95.236133)
		(end 40.150346 95.236132)
		(width 0.125)
		(layer "In5.Cu")
		(net 68)
	)
	(arc
		(start 38.551256 95.051256)
		(mid 39.028553 94.853553)
		(end 39.50585 95.051256)
		(width 0.125)
		(layer "In5.Cu")
		(net 68)
	)
	(arc
		(start 39.690727 95.236133)
		(mid 39.920537 95.331323)
		(end 40.150347 95.236133)
		(width 0.125)
		(layer "In5.Cu")
		(net 68)
	)
	(arc
		(start 39.073483 92.745052)
		(mid 39.55078 92.54735)
		(end 40.028079 92.745052)
		(width 0.125)
		(layer "In5.Cu")
		(net 68)
	)
	(arc
		(start 41.627174 91.515722)
		(mid 41.856984 91.610912)
		(end 42.086793 91.515721)
		(width 0.125)
		(layer "In5.Cu")
		(net 68)
	)
	(arc
		(start 40.150346 95.236132)
		(mid 40.245537 95.006323)
		(end 40.150347 94.776513)
		(width 0.125)
		(layer "In5.Cu")
		(net 68)
	)
	(arc
		(start 40.487708 92.285446)
		(mid 40.290005 91.808148)
		(end 40.487707 91.330851)
		(width 0.125)
		(layer "In5.Cu")
		(net 68)
	)
	(arc
		(start 39.073482 93.699648)
		(mid 38.875779 93.22235)
		(end 39.073481 92.745053)
		(width 0.125)
		(layer "In5.Cu")
		(net 68)
	)
	(arc
		(start 40.487709 91.33085)
		(mid 40.965006 91.133148)
		(end 41.442305 91.33085)
		(width 0.125)
		(layer "In5.Cu")
		(net 68)
	)
	(arc
		(start 41.104948 93.821925)
		(mid 41.334758 93.917115)
		(end 41.564568 93.821925)
		(width 0.125)
		(layer "In5.Cu")
		(net 68)
	)
	(arc
		(start 41.564568 93.821925)
		(mid 41.659758 93.592115)
		(end 41.564568 93.362305)
		(width 0.125)
		(layer "In5.Cu")
		(net 68)
	)
	(segment
		(start 76.3 81.9)
		(end 76.423823 81.776177)
		(width 0.125)
		(layer "F.Cu")
		(net 69)
	)
	(segment
		(start 76.423823 81.776177)
		(end 76.423823 81.006636)
		(width 0.125)
		(layer "F.Cu")
		(net 69)
	)
	(via
		(at 76.3 81.9)
		(size 0.45)
		(drill 0.1)
		(layers "F.Cu" "B.Cu")
		(net 69)
	)
	(segment
		(start 37.1 109.15)
		(end 36.9 109.35)
		(width 0.125)
		(layer "In5.Cu")
		(net 69)
	)
	(segment
		(start 38.51154 104.95)
		(end 38.425 104.95)
		(width 0.125)
		(layer "In5.Cu")
		(net 69)
	)
	(segment
		(start 37.1 107.95)
		(end 37.1 109.15)
		(width 0.125)
		(layer "In5.Cu")
		(net 69)
	)
	(segment
		(start 36.15 107.6)
		(end 36.75 107.6)
		(width 0.125)
		(layer "In5.Cu")
		(net 69)
	)
	(segment
		(start 35.974 107.776)
		(end 36.15 107.6)
		(width 0.125)
		(layer "In5.Cu")
		(net 69)
	)
	(segment
		(start 34.975 109.277512)
		(end 34.975 107.697488)
		(width 0.125)
		(layer "In5.Cu")
		(net 69)
	)
	(segment
		(start 39.32097 93.45216)
		(end 40.397834 94.529025)
		(width 0.125)
		(layer "In5.Cu")
		(net 69)
	)
	(segment
		(start 35.822488 106.85)
		(end 37.322488 106.85)
		(width 0.125)
		(layer "In5.Cu")
		(net 69)
	)
	(segment
		(start 38.225 95.872488)
		(end 38.798743 95.298743)
		(width 0.125)
		(layer "In5.Cu")
		(net 69)
	)
	(segment
		(start 41.812055 93.114816)
		(end 41.812055 93.114817)
		(width 0.125)
		(layer "In5.Cu")
		(net 69)
	)
	(segment
		(start 38.225 103.95)
		(end 38.225 95.872488)
		(width 0.125)
		(layer "In5.Cu")
		(net 69)
	)
	(segment
		(start 39.320969 92.992541)
		(end 39.320971 92.99254)
		(width 0.125)
		(layer "In5.Cu")
		(net 69)
	)
	(segment
		(start 37.322488 106.85)
		(end 38.225 105.947488)
		(width 0.125)
		(layer "In5.Cu")
		(net 69)
	)
	(segment
		(start 45.275 88.822488)
		(end 45.275 84.772488)
		(width 0.125)
		(layer "In5.Cu")
		(net 69)
	)
	(segment
		(start 39.780591 92.99254)
		(end 40.857461 94.069412)
		(width 0.125)
		(layer "In5.Cu")
		(net 69)
	)
	(segment
		(start 35.974 108.616397)
		(end 35.974 107.776)
		(width 0.125)
		(layer "In5.Cu")
		(net 69)
	)
	(segment
		(start 42.334279 91.763209)
		(end 45.275 88.822488)
		(width 0.125)
		(layer "In5.Cu")
		(net 69)
	)
	(segment
		(start 76.3 81.697488)
		(end 76.3 81.9)
		(width 0.125)
		(layer "In5.Cu")
		(net 69)
	)
	(segment
		(start 73.027512 79.925)
		(end 74.352512 81.25)
		(width 0.125)
		(layer "In5.Cu")
		(net 69)
	)
	(segment
		(start 36.9 109.35)
		(end 36.652512 109.35)
		(width 0.125)
		(layer "In5.Cu")
		(net 69)
	)
	(segment
		(start 45.275 84.772488)
		(end 50.122488 79.925)
		(width 0.125)
		(layer "In5.Cu")
		(net 69)
	)
	(segment
		(start 75.852512 81.25)
		(end 76.3 81.697488)
		(width 0.125)
		(layer "In5.Cu")
		(net 69)
	)
	(segment
		(start 74.352512 81.25)
		(end 75.852512 81.25)
		(width 0.125)
		(layer "In5.Cu")
		(net 69)
	)
	(segment
		(start 41.812055 93.114817)
		(end 40.735196 92.037958)
		(width 0.125)
		(layer "In5.Cu")
		(net 69)
	)
	(segment
		(start 38.51154 104.15)
		(end 38.425 104.15)
		(width 0.125)
		(layer "In5.Cu")
		(net 69)
	)
	(segment
		(start 50.122488 79.925)
		(end 73.027512 79.925)
		(width 0.125)
		(layer "In5.Cu")
		(net 69)
	)
	(segment
		(start 38.225 105.947488)
		(end 38.225 105.55)
		(width 0.125)
		(layer "In5.Cu")
		(net 69)
	)
	(segment
		(start 35.522488 109.825)
		(end 34.975 109.277512)
		(width 0.125)
		(layer "In5.Cu")
		(net 69)
	)
	(segment
		(start 36.177512 109.825)
		(end 35.522488 109.825)
		(width 0.125)
		(layer "In5.Cu")
		(net 69)
	)
	(segment
		(start 38.425 105.35)
		(end 38.51154 105.35)
		(width 0.125)
		(layer "In5.Cu")
		(net 69)
	)
	(segment
		(start 42.334282 91.763209)
		(end 42.334279 91.763209)
		(width 0.125)
		(layer "In5.Cu")
		(net 69)
	)
	(segment
		(start 36.75 107.6)
		(end 37.1 107.95)
		(width 0.125)
		(layer "In5.Cu")
		(net 69)
	)
	(segment
		(start 40.735195 91.578339)
		(end 40.735197 91.578338)
		(width 0.125)
		(layer "In5.Cu")
		(net 69)
	)
	(segment
		(start 34.975 107.697488)
		(end 35.822488 106.85)
		(width 0.125)
		(layer "In5.Cu")
		(net 69)
	)
	(segment
		(start 41.194817 91.578338)
		(end 41.379688 91.763209)
		(width 0.125)
		(layer "In5.Cu")
		(net 69)
	)
	(segment
		(start 38.425 104.55)
		(end 38.51154 104.55)
		(width 0.125)
		(layer "In5.Cu")
		(net 69)
	)
	(segment
		(start 40.397834 95.48362)
		(end 40.397834 95.483619)
		(width 0.125)
		(layer "In5.Cu")
		(net 69)
	)
	(segment
		(start 39.258363 95.298743)
		(end 39.44324 95.48362)
		(width 0.125)
		(layer "In5.Cu")
		(net 69)
	)
	(segment
		(start 36.652512 109.35)
		(end 36.177512 109.825)
		(width 0.125)
		(layer "In5.Cu")
		(net 69)
	)
	(arc
		(start 41.812055 94.069412)
		(mid 42.009758 93.592114)
		(end 41.812055 93.114816)
		(width 0.125)
		(layer "In5.Cu")
		(net 69)
	)
	(arc
		(start 38.425 104.95)
		(mid 38.283579 104.891421)
		(end 38.225 104.75)
		(width 0.125)
		(layer "In5.Cu")
		(net 69)
	)
	(arc
		(start 40.397834 95.483619)
		(mid 40.595537 95.006322)
		(end 40.397834 94.529025)
		(width 0.125)
		(layer "In5.Cu")
		(net 69)
	)
	(arc
		(start 41.379688 91.763209)
		(mid 41.856985 91.960912)
		(end 42.334282 91.763209)
		(width 0.125)
		(layer "In5.Cu")
		(net 69)
	)
	(arc
		(start 38.225 104.75)
		(mid 38.283579 104.608579)
		(end 38.425 104.55)
		(width 0.125)
		(layer "In5.Cu")
		(net 69)
	)
	(arc
		(start 39.44324 95.48362)
		(mid 39.920537 95.681323)
		(end 40.397834 95.48362)
		(width 0.125)
		(layer "In5.Cu")
		(net 69)
	)
	(arc
		(start 38.51154 104.55)
		(mid 38.652961 104.491421)
		(end 38.71154 104.35)
		(width 0.125)
		(layer "In5.Cu")
		(net 69)
	)
	(arc
		(start 38.225 105.55)
		(mid 38.283579 105.408579)
		(end 38.425 105.35)
		(width 0.125)
		(layer "In5.Cu")
		(net 69)
	)
	(arc
		(start 40.857461 94.069412)
		(mid 41.334758 94.267115)
		(end 41.812055 94.069412)
		(width 0.125)
		(layer "In5.Cu")
		(net 69)
	)
	(arc
		(start 38.425 104.15)
		(mid 38.283579 104.091421)
		(end 38.225 103.95)
		(width 0.125)
		(layer "In5.Cu")
		(net 69)
	)
	(arc
		(start 40.735196 92.037958)
		(mid 40.640005 91.808149)
		(end 40.735195 91.578339)
		(width 0.125)
		(layer "In5.Cu")
		(net 69)
	)
	(arc
		(start 38.51154 105.35)
		(mid 38.652961 105.291421)
		(end 38.71154 105.15)
		(width 0.125)
		(layer "In5.Cu")
		(net 69)
	)
	(arc
		(start 39.320971 92.99254)
		(mid 39.550781 92.89735)
		(end 39.780591 92.99254)
		(width 0.125)
		(layer "In5.Cu")
		(net 69)
	)
	(arc
		(start 38.71154 104.35)
		(mid 38.652961 104.208579)
		(end 38.51154 104.15)
		(width 0.125)
		(layer "In5.Cu")
		(net 69)
	)
	(arc
		(start 38.798743 95.298743)
		(mid 39.028553 95.203553)
		(end 39.258363 95.298743)
		(width 0.125)
		(layer "In5.Cu")
		(net 69)
	)
	(arc
		(start 39.32097 93.45216)
		(mid 39.225779 93.222351)
		(end 39.320969 92.992541)
		(width 0.125)
		(layer "In5.Cu")
		(net 69)
	)
	(arc
		(start 40.735197 91.578338)
		(mid 40.965007 91.483148)
		(end 41.194817 91.578338)
		(width 0.125)
		(layer "In5.Cu")
		(net 69)
	)
	(arc
		(start 38.71154 105.15)
		(mid 38.652961 105.008579)
		(end 38.51154 104.95)
		(width 0.125)
		(layer "In5.Cu")
		(net 69)
	)
	(segment
		(start 76.097323 70.947323)
		(end 76.097323 72.005136)
		(width 0.15)
		(layer "F.Cu")
		(net 70)
	)
	(segment
		(start 76.1 70.944646)
		(end 76.097323 70.947323)
		(width 0.15)
		(layer "F.Cu")
		(net 70)
	)
	(segment
		(start 147.775 101.565)
		(end 148.302 102.092)
		(width 0.15)
		(layer "F.Cu")
		(net 70)
	)
	(segment
		(start 76.1 69.8)
		(end 76.1 70.944646)
		(width 0.15)
		(layer "F.Cu")
		(net 70)
	)
	(segment
		(start 148.302 102.092)
		(end 148.302 102.318)
		(width 0.15)
		(layer "F.Cu")
		(net 70)
	)
	(segment
		(start 147.775 101.375)
		(end 147.775 101.565)
		(width 0.15)
		(layer "F.Cu")
		(net 70)
	)
	(via
		(at 76.1 69.8)
		(size 0.45)
		(drill 0.1)
		(layers "F.Cu" "B.Cu")
		(net 70)
	)
	(via
		(at 147.775 101.375)
		(size 0.45)
		(drill 0.1)
		(layers "F.Cu" "B.Cu")
		(net 70)
	)
	(segment
		(start 101.775 103.075)
		(end 90.275 103.075)
		(width 0.125)
		(layer "In3.Cu")
		(net 70)
	)
	(segment
		(start 147.925 101.375)
		(end 148.29 101.01)
		(width 0.125)
		(layer "In3.Cu")
		(net 70)
	)
	(segment
		(start 69.68 83.68)
		(end 69.68 73.27)
		(width 0.125)
		(layer "In3.Cu")
		(net 70)
	)
	(segment
		(start 137.358364 99.375)
		(end 124.683364 112.05)
		(width 0.125)
		(layer "In3.Cu")
		(net 70)
	)
	(segment
		(start 147.775 101.375)
		(end 147.925 101.375)
		(width 0.125)
		(layer "In3.Cu")
		(net 70)
	)
	(segment
		(start 90.275 103.075)
		(end 89.15 104.2)
		(width 0.125)
		(layer "In3.Cu")
		(net 70)
	)
	(segment
		(start 70.16 84.16)
		(end 69.68 83.68)
		(width 0.125)
		(layer "In3.Cu")
		(net 70)
	)
	(segment
		(start 108.7 112.05)
		(end 108 111.35)
		(width 0.125)
		(layer "In3.Cu")
		(net 70)
	)
	(segment
		(start 148.29 101.01)
		(end 148.29 100.61)
		(width 0.125)
		(layer "In3.Cu")
		(net 70)
	)
	(segment
		(start 70.2 72.75)
		(end 74.16 72.75)
		(width 0.125)
		(layer "In3.Cu")
		(net 70)
	)
	(segment
		(start 108 109.3)
		(end 101.775 103.075)
		(width 0.125)
		(layer "In3.Cu")
		(net 70)
	)
	(segment
		(start 76.32 99.72)
		(end 71.8 95.2)
		(width 0.125)
		(layer "In3.Cu")
		(net 70)
	)
	(segment
		(start 71.8 89.2)
		(end 70.16 87.56)
		(width 0.125)
		(layer "In3.Cu")
		(net 70)
	)
	(segment
		(start 108 111.35)
		(end 108 109.3)
		(width 0.125)
		(layer "In3.Cu")
		(net 70)
	)
	(segment
		(start 69.68 73.27)
		(end 70.2 72.75)
		(width 0.125)
		(layer "In3.Cu")
		(net 70)
	)
	(segment
		(start 79.97 102.77)
		(end 76.92 99.72)
		(width 0.125)
		(layer "In3.Cu")
		(net 70)
	)
	(segment
		(start 76.92 99.72)
		(end 76.32 99.72)
		(width 0.125)
		(layer "In3.Cu")
		(net 70)
	)
	(segment
		(start 74.16 72.75)
		(end 76.1 70.81)
		(width 0.125)
		(layer "In3.Cu")
		(net 70)
	)
	(segment
		(start 71.8 95.2)
		(end 71.8 89.2)
		(width 0.125)
		(layer "In3.Cu")
		(net 70)
	)
	(segment
		(start 148.29 100.61)
		(end 147.055 99.375)
		(width 0.125)
		(layer "In3.Cu")
		(net 70)
	)
	(segment
		(start 89.15 104.2)
		(end 86.3 104.2)
		(width 0.125)
		(layer "In3.Cu")
		(net 70)
	)
	(segment
		(start 124.683364 112.05)
		(end 108.7 112.05)
		(width 0.125)
		(layer "In3.Cu")
		(net 70)
	)
	(segment
		(start 76.1 70.81)
		(end 76.1 69.8)
		(width 0.125)
		(layer "In3.Cu")
		(net 70)
	)
	(segment
		(start 70.16 87.56)
		(end 70.16 84.16)
		(width 0.125)
		(layer "In3.Cu")
		(net 70)
	)
	(segment
		(start 84.87 102.77)
		(end 79.97 102.77)
		(width 0.125)
		(layer "In3.Cu")
		(net 70)
	)
	(segment
		(start 147.055 99.375)
		(end 137.358364 99.375)
		(width 0.125)
		(layer "In3.Cu")
		(net 70)
	)
	(segment
		(start 86.3 104.2)
		(end 84.87 102.77)
		(width 0.125)
		(layer "In3.Cu")
		(net 70)
	)
	(segment
		(start 75.6 70.944646)
		(end 75.597323 70.947323)
		(width 0.15)
		(layer "F.Cu")
		(net 71)
	)
	(segment
		(start 75.597323 70.947323)
		(end 75.597323 72.005136)
		(width 0.15)
		(layer "F.Cu")
		(net 71)
	)
	(segment
		(start 75.6 69.45)
		(end 75.6 70.944646)
		(width 0.15)
		(layer "F.Cu")
		(net 71)
	)
	(segment
		(start 136.31 101.5)
		(end 138.85 101.5)
		(width 0.15)
		(layer "F.Cu")
		(net 71)
	)
	(via
		(at 75.6 69.45)
		(size 0.45)
		(drill 0.1)
		(layers "F.Cu" "B.Cu")
		(net 71)
	)
	(via
		(at 136.31 101.5)
		(size 0.45)
		(drill 0.1)
		(layers "F.Cu" "B.Cu")
		(net 71)
	)
	(segment
		(start 69.9 84.26)
		(end 69.38 83.74)
		(width 0.125)
		(layer "In3.Cu")
		(net 71)
	)
	(segment
		(start 124.77 112.35)
		(end 108.6 112.35)
		(width 0.125)
		(layer "In3.Cu")
		(net 71)
	)
	(segment
		(start 71.5 95.3)
		(end 71.5 89.3)
		(width 0.125)
		(layer "In3.Cu")
		(net 71)
	)
	(segment
		(start 107.7 111.45)
		(end 107.7 109.4)
		(width 0.125)
		(layer "In3.Cu")
		(net 71)
	)
	(segment
		(start 107.7 109.4)
		(end 101.65 103.35)
		(width 0.125)
		(layer "In3.Cu")
		(net 71)
	)
	(segment
		(start 69.38 73.16)
		(end 70.09 72.45)
		(width 0.125)
		(layer "In3.Cu")
		(net 71)
	)
	(segment
		(start 74.05 72.45)
		(end 75.6 70.9)
		(width 0.125)
		(layer "In3.Cu")
		(net 71)
	)
	(segment
		(start 136.31 101.5)
		(end 135.62 101.5)
		(width 0.125)
		(layer "In3.Cu")
		(net 71)
	)
	(segment
		(start 84.78 103.08)
		(end 79.883554 103.08)
		(width 0.125)
		(layer "In3.Cu")
		(net 71)
	)
	(segment
		(start 108.6 112.35)
		(end 107.7 111.45)
		(width 0.125)
		(layer "In3.Cu")
		(net 71)
	)
	(segment
		(start 69.38 83.74)
		(end 69.38 73.16)
		(width 0.125)
		(layer "In3.Cu")
		(net 71)
	)
	(segment
		(start 135.62 101.5)
		(end 124.77 112.35)
		(width 0.125)
		(layer "In3.Cu")
		(net 71)
	)
	(segment
		(start 69.9 87.7)
		(end 69.9 84.26)
		(width 0.125)
		(layer "In3.Cu")
		(net 71)
	)
	(segment
		(start 90.353554 103.35)
		(end 89.253554 104.45)
		(width 0.125)
		(layer "In3.Cu")
		(net 71)
	)
	(segment
		(start 101.65 103.35)
		(end 90.353554 103.35)
		(width 0.125)
		(layer "In3.Cu")
		(net 71)
	)
	(segment
		(start 76.17 99.97)
		(end 71.5 95.3)
		(width 0.125)
		(layer "In3.Cu")
		(net 71)
	)
	(segment
		(start 71.5 89.3)
		(end 69.9 87.7)
		(width 0.125)
		(layer "In3.Cu")
		(net 71)
	)
	(segment
		(start 75.6 70.9)
		(end 75.6 69.45)
		(width 0.125)
		(layer "In3.Cu")
		(net 71)
	)
	(segment
		(start 79.883554 103.08)
		(end 76.773554 99.97)
		(width 0.125)
		(layer "In3.Cu")
		(net 71)
	)
	(segment
		(start 89.253554 104.45)
		(end 86.15 104.45)
		(width 0.125)
		(layer "In3.Cu")
		(net 71)
	)
	(segment
		(start 76.773554 99.97)
		(end 76.17 99.97)
		(width 0.125)
		(layer "In3.Cu")
		(net 71)
	)
	(segment
		(start 70.09 72.45)
		(end 74.05 72.45)
		(width 0.125)
		(layer "In3.Cu")
		(net 71)
	)
	(segment
		(start 86.15 104.45)
		(end 84.78 103.08)
		(width 0.125)
		(layer "In3.Cu")
		(net 71)
	)
	(segment
		(start 72.822499 83.593501)
		(end 72.66 83.756)
		(width 0.125)
		(layer "F.Cu")
		(net 72)
	)
	(segment
		(start 75.270823 81.006636)
		(end 75.270823 81.874545)
		(width 0.125)
		(layer "F.Cu")
		(net 72)
	)
	(segment
		(start 73.551867 83.593501)
		(end 72.822499 83.593501)
		(width 0.125)
		(layer "F.Cu")
		(net 72)
	)
	(segment
		(start 75.270823 81.874545)
		(end 73.551867 83.593501)
		(width 0.125)
		(layer "F.Cu")
		(net 72)
	)
	(via
		(at 72.66 83.756)
		(size 0.45)
		(drill 0.1)
		(layers "F.Cu" "B.Cu")
		(net 72)
	)
	(segment
		(start 48.552463 93.805403)
		(end 48.552462 93.805403)
		(width 0.125)
		(layer "In5.Cu")
		(net 72)
	)
	(segment
		(start 60.105 83.58)
		(end 60.105 85.18)
		(width 0.125)
		(layer "In5.Cu")
		(net 72)
	)
	(segment
		(start 64.342488 83.875)
		(end 70.015 83.875)
		(width 0.125)
		(layer "In5.Cu")
		(net 72)
	)
	(segment
		(start 47.312759 91.9293)
		(end 47.312757 91.929301)
		(width 0.125)
		(layer "In5.Cu")
		(net 72)
	)
	(segment
		(start 48.552462 94.618578)
		(end 48.552462 94.618576)
		(width 0.125)
		(layer "In5.Cu")
		(net 72)
	)
	(segment
		(start 41.79 110.621397)
		(end 41.79 110.08)
		(width 0.125)
		(layer "In5.Cu")
		(net 72)
	)
	(segment
		(start 70.275 84.135)
		(end 71.772488 84.135)
		(width 0.125)
		(layer "In5.Cu")
		(net 72)
	)
	(segment
		(start 55.575 84.072488)
		(end 55.822488 83.825)
		(width 0.125)
		(layer "In5.Cu")
		(net 72)
	)
	(segment
		(start 42.897512 109.935)
		(end 43.445 110.482488)
		(width 0.125)
		(layer "In5.Cu")
		(net 72)
	)
	(segment
		(start 72.312488 83.595)
		(end 72.499 83.595)
		(width 0.125)
		(layer "In5.Cu")
		(net 72)
	)
	(segment
		(start 41.79 110.08)
		(end 41.935 109.935)
		(width 0.125)
		(layer "In5.Cu")
		(net 72)
	)
	(segment
		(start 57.167512 83.825)
		(end 57.897512 84.555)
		(width 0.125)
		(layer "In5.Cu")
		(net 72)
	)
	(segment
		(start 57.897512 84.555)
		(end 58.405 84.555)
		(width 0.125)
		(layer "In5.Cu")
		(net 72)
	)
	(segment
		(start 49.683854 92.674051)
		(end 49.683854 92.674052)
		(width 0.125)
		(layer "In5.Cu")
		(net 72)
	)
	(segment
		(start 58.605 84.755)
		(end 58.605 85.18)
		(width 0.125)
		(layer "In5.Cu")
		(net 72)
	)
	(segment
		(start 49.187743 91.859743)
		(end 55.575 85.472488)
		(width 0.125)
		(layer "In5.Cu")
		(net 72)
	)
	(segment
		(start 71.772488 84.135)
		(end 72.312488 83.595)
		(width 0.125)
		(layer "In5.Cu")
		(net 72)
	)
	(segment
		(start 62.705 85.18)
		(end 62.705 84.755)
		(width 0.125)
		(layer "In5.Cu")
		(net 72)
	)
	(segment
		(start 49.683854 92.674052)
		(end 49.187742 92.17794)
		(width 0.125)
		(layer "In5.Cu")
		(net 72)
	)
	(segment
		(start 42.325 111.156397)
		(end 41.79 110.621397)
		(width 0.125)
		(layer "In5.Cu")
		(net 72)
	)
	(segment
		(start 47.312757 91.929301)
		(end 48.870682 93.487225)
		(width 0.125)
		(layer "In5.Cu")
		(net 72)
	)
	(segment
		(start 70.015 83.875)
		(end 70.275 84.135)
		(width 0.125)
		(layer "In5.Cu")
		(net 72)
	)
	(segment
		(start 62.905 84.555)
		(end 63.662488 84.555)
		(width 0.125)
		(layer "In5.Cu")
		(net 72)
	)
	(segment
		(start 61.205 85.18)
		(end 61.205 83.58)
		(width 0.125)
		(layer "In5.Cu")
		(net 72)
	)
	(segment
		(start 48.552462 93.805403)
		(end 46.994559 92.247498)
		(width 0.125)
		(layer "In5.Cu")
		(net 72)
	)
	(segment
		(start 55.822488 83.825)
		(end 57.167512 83.825)
		(width 0.125)
		(layer "In5.Cu")
		(net 72)
	)
	(segment
		(start 43.836138 112.393626)
		(end 45.993862 112.393626)
		(width 0.125)
		(layer "In5.Cu")
		(net 72)
	)
	(segment
		(start 61.605 83.58)
		(end 61.605 85.18)
		(width 0.125)
		(layer "In5.Cu")
		(net 72)
	)
	(segment
		(start 43.445 112.002488)
		(end 43.836138 112.393626)
		(width 0.125)
		(layer "In5.Cu")
		(net 72)
	)
	(segment
		(start 63.662488 84.555)
		(end 64.342488 83.875)
		(width 0.125)
		(layer "In5.Cu")
		(net 72)
	)
	(segment
		(start 49.187742 91.859742)
		(end 49.187743 91.859743)
		(width 0.125)
		(layer "In5.Cu")
		(net 72)
	)
	(segment
		(start 43.445 110.482488)
		(end 43.445 112.002488)
		(width 0.125)
		(layer "In5.Cu")
		(net 72)
	)
	(segment
		(start 55.575 85.472488)
		(end 55.575 84.072488)
		(width 0.125)
		(layer "In5.Cu")
		(net 72)
	)
	(segment
		(start 46.925 111.462488)
		(end 46.925 94.122486)
		(width 0.125)
		(layer "In5.Cu")
		(net 72)
	)
	(segment
		(start 59.705 85.18)
		(end 59.705 83.58)
		(width 0.125)
		(layer "In5.Cu")
		(net 72)
	)
	(segment
		(start 41.935 109.935)
		(end 42.897512 109.935)
		(width 0.125)
		(layer "In5.Cu")
		(net 72)
	)
	(segment
		(start 72.499 83.595)
		(end 72.66 83.756)
		(width 0.125)
		(layer "In5.Cu")
		(net 72)
	)
	(segment
		(start 47.243198 94.122486)
		(end 47.739289 94.618577)
		(width 0.125)
		(layer "In5.Cu")
		(net 72)
	)
	(segment
		(start 45.993862 112.393626)
		(end 46.925 111.462488)
		(width 0.125)
		(layer "In5.Cu")
		(net 72)
	)
	(arc
		(start 48.870682 93.487225)
		(mid 49.277268 93.655638)
		(end 49.683854 93.487225)
		(width 0.125)
		(layer "In5.Cu")
		(net 72)
	)
	(arc
		(start 61.205 83.58)
		(mid 61.263579 83.438579)
		(end 61.405 83.38)
		(width 0.125)
		(layer "In5.Cu")
		(net 72)
	)
	(arc
		(start 49.683854 93.487225)
		(mid 49.852268 93.080638)
		(end 49.683854 92.674051)
		(width 0.125)
		(layer "In5.Cu")
		(net 72)
	)
	(arc
		(start 46.994559 92.247498)
		(mid 46.928658 92.088399)
		(end 46.994559 91.9293)
		(width 0.125)
		(layer "In5.Cu")
		(net 72)
	)
	(arc
		(start 47.739289 94.618577)
		(mid 48.145875 94.786991)
		(end 48.552462 94.618578)
		(width 0.125)
		(layer "In5.Cu")
		(net 72)
	)
	(arc
		(start 59.905 83.38)
		(mid 60.046421 83.438579)
		(end 60.105 83.58)
		(width 0.125)
		(layer "In5.Cu")
		(net 72)
	)
	(arc
		(start 62.705 84.755)
		(mid 62.763579 84.613579)
		(end 62.905 84.555)
		(width 0.125)
		(layer "In5.Cu")
		(net 72)
	)
	(arc
		(start 59.705 83.58)
		(mid 59.763579 83.438579)
		(end 59.905 83.38)
		(width 0.125)
		(layer "In5.Cu")
		(net 72)
	)
	(arc
		(start 49.187742 92.17794)
		(mid 49.121841 92.018841)
		(end 49.187742 91.859742)
		(width 0.125)
		(layer "In5.Cu")
		(net 72)
	)
	(arc
		(start 62.155 85.73)
		(mid 62.543909 85.568909)
		(end 62.705 85.18)
		(width 0.125)
		(layer "In5.Cu")
		(net 72)
	)
	(arc
		(start 58.405 84.555)
		(mid 58.546421 84.613579)
		(end 58.605 84.755)
		(width 0.125)
		(layer "In5.Cu")
		(net 72)
	)
	(arc
		(start 58.605 85.18)
		(mid 58.766091 85.568909)
		(end 59.155 85.73)
		(width 0.125)
		(layer "In5.Cu")
		(net 72)
	)
	(arc
		(start 61.605 85.18)
		(mid 61.766091 85.568909)
		(end 62.155 85.73)
		(width 0.125)
		(layer "In5.Cu")
		(net 72)
	)
	(arc
		(start 60.105 85.18)
		(mid 60.266091 85.568909)
		(end 60.655 85.73)
		(width 0.125)
		(layer "In5.Cu")
		(net 72)
	)
	(arc
		(start 60.655 85.73)
		(mid 61.043909 85.568909)
		(end 61.205 85.18)
		(width 0.125)
		(layer "In5.Cu")
		(net 72)
	)
	(arc
		(start 46.994559 91.9293)
		(mid 47.153658 91.8634)
		(end 47.312759 91.9293)
		(width 0.125)
		(layer "In5.Cu")
		(net 72)
	)
	(arc
		(start 48.552462 94.618576)
		(mid 48.720876 94.21199)
		(end 48.552463 93.805403)
		(width 0.125)
		(layer "In5.Cu")
		(net 72)
	)
	(arc
		(start 61.405 83.38)
		(mid 61.546421 83.438579)
		(end 61.605 83.58)
		(width 0.125)
		(layer "In5.Cu")
		(net 72)
	)
	(arc
		(start 59.155 85.73)
		(mid 59.543909 85.568909)
		(end 59.705 85.18)
		(width 0.125)
		(layer "In5.Cu")
		(net 72)
	)
	(arc
		(start 46.925 94.122486)
		(mid 47.084099 94.056585)
		(end 47.243198 94.122486)
		(width 0.125)
		(layer "In5.Cu")
		(net 72)
	)
	(segment
		(start 75.097323 70.947323)
		(end 75.097323 72.005136)
		(width 0.15)
		(layer "F.Cu")
		(net 73)
	)
	(segment
		(start 75.1 69.8)
		(end 75.1 70.944646)
		(width 0.15)
		(layer "F.Cu")
		(net 73)
	)
	(segment
		(start 135.89 102.05)
		(end 138.85 102.05)
		(width 0.15)
		(layer "F.Cu")
		(net 73)
	)
	(segment
		(start 135.88 102.06)
		(end 135.89 102.05)
		(width 0.15)
		(layer "F.Cu")
		(net 73)
	)
	(segment
		(start 75.1 70.944646)
		(end 75.097323 70.947323)
		(width 0.15)
		(layer "F.Cu")
		(net 73)
	)
	(via
		(at 75.1 69.8)
		(size 0.45)
		(drill 0.1)
		(layers "F.Cu" "B.Cu")
		(net 73)
	)
	(via
		(at 135.88 102.06)
		(size 0.45)
		(drill 0.1)
		(layers "F.Cu" "B.Cu")
		(net 73)
	)
	(segment
		(start 76.02 100.22)
		(end 70.9 95.1)
		(width 0.125)
		(layer "In3.Cu")
		(net 73)
	)
	(segment
		(start 76.67 100.22)
		(end 76.02 100.22)
		(width 0.125)
		(layer "In3.Cu")
		(net 73)
	)
	(segment
		(start 70.9 93.4)
		(end 68.95 91.45)
		(width 0.125)
		(layer "In3.Cu")
		(net 73)
	)
	(segment
		(start 67.15 91.096446)
		(end 67.15 88.66)
		(width 0.125)
		(layer "In3.Cu")
		(net 73)
	)
	(segment
		(start 70.026446 72.16)
		(end 73.9 72.16)
		(width 0.125)
		(layer "In3.Cu")
		(net 73)
	)
	(segment
		(start 73.9 72.16)
		(end 75.1 70.96)
		(width 0.125)
		(layer "In3.Cu")
		(net 73)
	)
	(segment
		(start 67.15 88.66)
		(end 68.8 87.01)
		(width 0.125)
		(layer "In3.Cu")
		(net 73)
	)
	(segment
		(start 68.8 79.15)
		(end 69.1 78.85)
		(width 0.125)
		(layer "In3.Cu")
		(net 73)
	)
	(segment
		(start 68.95 91.45)
		(end 67.503554 91.45)
		(width 0.125)
		(layer "In3.Cu")
		(net 73)
	)
	(segment
		(start 124.88 112.65)
		(end 108.5 112.65)
		(width 0.125)
		(layer "In3.Cu")
		(net 73)
	)
	(segment
		(start 90.457108 103.6)
		(end 89.357108 104.7)
		(width 0.125)
		(layer "In3.Cu")
		(net 73)
	)
	(segment
		(start 108.5 112.65)
		(end 107.4 111.55)
		(width 0.125)
		(layer "In3.Cu")
		(net 73)
	)
	(segment
		(start 67.503554 91.45)
		(end 67.15 91.096446)
		(width 0.125)
		(layer "In3.Cu")
		(net 73)
	)
	(segment
		(start 69.1 78.85)
		(end 69.1 73.086446)
		(width 0.125)
		(layer "In3.Cu")
		(net 73)
	)
	(segment
		(start 84.676777 103.4)
		(end 79.85 103.4)
		(width 0.125)
		(layer "In3.Cu")
		(net 73)
	)
	(segment
		(start 75.1 70.96)
		(end 75.1 69.8)
		(width 0.125)
		(layer "In3.Cu")
		(net 73)
	)
	(segment
		(start 69.1 73.086446)
		(end 70.026446 72.16)
		(width 0.125)
		(layer "In3.Cu")
		(net 73)
	)
	(segment
		(start 70.9 95.1)
		(end 70.9 93.4)
		(width 0.125)
		(layer "In3.Cu")
		(net 73)
	)
	(segment
		(start 79.85 103.4)
		(end 76.67 100.22)
		(width 0.125)
		(layer "In3.Cu")
		(net 73)
	)
	(segment
		(start 68.8 87.01)
		(end 68.8 79.15)
		(width 0.125)
		(layer "In3.Cu")
		(net 73)
	)
	(segment
		(start 135.47 102.06)
		(end 124.88 112.65)
		(width 0.125)
		(layer "In3.Cu")
		(net 73)
	)
	(segment
		(start 101.5 103.6)
		(end 90.457108 103.6)
		(width 0.125)
		(layer "In3.Cu")
		(net 73)
	)
	(segment
		(start 85.976777 104.7)
		(end 84.676777 103.4)
		(width 0.125)
		(layer "In3.Cu")
		(net 73)
	)
	(segment
		(start 135.88 102.06)
		(end 135.47 102.06)
		(width 0.125)
		(layer "In3.Cu")
		(net 73)
	)
	(segment
		(start 107.4 111.55)
		(end 107.4 109.5)
		(width 0.125)
		(layer "In3.Cu")
		(net 73)
	)
	(segment
		(start 107.4 109.5)
		(end 101.5 103.6)
		(width 0.125)
		(layer "In3.Cu")
		(net 73)
	)
	(segment
		(start 89.357108 104.7)
		(end 85.976777 104.7)
		(width 0.125)
		(layer "In3.Cu")
		(net 73)
	)
	(segment
		(start 73.408133 83.246499)
		(end 72.822499 83.246499)
		(width 0.125)
		(layer "F.Cu")
		(net 74)
	)
	(segment
		(start 72.822499 83.246499)
		(end 72.66 83.084)
		(width 0.125)
		(layer "F.Cu")
		(net 74)
	)
	(segment
		(start 74.923823 81.730809)
		(end 73.408133 83.246499)
		(width 0.125)
		(layer "F.Cu")
		(net 74)
	)
	(segment
		(start 74.923823 81.006636)
		(end 74.923823 81.730809)
		(width 0.125)
		(layer "F.Cu")
		(net 74)
	)
	(via
		(at 72.66 83.084)
		(size 0.45)
		(drill 0.1)
		(layers "F.Cu" "B.Cu")
		(net 74)
	)
	(segment
		(start 41.815 109.585)
		(end 43.042488 109.585)
		(width 0.125)
		(layer "In5.Cu")
		(net 74)
	)
	(segment
		(start 72.499 83.245)
		(end 72.66 83.084)
		(width 0.125)
		(layer "In5.Cu")
		(net 74)
	)
	(segment
		(start 62.905 84.205)
		(end 63.517512 84.205)
		(width 0.125)
		(layer "In5.Cu")
		(net 74)
	)
	(segment
		(start 55.677512 83.475)
		(end 57.312488 83.475)
		(width 0.125)
		(layer "In5.Cu")
		(net 74)
	)
	(segment
		(start 45.848654 112.043858)
		(end 46.575 111.317512)
		(width 0.125)
		(layer "In5.Cu")
		(net 74)
	)
	(segment
		(start 46.575 111.317512)
		(end 46.575 110.315)
		(width 0.125)
		(layer "In5.Cu")
		(net 74)
	)
	(segment
		(start 47.490685 93.874999)
		(end 47.490686 93.874999)
		(width 0.125)
		(layer "In5.Cu")
		(net 74)
	)
	(segment
		(start 70.155 83.525)
		(end 70.43 83.8)
		(width 0.125)
		(layer "In5.Cu")
		(net 74)
	)
	(segment
		(start 46.747072 91.681813)
		(end 46.747071 91.681813)
		(width 0.125)
		(layer "In5.Cu")
		(net 74)
	)
	(segment
		(start 60.855 85.18)
		(end 60.855 83.58)
		(width 0.125)
		(layer "In5.Cu")
		(net 74)
	)
	(segment
		(start 46.575 109.515)
		(end 46.575 93.977512)
		(width 0.125)
		(layer "In5.Cu")
		(net 74)
	)
	(segment
		(start 47.560245 91.681813)
		(end 47.560245 91.681812)
		(width 0.125)
		(layer "In5.Cu")
		(net 74)
	)
	(segment
		(start 58.042488 84.205)
		(end 58.405 84.205)
		(width 0.125)
		(layer "In5.Cu")
		(net 74)
	)
	(segment
		(start 43.981346 112.043858)
		(end 45.848654 112.043858)
		(width 0.125)
		(layer "In5.Cu")
		(net 74)
	)
	(segment
		(start 60.455 83.58)
		(end 60.455 85.18)
		(width 0.125)
		(layer "In5.Cu")
		(net 74)
	)
	(segment
		(start 55.225 83.927512)
		(end 55.677512 83.475)
		(width 0.125)
		(layer "In5.Cu")
		(net 74)
	)
	(segment
		(start 41.055 108.825)
		(end 41.815 109.585)
		(width 0.125)
		(layer "In5.Cu")
		(net 74)
	)
	(segment
		(start 43.795 110.337512)
		(end 43.795 111.857512)
		(width 0.125)
		(layer "In5.Cu")
		(net 74)
	)
	(segment
		(start 46.161724 109.715)
		(end 46.375 109.715)
		(width 0.125)
		(layer "In5.Cu")
		(net 74)
	)
	(segment
		(start 47.560245 91.681812)
		(end 49.118169 93.239738)
		(width 0.125)
		(layer "In5.Cu")
		(net 74)
	)
	(segment
		(start 43.042488 109.585)
		(end 43.795 110.337512)
		(width 0.125)
		(layer "In5.Cu")
		(net 74)
	)
	(segment
		(start 58.955 84.755)
		(end 58.955 85.18)
		(width 0.125)
		(layer "In5.Cu")
		(net 74)
	)
	(segment
		(start 62.355 85.18)
		(end 62.355 84.755)
		(width 0.125)
		(layer "In5.Cu")
		(net 74)
	)
	(segment
		(start 49.436367 92.921538)
		(end 49.436367 92.921539)
		(width 0.125)
		(layer "In5.Cu")
		(net 74)
	)
	(segment
		(start 55.225 85.327512)
		(end 55.225 83.927512)
		(width 0.125)
		(layer "In5.Cu")
		(net 74)
	)
	(segment
		(start 59.355 85.18)
		(end 59.355 83.58)
		(width 0.125)
		(layer "In5.Cu")
		(net 74)
	)
	(segment
		(start 70.43 83.8)
		(end 71.612512 83.8)
		(width 0.125)
		(layer "In5.Cu")
		(net 74)
	)
	(segment
		(start 48.304976 94.052891)
		(end 46.74707 92.494987)
		(width 0.125)
		(layer "In5.Cu")
		(net 74)
	)
	(segment
		(start 57.312488 83.475)
		(end 58.042488 84.205)
		(width 0.125)
		(layer "In5.Cu")
		(net 74)
	)
	(segment
		(start 46.375 110.115)
		(end 46.161724 110.115)
		(width 0.125)
		(layer "In5.Cu")
		(net 74)
	)
	(segment
		(start 72.167512 83.245)
		(end 72.499 83.245)
		(width 0.125)
		(layer "In5.Cu")
		(net 74)
	)
	(segment
		(start 48.940256 91.612254)
		(end 48.940255 91.612255)
		(width 0.125)
		(layer "In5.Cu")
		(net 74)
	)
	(segment
		(start 64.197512 83.525)
		(end 70.155 83.525)
		(width 0.125)
		(layer "In5.Cu")
		(net 74)
	)
	(segment
		(start 61.955 83.58)
		(end 61.955 85.18)
		(width 0.125)
		(layer "In5.Cu")
		(net 74)
	)
	(segment
		(start 71.612512 83.8)
		(end 72.167512 83.245)
		(width 0.125)
		(layer "In5.Cu")
		(net 74)
	)
	(segment
		(start 47.490686 93.874999)
		(end 47.986777 94.37109)
		(width 0.125)
		(layer "In5.Cu")
		(net 74)
	)
	(segment
		(start 48.940255 91.612255)
		(end 55.225 85.327512)
		(width 0.125)
		(layer "In5.Cu")
		(net 74)
	)
	(segment
		(start 43.795 111.857512)
		(end 43.981346 112.043858)
		(width 0.125)
		(layer "In5.Cu")
		(net 74)
	)
	(segment
		(start 46.575 93.977512)
		(end 46.677513 93.874999)
		(width 0.125)
		(layer "In5.Cu")
		(net 74)
	)
	(segment
		(start 49.436367 92.921539)
		(end 48.940255 92.425427)
		(width 0.125)
		(layer "In5.Cu")
		(net 74)
	)
	(segment
		(start 48.304976 94.371091)
		(end 48.304976 94.371089)
		(width 0.125)
		(layer "In5.Cu")
		(net 74)
	)
	(segment
		(start 63.517512 84.205)
		(end 64.197512 83.525)
		(width 0.125)
		(layer "In5.Cu")
		(net 74)
	)
	(arc
		(start 49.436367 93.239738)
		(mid 49.502268 93.080638)
		(end 49.436367 92.921538)
		(width 0.125)
		(layer "In5.Cu")
		(net 74)
	)
	(arc
		(start 62.155 85.38)
		(mid 62.296421 85.321421)
		(end 62.355 85.18)
		(width 0.125)
		(layer "In5.Cu")
		(net 74)
	)
	(arc
		(start 58.955 85.18)
		(mid 59.013579 85.321421)
		(end 59.155 85.38)
		(width 0.125)
		(layer "In5.Cu")
		(net 74)
	)
	(arc
		(start 46.74707 92.494987)
		(mid 46.578658 92.0884)
		(end 46.747072 91.681813)
		(width 0.125)
		(layer "In5.Cu")
		(net 74)
	)
	(arc
		(start 61.405 83.03)
		(mid 61.793909 83.191091)
		(end 61.955 83.58)
		(width 0.125)
		(layer "In5.Cu")
		(net 74)
	)
	(arc
		(start 58.405 84.205)
		(mid 58.793909 84.366091)
		(end 58.955 84.755)
		(width 0.125)
		(layer "In5.Cu")
		(net 74)
	)
	(arc
		(start 47.986777 94.37109)
		(mid 48.145876 94.436992)
		(end 48.304976 94.371091)
		(width 0.125)
		(layer "In5.Cu")
		(net 74)
	)
	(arc
		(start 48.940255 92.425427)
		(mid 48.771842 92.01884)
		(end 48.940256 91.612254)
		(width 0.125)
		(layer "In5.Cu")
		(net 74)
	)
	(arc
		(start 61.955 85.18)
		(mid 62.013579 85.321421)
		(end 62.155 85.38)
		(width 0.125)
		(layer "In5.Cu")
		(net 74)
	)
	(arc
		(start 48.304976 94.371089)
		(mid 48.370877 94.21199)
		(end 48.304976 94.052891)
		(width 0.125)
		(layer "In5.Cu")
		(net 74)
	)
	(arc
		(start 46.747071 91.681813)
		(mid 47.153659 91.513398)
		(end 47.560245 91.681813)
		(width 0.125)
		(layer "In5.Cu")
		(net 74)
	)
	(arc
		(start 45.961724 109.915)
		(mid 46.020303 109.773579)
		(end 46.161724 109.715)
		(width 0.125)
		(layer "In5.Cu")
		(net 74)
	)
	(arc
		(start 60.655 85.38)
		(mid 60.796421 85.321421)
		(end 60.855 85.18)
		(width 0.125)
		(layer "In5.Cu")
		(net 74)
	)
	(arc
		(start 46.375 109.715)
		(mid 46.516421 109.656421)
		(end 46.575 109.515)
		(width 0.125)
		(layer "In5.Cu")
		(net 74)
	)
	(arc
		(start 59.355 83.58)
		(mid 59.516091 83.191091)
		(end 59.905 83.03)
		(width 0.125)
		(layer "In5.Cu")
		(net 74)
	)
	(arc
		(start 60.455 85.18)
		(mid 60.513579 85.321421)
		(end 60.655 85.38)
		(width 0.125)
		(layer "In5.Cu")
		(net 74)
	)
	(arc
		(start 46.575 110.315)
		(mid 46.516421 110.173579)
		(end 46.375 110.115)
		(width 0.125)
		(layer "In5.Cu")
		(net 74)
	)
	(arc
		(start 59.905 83.03)
		(mid 60.293909 83.191091)
		(end 60.455 83.58)
		(width 0.125)
		(layer "In5.Cu")
		(net 74)
	)
	(arc
		(start 59.155 85.38)
		(mid 59.296421 85.321421)
		(end 59.355 85.18)
		(width 0.125)
		(layer "In5.Cu")
		(net 74)
	)
	(arc
		(start 49.118169 93.239738)
		(mid 49.277268 93.305639)
		(end 49.436367 93.239738)
		(width 0.125)
		(layer "In5.Cu")
		(net 74)
	)
	(arc
		(start 62.355 84.755)
		(mid 62.516091 84.366091)
		(end 62.905 84.205)
		(width 0.125)
		(layer "In5.Cu")
		(net 74)
	)
	(arc
		(start 46.161724 110.115)
		(mid 46.020303 110.056421)
		(end 45.961724 109.915)
		(width 0.125)
		(layer "In5.Cu")
		(net 74)
	)
	(arc
		(start 46.677513 93.874999)
		(mid 47.084099 93.706586)
		(end 47.490685 93.874999)
		(width 0.125)
		(layer "In5.Cu")
		(net 74)
	)
	(arc
		(start 60.855 83.58)
		(mid 61.016091 83.191091)
		(end 61.405 83.03)
		(width 0.125)
		(layer "In5.Cu")
		(net 74)
	)
	(segment
		(start 74.6 70.994646)
		(end 74.597323 70.997323)
		(width 0.15)
		(layer "F.Cu")
		(net 75)
	)
	(segment
		(start 147.825 100.8)
		(end 148.36 100.265)
		(width 0.15)
		(layer "F.Cu")
		(net 75)
	)
	(segment
		(start 74.597323 70.997323)
		(end 74.597323 72.005136)
		(width 0.15)
		(layer "F.Cu")
		(net 75)
	)
	(segment
		(start 74.6 69.45)
		(end 74.6 70.994646)
		(width 0.15)
		(layer "F.Cu")
		(net 75)
	)
	(via
		(at 147.825 100.8)
		(size 0.45)
		(drill 0.1)
		(layers "F.Cu" "B.Cu")
		(net 75)
	)
	(via
		(at 74.6 69.45)
		(size 0.45)
		(drill 0.1)
		(layers "F.Cu" "B.Cu")
		(net 75)
	)
	(segment
		(start 136.78 101.77)
		(end 136.04 102.51)
		(width 0.125)
		(layer "In3.Cu")
		(net 75)
	)
	(segment
		(start 101.4 103.9)
		(end 90.535 103.9)
		(width 0.125)
		(layer "In3.Cu")
		(net 75)
	)
	(segment
		(start 77.9 103.7)
		(end 73.33 99.13)
		(width 0.125)
		(layer "In3.Cu")
		(net 75)
	)
	(segment
		(start 84.6 103.7)
		(end 77.9 103.7)
		(width 0.125)
		(layer "In3.Cu")
		(net 75)
	)
	(segment
		(start 66.9 91.199999)
		(end 66.9 88.55)
		(width 0.125)
		(layer "In3.Cu")
		(net 75)
	)
	(segment
		(start 147.825 100.8)
		(end 147.825 100.715)
		(width 0.125)
		(layer "In3.Cu")
		(net 75)
	)
	(segment
		(start 108.4 112.95)
		(end 107.1 111.65)
		(width 0.125)
		(layer "In3.Cu")
		(net 75)
	)
	(segment
		(start 66.9 88.55)
		(end 68.55 86.9)
		(width 0.125)
		(layer "In3.Cu")
		(net 75)
	)
	(segment
		(start 68.55 79.046446)
		(end 68.85 78.746446)
		(width 0.125)
		(layer "In3.Cu")
		(net 75)
	)
	(segment
		(start 68.85 78.746446)
		(end 68.85 72.9)
		(width 0.125)
		(layer "In3.Cu")
		(net 75)
	)
	(segment
		(start 136.04 102.51)
		(end 135.5 102.51)
		(width 0.125)
		(layer "In3.Cu")
		(net 75)
	)
	(segment
		(start 137.47 99.65)
		(end 136.78 100.34)
		(width 0.125)
		(layer "In3.Cu")
		(net 75)
	)
	(segment
		(start 69.87 71.88)
		(end 73.62 71.88)
		(width 0.125)
		(layer "In3.Cu")
		(net 75)
	)
	(segment
		(start 73.33 99.13)
		(end 73.33 98.28)
		(width 0.125)
		(layer "In3.Cu")
		(net 75)
	)
	(segment
		(start 136.78 100.34)
		(end 136.78 101.77)
		(width 0.125)
		(layer "In3.Cu")
		(net 75)
	)
	(segment
		(start 85.85 104.95)
		(end 84.6 103.7)
		(width 0.125)
		(layer "In3.Cu")
		(net 75)
	)
	(segment
		(start 67.4 91.7)
		(end 66.9 91.199999)
		(width 0.125)
		(layer "In3.Cu")
		(net 75)
	)
	(segment
		(start 135.5 102.51)
		(end 125.06 112.95)
		(width 0.125)
		(layer "In3.Cu")
		(net 75)
	)
	(segment
		(start 70.6 95.55)
		(end 70.6 93.453554)
		(width 0.125)
		(layer "In3.Cu")
		(net 75)
	)
	(segment
		(start 73.33 98.28)
		(end 70.6 95.55)
		(width 0.125)
		(layer "In3.Cu")
		(net 75)
	)
	(segment
		(start 147.825 100.715)
		(end 146.76 99.65)
		(width 0.125)
		(layer "In3.Cu")
		(net 75)
	)
	(segment
		(start 89.485 104.95)
		(end 85.85 104.95)
		(width 0.125)
		(layer "In3.Cu")
		(net 75)
	)
	(segment
		(start 125.06 112.95)
		(end 108.4 112.95)
		(width 0.125)
		(layer "In3.Cu")
		(net 75)
	)
	(segment
		(start 90.535 103.9)
		(end 89.485 104.95)
		(width 0.125)
		(layer "In3.Cu")
		(net 75)
	)
	(segment
		(start 146.76 99.65)
		(end 137.47 99.65)
		(width 0.125)
		(layer "In3.Cu")
		(net 75)
	)
	(segment
		(start 107.1 109.6)
		(end 101.4 103.9)
		(width 0.125)
		(layer "In3.Cu")
		(net 75)
	)
	(segment
		(start 74.6 70.9)
		(end 74.6 69.45)
		(width 0.125)
		(layer "In3.Cu")
		(net 75)
	)
	(segment
		(start 68.55 86.9)
		(end 68.55 79.046446)
		(width 0.125)
		(layer "In3.Cu")
		(net 75)
	)
	(segment
		(start 107.1 111.65)
		(end 107.1 109.6)
		(width 0.125)
		(layer "In3.Cu")
		(net 75)
	)
	(segment
		(start 73.62 71.88)
		(end 74.6 70.9)
		(width 0.125)
		(layer "In3.Cu")
		(net 75)
	)
	(segment
		(start 68.846446 91.7)
		(end 67.4 91.7)
		(width 0.125)
		(layer "In3.Cu")
		(net 75)
	)
	(segment
		(start 70.6 93.453554)
		(end 68.846446 91.7)
		(width 0.125)
		(layer "In3.Cu")
		(net 75)
	)
	(segment
		(start 68.85 72.9)
		(end 69.87 71.88)
		(width 0.125)
		(layer "In3.Cu")
		(net 75)
	)
	(segment
		(start 71.1 82.95)
		(end 71.275 82.775)
		(width 0.125)
		(layer "F.Cu")
		(net 76)
	)
	(segment
		(start 72.5 82.5)
		(end 73.197488 82.5)
		(width 0.125)
		(layer "F.Cu")
		(net 76)
	)
	(segment
		(start 72.225 82.775)
		(end 72.5 82.5)
		(width 0.125)
		(layer "F.Cu")
		(net 76)
	)
	(segment
		(start 73.197488 82.5)
		(end 73.770823 81.926665)
		(width 0.125)
		(layer "F.Cu")
		(net 76)
	)
	(segment
		(start 71.275 82.775)
		(end 72.225 82.775)
		(width 0.125)
		(layer "F.Cu")
		(net 76)
	)
	(segment
		(start 73.770823 81.926665)
		(end 73.770823 81.006636)
		(width 0.125)
		(layer "F.Cu")
		(net 76)
	)
	(via
		(at 71.1 82.95)
		(size 0.45)
		(drill 0.1)
		(layers "F.Cu" "B.Cu")
		(net 76)
	)
	(segment
		(start 52.961931 85.753789)
		(end 52.452814 85.244672)
		(width 0.125)
		(layer "In5.Cu")
		(net 76)
	)
	(segment
		(start 49.64206 87.807938)
		(end 49.642063 87.807938)
		(width 0.125)
		(layer "In5.Cu")
		(net 76)
	)
	(segment
		(start 50.861824 86.340689)
		(end 50.352707 85.831573)
		(width 0.125)
		(layer "In5.Cu")
		(net 76)
	)
	(segment
		(start 51.109309 86.588177)
		(end 50.985565 86.464433)
		(width 0.125)
		(layer "In5.Cu")
		(net 76)
	)
	(segment
		(start 50.190071 87.507416)
		(end 50.699187 88.016533)
		(width 0.125)
		(layer "In5.Cu")
		(net 76)
	)
	(segment
		(start 44.145 106.755)
		(end 45.25 106.755)
		(width 0.125)
		(layer "In5.Cu")
		(net 76)
	)
	(segment
		(start 45.25 106.355)
		(end 44.145 106.355)
		(width 0.125)
		(layer "In5.Cu")
		(net 76)
	)
	(segment
		(start 52.827581 86.673028)
		(end 52.961931 86.538677)
		(width 0.125)
		(layer "In5.Cu")
		(net 76)
	)
	(segment
		(start 52.120478 84.063803)
		(end 52.629595 84.57292)
		(width 0.125)
		(layer "In5.Cu")
		(net 76)
	)
	(segment
		(start 45.725 108.642488)
		(end 44.865 109.502488)
		(width 0.125)
		(layer "In5.Cu")
		(net 76)
	)
	(segment
		(start 51.28609 85.916425)
		(end 51.409834 86.040169)
		(width 0.125)
		(layer "In5.Cu")
		(net 76)
	)
	(segment
		(start 49.942585 87.25993)
		(end 50.066329 87.383674)
		(width 0.125)
		(layer "In5.Cu")
		(net 76)
	)
	(segment
		(start 51.484076 88.016533)
		(end 51.618426 87.882182)
		(width 0.125)
		(layer "In5.Cu")
		(net 76)
	)
	(segment
		(start 50.066329 87.383674)
		(end 50.066327 87.383672)
		(width 0.125)
		(layer "In5.Cu")
		(net 76)
	)
	(segment
		(start 61.077512 82.575)
		(end 67.772488 82.575)
		(width 0.125)
		(layer "In5.Cu")
		(net 76)
	)
	(segment
		(start 50.985568 86.464433)
		(end 50.861824 86.340689)
		(width 0.125)
		(layer "In5.Cu")
		(net 76)
	)
	(segment
		(start 56.821631 82.125)
		(end 60.627512 82.125)
		(width 0.125)
		(layer "In5.Cu")
		(net 76)
	)
	(segment
		(start 48.454124 88.458479)
		(end 48.722825 88.72718)
		(width 0.125)
		(layer "In5.Cu")
		(net 76)
	)
	(segment
		(start 54.171086 85.329523)
		(end 54.305436 85.195172)
		(width 0.125)
		(layer "In5.Cu")
		(net 76)
	)
	(segment
		(start 45.725 105.73)
		(end 45.725 105.88)
		(width 0.125)
		(layer "In5.Cu")
		(net 76)
	)
	(segment
		(start 45.725 107.48)
		(end 45.725 108.642488)
		(width 0.125)
		(layer "In5.Cu")
		(net 76)
	)
	(segment
		(start 70.283762 82.78125)
		(end 70.93125 82.78125)
		(width 0.125)
		(layer "In5.Cu")
		(net 76)
	)
	(segment
		(start 45.725 107.38)
		(end 45.725 107.48)
		(width 0.125)
		(layer "In5.Cu")
		(net 76)
	)
	(segment
		(start 69.627512 82.125)
		(end 70.283762 82.78125)
		(width 0.125)
		(layer "In5.Cu")
		(net 76)
	)
	(segment
		(start 50.776973 85.407308)
		(end 51.28609 85.916425)
		(width 0.125)
		(layer "In5.Cu")
		(net 76)
	)
	(segment
		(start 49.642063 87.807938)
		(end 49.518319 87.684194)
		(width 0.125)
		(layer "In5.Cu")
		(net 76)
	)
	(segment
		(start 53.941276 83.75621)
		(end 54.075626 83.62186)
		(width 0.125)
		(layer "In5.Cu")
		(net 76)
	)
	(segment
		(start 52.329073 85.120928)
		(end 52.205329 84.997184)
		(width 0.125)
		(layer "In5.Cu")
		(net 76)
	)
	(segment
		(start 51.618426 87.097294)
		(end 51.109309 86.588177)
		(width 0.125)
		(layer "In5.Cu")
		(net 76)
	)
	(segment
		(start 50.352707 85.541659)
		(end 50.487059 85.407308)
		(width 0.125)
		(layer "In5.Cu")
		(net 76)
	)
	(segment
		(start 50.066327 87.383672)
		(end 50.190071 87.507416)
		(width 0.125)
		(layer "In5.Cu")
		(net 76)
	)
	(segment
		(start 48.722825 88.72718)
		(end 48.722822 88.727177)
		(width 0.125)
		(layer "In5.Cu")
		(net 76)
	)
	(segment
		(start 54.992488 82.705)
		(end 56.112488 82.705)
		(width 0.125)
		(layer "In5.Cu")
		(net 76)
	)
	(segment
		(start 48.029857 88.882743)
		(end 47.665698 88.518584)
		(width 0.125)
		(layer "In5.Cu")
		(net 76)
	)
	(segment
		(start 50.274921 88.440799)
		(end 49.765804 87.931682)
		(width 0.125)
		(layer "In5.Cu")
		(net 76)
	)
	(segment
		(start 44.145 105.255)
		(end 45.25 105.255)
		(width 0.125)
		(layer "In5.Cu")
		(net 76)
	)
	(segment
		(start 45.25 103.355)
		(end 44.145 103.355)
		(width 0.125)
		(layer "In5.Cu")
		(net 76)
	)
	(segment
		(start 53.022037 84.965363)
		(end 53.386197 85.329523)
		(width 0.125)
		(layer "In5.Cu")
		(net 76)
	)
	(segment
		(start 44.02 104.98)
		(end 44.02 105.13)
		(width 0.125)
		(layer "In5.Cu")
		(net 76)
	)
	(segment
		(start 51.696212 84.198154)
		(end 51.830564 84.063803)
		(width 0.125)
		(layer "In5.Cu")
		(net 76)
	)
	(segment
		(start 50.140571 89.360038)
		(end 50.274921 89.225687)
		(width 0.125)
		(layer "In5.Cu")
		(net 76)
	)
	(segment
		(start 49.009202 86.885164)
		(end 49.143554 86.750813)
		(width 0.125)
		(layer "In5.Cu")
		(net 76)
	)
	(segment
		(start 51.533576 86.163911)
		(end 52.042692 86.673028)
		(width 0.125)
		(layer "In5.Cu")
		(net 76)
	)
	(segment
		(start 67.772488 82.575)
		(end 68.222488 82.125)
		(width 0.125)
		(layer "In5.Cu")
		(net 76)
	)
	(segment
		(start 50.985565 86.464433)
		(end 50.985568 86.464433)
		(width 0.125)
		(layer "In5.Cu")
		(net 76)
	)
	(segment
		(start 45.725 91.972488)
		(end 45.725 102.88)
		(width 0.125)
		(layer "In5.Cu")
		(net 76)
	)
	(segment
		(start 54.075626 83.62186)
		(end 54.992488 82.705)
		(width 0.125)
		(layer "In5.Cu")
		(net 76)
	)
	(segment
		(start 44.865 109.502488)
		(end 44.865 111.156397)
		(width 0.125)
		(layer "In5.Cu")
		(net 76)
	)
	(segment
		(start 56.112488 82.705)
		(end 56.692488 82.125)
		(width 0.125)
		(layer "In5.Cu")
		(net 76)
	)
	(segment
		(start 48.722822 88.727177)
		(end 48.846566 88.850921)
		(width 0.125)
		(layer "In5.Cu")
		(net 76)
	)
	(segment
		(start 45.25 104.855)
		(end 44.145 104.855)
		(width 0.125)
		(layer "In5.Cu")
		(net 76)
	)
	(segment
		(start 48.089964 88.094319)
		(end 48.454124 88.458479)
		(width 0.125)
		(layer "In5.Cu")
		(net 76)
	)
	(segment
		(start 52.753337 84.696662)
		(end 52.898294 84.841619)
		(width 0.125)
		(layer "In5.Cu")
		(net 76)
	)
	(segment
		(start 47.665698 88.22867)
		(end 47.80005 88.094319)
		(width 0.125)
		(layer "In5.Cu")
		(net 76)
	)
	(segment
		(start 51.409832 86.040167)
		(end 51.533576 86.163911)
		(width 0.125)
		(layer "In5.Cu")
		(net 76)
	)
	(segment
		(start 45.725 104.23)
		(end 45.725 104.38)
		(width 0.125)
		(layer "In5.Cu")
		(net 76)
	)
	(segment
		(start 68.222488 82.125)
		(end 69.627512 82.125)
		(width 0.125)
		(layer "In5.Cu")
		(net 76)
	)
	(segment
		(start 56.692488 82.125)
		(end 56.821631 82.125)
		(width 0.125)
		(layer "In5.Cu")
		(net 76)
	)
	(segment
		(start 48.846566 88.850921)
		(end 49.355682 89.360038)
		(width 0.125)
		(layer "In5.Cu")
		(net 76)
	)
	(segment
		(start 70.93125 82.78125)
		(end 71.1 82.95)
		(width 0.125)
		(layer "In5.Cu")
		(net 76)
	)
	(segment
		(start 52.629595 84.57292)
		(end 52.753339 84.696664)
		(width 0.125)
		(layer "In5.Cu")
		(net 76)
	)
	(segment
		(start 49.433468 86.750813)
		(end 49.942585 87.25993)
		(width 0.125)
		(layer "In5.Cu")
		(net 76)
	)
	(segment
		(start 52.753339 84.696664)
		(end 52.753337 84.696662)
		(width 0.125)
		(layer "In5.Cu")
		(net 76)
	)
	(segment
		(start 52.205329 84.997184)
		(end 51.696212 84.488068)
		(width 0.125)
		(layer "In5.Cu")
		(net 76)
	)
	(segment
		(start 51.409834 86.040169)
		(end 51.409832 86.040167)
		(width 0.125)
		(layer "In5.Cu")
		(net 76)
	)
	(segment
		(start 44.145 103.755)
		(end 45.25 103.755)
		(width 0.125)
		(layer "In5.Cu")
		(net 76)
	)
	(segment
		(start 49.765804 87.931682)
		(end 49.64206 87.807938)
		(width 0.125)
		(layer "In5.Cu")
		(net 76)
	)
	(segment
		(start 52.32907 85.120928)
		(end 52.329073 85.120928)
		(width 0.125)
		(layer "In5.Cu")
		(net 76)
	)
	(segment
		(start 44.02 103.48)
		(end 44.02 103.63)
		(width 0.125)
		(layer "In5.Cu")
		(net 76)
	)
	(segment
		(start 52.452814 85.244672)
		(end 52.32907 85.120928)
		(width 0.125)
		(layer "In5.Cu")
		(net 76)
	)
	(segment
		(start 49.518319 87.684194)
		(end 49.009202 87.175078)
		(width 0.125)
		(layer "In5.Cu")
		(net 76)
	)
	(segment
		(start 45.725 107.23)
		(end 45.725 107.38)
		(width 0.125)
		(layer "In5.Cu")
		(net 76)
	)
	(segment
		(start 60.627512 82.125)
		(end 61.077512 82.575)
		(width 0.125)
		(layer "In5.Cu")
		(net 76)
	)
	(segment
		(start 52.898294 84.841619)
		(end 53.022037 84.965363)
		(width 0.125)
		(layer "In5.Cu")
		(net 76)
	)
	(segment
		(start 44.02 106.48)
		(end 44.02 106.63)
		(width 0.125)
		(layer "In5.Cu")
		(net 76)
	)
	(segment
		(start 48.029857 89.667631)
		(end 45.725 91.972488)
		(width 0.125)
		(layer "In5.Cu")
		(net 76)
	)
	(segment
		(start 54.305436 84.410284)
		(end 53.941276 84.046124)
		(width 0.125)
		(layer "In5.Cu")
		(net 76)
	)
	(arc
		(start 44.145 103.355)
		(mid 44.056612 103.391612)
		(end 44.02 103.48)
		(width 0.125)
		(layer "In5.Cu")
		(net 76)
	)
	(arc
		(start 51.830564 84.063803)
		(mid 51.975521 84.00376)
		(end 52.120478 84.063803)
		(width 0.125)
		(layer "In5.Cu")
		(net 76)
	)
	(arc
		(start 50.487059 85.407308)
		(mid 50.632016 85.347265)
		(end 50.776973 85.407308)
		(width 0.125)
		(layer "In5.Cu")
		(net 76)
	)
	(arc
		(start 50.274921 89.225687)
		(mid 50.437477 88.833243)
		(end 50.274921 88.440799)
		(width 0.125)
		(layer "In5.Cu")
		(net 76)
	)
	(arc
		(start 45.25 106.755)
		(mid 45.585876 106.894124)
		(end 45.725 107.23)
		(width 0.125)
		(layer "In5.Cu")
		(net 76)
	)
	(arc
		(start 54.305436 85.195172)
		(mid 54.467992 84.802728)
		(end 54.305436 84.410284)
		(width 0.125)
		(layer "In5.Cu")
		(net 76)
	)
	(arc
		(start 44.02 106.63)
		(mid 44.056612 106.718388)
		(end 44.145 106.755)
		(width 0.125)
		(layer "In5.Cu")
		(net 76)
	)
	(arc
		(start 50.352707 85.831573)
		(mid 50.292664 85.686616)
		(end 50.352707 85.541659)
		(width 0.125)
		(layer "In5.Cu")
		(net 76)
	)
	(arc
		(start 53.386197 85.329523)
		(mid 53.778642 85.492078)
		(end 54.171086 85.329523)
		(width 0.125)
		(layer "In5.Cu")
		(net 76)
	)
	(arc
		(start 50.699187 88.016533)
		(mid 51.091632 88.179088)
		(end 51.484076 88.016533)
		(width 0.125)
		(layer "In5.Cu")
		(net 76)
	)
	(arc
		(start 53.941276 84.046124)
		(mid 53.881233 83.901167)
		(end 53.941276 83.75621)
		(width 0.125)
		(layer "In5.Cu")
		(net 76)
	)
	(arc
		(start 45.25 105.255)
		(mid 45.585876 105.394124)
		(end 45.725 105.73)
		(width 0.125)
		(layer "In5.Cu")
		(net 76)
	)
	(arc
		(start 45.725 102.88)
		(mid 45.585876 103.215876)
		(end 45.25 103.355)
		(width 0.125)
		(layer "In5.Cu")
		(net 76)
	)
	(arc
		(start 45.725 104.38)
		(mid 45.585876 104.715876)
		(end 45.25 104.855)
		(width 0.125)
		(layer "In5.Cu")
		(net 76)
	)
	(arc
		(start 51.618426 87.882182)
		(mid 51.780982 87.489738)
		(end 51.618426 87.097294)
		(width 0.125)
		(layer "In5.Cu")
		(net 76)
	)
	(arc
		(start 51.696212 84.488068)
		(mid 51.636169 84.343111)
		(end 51.696212 84.198154)
		(width 0.125)
		(layer "In5.Cu")
		(net 76)
	)
	(arc
		(start 52.042692 86.673028)
		(mid 52.435137 86.835583)
		(end 52.827581 86.673028)
		(width 0.125)
		(layer "In5.Cu")
		(net 76)
	)
	(arc
		(start 49.143554 86.750813)
		(mid 49.288511 86.69077)
		(end 49.433468 86.750813)
		(width 0.125)
		(layer "In5.Cu")
		(net 76)
	)
	(arc
		(start 44.145 104.855)
		(mid 44.056612 104.891612)
		(end 44.02 104.98)
		(width 0.125)
		(layer "In5.Cu")
		(net 76)
	)
	(arc
		(start 52.961931 86.538677)
		(mid 53.124487 86.146233)
		(end 52.961931 85.753789)
		(width 0.125)
		(layer "In5.Cu")
		(net 76)
	)
	(arc
		(start 47.665698 88.518584)
		(mid 47.605655 88.373627)
		(end 47.665698 88.22867)
		(width 0.125)
		(layer "In5.Cu")
		(net 76)
	)
	(arc
		(start 44.02 103.63)
		(mid 44.056612 103.718388)
		(end 44.145 103.755)
		(width 0.125)
		(layer "In5.Cu")
		(net 76)
	)
	(arc
		(start 44.02 105.13)
		(mid 44.056612 105.218388)
		(end 44.145 105.255)
		(width 0.125)
		(layer "In5.Cu")
		(net 76)
	)
	(arc
		(start 48.029857 89.667631)
		(mid 48.192413 89.275187)
		(end 48.029857 88.882743)
		(width 0.125)
		(layer "In5.Cu")
		(net 76)
	)
	(arc
		(start 44.145 106.355)
		(mid 44.056612 106.391612)
		(end 44.02 106.48)
		(width 0.125)
		(layer "In5.Cu")
		(net 76)
	)
	(arc
		(start 45.25 103.755)
		(mid 45.585876 103.894124)
		(end 45.725 104.23)
		(width 0.125)
		(layer "In5.Cu")
		(net 76)
	)
	(arc
		(start 49.355682 89.360038)
		(mid 49.748127 89.522593)
		(end 50.140571 89.360038)
		(width 0.125)
		(layer "In5.Cu")
		(net 76)
	)
	(arc
		(start 45.725 105.88)
		(mid 45.585876 106.215876)
		(end 45.25 106.355)
		(width 0.125)
		(layer "In5.Cu")
		(net 76)
	)
	(arc
		(start 47.80005 88.094319)
		(mid 47.945007 88.034276)
		(end 48.089964 88.094319)
		(width 0.125)
		(layer "In5.Cu")
		(net 76)
	)
	(arc
		(start 49.009202 87.175078)
		(mid 48.949159 87.030121)
		(end 49.009202 86.885164)
		(width 0.125)
		(layer "In5.Cu")
		(net 76)
	)
	(segment
		(start 73.052512 82.15)
		(end 72.302512 82.15)
		(width 0.125)
		(layer "F.Cu")
		(net 77)
	)
	(segment
		(start 71.2625 82.425)
		(end 71.1 82.2625)
		(width 0.125)
		(layer "F.Cu")
		(net 77)
	)
	(segment
		(start 72.302512 82.15)
		(end 72.027512 82.425)
		(width 0.125)
		(layer "F.Cu")
		(net 77)
	)
	(segment
		(start 72.027512 82.425)
		(end 71.2625 82.425)
		(width 0.125)
		(layer "F.Cu")
		(net 77)
	)
	(segment
		(start 73.423823 81.778689)
		(end 73.423823 80.281636)
		(width 0.125)
		(layer "F.Cu")
		(net 77)
	)
	(segment
		(start 73.423823 81.778689)
		(end 73.052512 82.15)
		(width 0.125)
		(layer "F.Cu")
		(net 77)
	)
	(via
		(at 71.1 82.2625)
		(size 0.45)
		(drill 0.1)
		(layers "F.Cu" "B.Cu")
		(net 77)
	)
	(segment
		(start 68.077512 81.775)
		(end 69.772488 81.775)
		(width 0.125)
		(layer "In5.Cu")
		(net 77)
	)
	(segment
		(start 47.78237 89.13023)
		(end 47.418211 88.766071)
		(width 0.125)
		(layer "In5.Cu")
		(net 77)
	)
	(segment
		(start 52.87708 84.325434)
		(end 53.000824 84.449178)
		(width 0.125)
		(layer "In5.Cu")
		(net 77)
	)
	(segment
		(start 47.418212 87.981181)
		(end 47.552562 87.846832)
		(width 0.125)
		(layer "In5.Cu")
		(net 77)
	)
	(segment
		(start 54.057949 84.65777)
		(end 53.693789 84.29361)
		(width 0.125)
		(layer "In5.Cu")
		(net 77)
	)
	(segment
		(start 52.580094 86.42554)
		(end 52.714444 86.291189)
		(width 0.125)
		(layer "In5.Cu")
		(net 77)
	)
	(segment
		(start 51.024458 85.159822)
		(end 51.533575 85.668939)
		(width 0.125)
		(layer "In5.Cu")
		(net 77)
	)
	(segment
		(start 53.000824 84.449175)
		(end 53.145781 84.594132)
		(width 0.125)
		(layer "In5.Cu")
		(net 77)
	)
	(segment
		(start 52.714444 86.001275)
		(end 52.205327 85.492158)
		(width 0.125)
		(layer "In5.Cu")
		(net 77)
	)
	(segment
		(start 50.027434 88.688285)
		(end 49.518317 88.179168)
		(width 0.125)
		(layer "In5.Cu")
		(net 77)
	)
	(segment
		(start 51.657319 85.792683)
		(end 51.657319 85.79268)
		(width 0.125)
		(layer "In5.Cu")
		(net 77)
	)
	(segment
		(start 67.581521 82.270991)
		(end 68.077512 81.775)
		(width 0.125)
		(layer "In5.Cu")
		(net 77)
	)
	(segment
		(start 48.761715 86.637676)
		(end 48.896065 86.503327)
		(width 0.125)
		(layer "In5.Cu")
		(net 77)
	)
	(segment
		(start 51.236589 87.769045)
		(end 51.370939 87.634694)
		(width 0.125)
		(layer "In5.Cu")
		(net 77)
	)
	(segment
		(start 56.547512 81.775)
		(end 56.821631 81.775)
		(width 0.125)
		(layer "In5.Cu")
		(net 77)
	)
	(segment
		(start 50.861822 86.835663)
		(end 50.738078 86.711919)
		(width 0.125)
		(layer "In5.Cu")
		(net 77)
	)
	(segment
		(start 45.375 107.552283)
		(end 45.375 107.48)
		(width 0.125)
		(layer "In5.Cu")
		(net 77)
	)
	(segment
		(start 43.67 104.98)
		(end 43.67 105.13)
		(width 0.125)
		(layer "In5.Cu")
		(net 77)
	)
	(segment
		(start 52.081583 85.368414)
		(end 52.081584 85.368417)
		(width 0.125)
		(layer "In5.Cu")
		(net 77)
	)
	(segment
		(start 44.145 105.605)
		(end 45.25 105.605)
		(width 0.125)
		(layer "In5.Cu")
		(net 77)
	)
	(segment
		(start 56.821631 81.775)
		(end 60.772488 81.775)
		(width 0.125)
		(layer "In5.Cu")
		(net 77)
	)
	(segment
		(start 69.772488 81.775)
		(end 70.259988 82.2625)
		(width 0.125)
		(layer "In5.Cu")
		(net 77)
	)
	(segment
		(start 43.67 106.48)
		(end 43.67 106.63)
		(width 0.125)
		(layer "In5.Cu")
		(net 77)
	)
	(segment
		(start 44.145 107.105)
		(end 45.25 107.105)
		(width 0.125)
		(layer "In5.Cu")
		(net 77)
	)
	(segment
		(start 51.533575 85.668939)
		(end 51.657319 85.792683)
		(width 0.125)
		(layer "In5.Cu")
		(net 77)
	)
	(segment
		(start 50.313814 87.136185)
		(end 50.437558 87.259929)
		(width 0.125)
		(layer "In5.Cu")
		(net 77)
	)
	(segment
		(start 43.67 103.48)
		(end 43.67 103.63)
		(width 0.125)
		(layer "In5.Cu")
		(net 77)
	)
	(segment
		(start 45.375 107.622283)
		(end 45.375 107.552283)
		(width 0.125)
		(layer "In5.Cu")
		(net 77)
	)
	(segment
		(start 45.375 91.827512)
		(end 45.375 102.88)
		(width 0.125)
		(layer "In5.Cu")
		(net 77)
	)
	(segment
		(start 48.970309 88.47969)
		(end 49.094053 88.603434)
		(width 0.125)
		(layer "In5.Cu")
		(net 77)
	)
	(segment
		(start 49.27083 87.931683)
		(end 48.761714 87.422566)
		(width 0.125)
		(layer "In5.Cu")
		(net 77)
	)
	(segment
		(start 52.205327 85.492158)
		(end 52.081583 85.368414)
		(width 0.125)
		(layer "In5.Cu")
		(net 77)
	)
	(segment
		(start 45.25 104.505)
		(end 44.145 104.505)
		(width 0.125)
		(layer "In5.Cu")
		(net 77)
	)
	(segment
		(start 53.269525 84.717875)
		(end 53.633685 85.082035)
		(width 0.125)
		(layer "In5.Cu")
		(net 77)
	)
	(segment
		(start 45.375 104.23)
		(end 45.375 104.38)
		(width 0.125)
		(layer "In5.Cu")
		(net 77)
	)
	(segment
		(start 47.782369 89.420143)
		(end 47.78237 89.420144)
		(width 0.125)
		(layer "In5.Cu")
		(net 77)
	)
	(segment
		(start 50.738078 86.711919)
		(end 50.738079 86.711922)
		(width 0.125)
		(layer "In5.Cu")
		(net 77)
	)
	(segment
		(start 45.375 108.497512)
		(end 45.375 108.252283)
		(width 0.125)
		(layer "In5.Cu")
		(net 77)
	)
	(segment
		(start 44.145 104.105)
		(end 45.25 104.105)
		(width 0.125)
		(layer "In5.Cu")
		(net 77)
	)
	(segment
		(start 48.70161 88.210992)
		(end 48.970311 88.479693)
		(width 0.125)
		(layer "In5.Cu")
		(net 77)
	)
	(segment
		(start 55.967512 82.355)
		(end 56.547512 81.775)
		(width 0.125)
		(layer "In5.Cu")
		(net 77)
	)
	(segment
		(start 51.370939 87.34478)
		(end 50.861822 86.835663)
		(width 0.125)
		(layer "In5.Cu")
		(net 77)
	)
	(segment
		(start 48.33745 87.846832)
		(end 48.70161 88.210992)
		(width 0.125)
		(layer "In5.Cu")
		(net 77)
	)
	(segment
		(start 45.083746 107.972283)
		(end 45.083746 107.902283)
		(width 0.125)
		(layer "In5.Cu")
		(net 77)
	)
	(segment
		(start 45.375 105.73)
		(end 45.375 105.88)
		(width 0.125)
		(layer "In5.Cu")
		(net 77)
	)
	(segment
		(start 50.614335 86.588178)
		(end 50.105219 86.079061)
		(width 0.125)
		(layer "In5.Cu")
		(net 77)
	)
	(segment
		(start 50.10522 85.294171)
		(end 50.23957 85.159822)
		(width 0.125)
		(layer "In5.Cu")
		(net 77)
	)
	(segment
		(start 45.235 108.112283)
		(end 45.223746 108.112283)
		(width 0.125)
		(layer "In5.Cu")
		(net 77)
	)
	(segment
		(start 49.394573 88.055424)
		(end 49.394574 88.055427)
		(width 0.125)
		(layer "In5.Cu")
		(net 77)
	)
	(segment
		(start 45.375 107.38)
		(end 45.375 107.48)
		(width 0.125)
		(layer "In5.Cu")
		(net 77)
	)
	(segment
		(start 53.145781 84.594132)
		(end 53.269525 84.717875)
		(width 0.125)
		(layer "In5.Cu")
		(net 77)
	)
	(segment
		(start 49.518317 88.179168)
		(end 49.394573 88.055424)
		(width 0.125)
		(layer "In5.Cu")
		(net 77)
	)
	(segment
		(start 50.437558 87.259929)
		(end 50.946675 87.769045)
		(width 0.125)
		(layer "In5.Cu")
		(net 77)
	)
	(segment
		(start 61.268479 82.270991)
		(end 67.581521 82.270991)
		(width 0.125)
		(layer "In5.Cu")
		(net 77)
	)
	(segment
		(start 52.367963 83.816317)
		(end 52.87708 84.325434)
		(width 0.125)
		(layer "In5.Cu")
		(net 77)
	)
	(segment
		(start 51.657319 85.79268)
		(end 51.781063 85.916424)
		(width 0.125)
		(layer "In5.Cu")
		(net 77)
	)
	(segment
		(start 45.25 106.005)
		(end 44.145 106.005)
		(width 0.125)
		(layer "In5.Cu")
		(net 77)
	)
	(segment
		(start 51.448725 83.950666)
		(end 51.583075 83.816317)
		(width 0.125)
		(layer "In5.Cu")
		(net 77)
	)
	(segment
		(start 51.95784 85.244673)
		(end 51.448724 84.735556)
		(width 0.125)
		(layer "In5.Cu")
		(net 77)
	)
	(segment
		(start 49.893084 89.11255)
		(end 50.027434 88.978199)
		(width 0.125)
		(layer "In5.Cu")
		(net 77)
	)
	(segment
		(start 53.693789 83.508721)
		(end 53.828139 83.374373)
		(width 0.125)
		(layer "In5.Cu")
		(net 77)
	)
	(segment
		(start 49.680953 86.503327)
		(end 50.19007 87.012444)
		(width 0.125)
		(layer "In5.Cu")
		(net 77)
	)
	(segment
		(start 45.375 107.23)
		(end 45.375 107.38)
		(width 0.125)
		(layer "In5.Cu")
		(net 77)
	)
	(segment
		(start 51.781063 85.916424)
		(end 52.29018 86.42554)
		(width 0.125)
		(layer "In5.Cu")
		(net 77)
	)
	(segment
		(start 52.081584 85.368417)
		(end 51.95784 85.244673)
		(width 0.125)
		(layer "In5.Cu")
		(net 77)
	)
	(segment
		(start 53.000824 84.449178)
		(end 53.000824 84.449175)
		(width 0.125)
		(layer "In5.Cu")
		(net 77)
	)
	(segment
		(start 45.223746 107.762283)
		(end 45.235 107.762283)
		(width 0.125)
		(layer "In5.Cu")
		(net 77)
	)
	(segment
		(start 49.094053 88.603434)
		(end 49.60317 89.11255)
		(width 0.125)
		(layer "In5.Cu")
		(net 77)
	)
	(segment
		(start 50.19007 87.012444)
		(end 50.313814 87.136188)
		(width 0.125)
		(layer "In5.Cu")
		(net 77)
	)
	(segment
		(start 43.746397 108.616397)
		(end 44.2 109.07)
		(width 0.125)
		(layer "In5.Cu")
		(net 77)
	)
	(segment
		(start 50.738079 86.711922)
		(end 50.614335 86.588178)
		(width 0.125)
		(layer "In5.Cu")
		(net 77)
	)
	(segment
		(start 53.923599 85.082035)
		(end 54.057949 84.947684)
		(width 0.125)
		(layer "In5.Cu")
		(net 77)
	)
	(segment
		(start 70.259988 82.2625)
		(end 71.1 82.2625)
		(width 0.125)
		(layer "In5.Cu")
		(net 77)
	)
	(segment
		(start 44.802512 109.07)
		(end 45.375 108.497512)
		(width 0.125)
		(layer "In5.Cu")
		(net 77)
	)
	(segment
		(start 54.847512 82.355)
		(end 55.967512 82.355)
		(width 0.125)
		(layer "In5.Cu")
		(net 77)
	)
	(segment
		(start 48.970311 88.479693)
		(end 48.970309 88.47969)
		(width 0.125)
		(layer "In5.Cu")
		(net 77)
	)
	(segment
		(start 53.828139 83.374373)
		(end 54.847512 82.355)
		(width 0.125)
		(layer "In5.Cu")
		(net 77)
	)
	(segment
		(start 49.394574 88.055427)
		(end 49.27083 87.931683)
		(width 0.125)
		(layer "In5.Cu")
		(net 77)
	)
	(segment
		(start 60.772488 81.775)
		(end 61.268479 82.270991)
		(width 0.125)
		(layer "In5.Cu")
		(net 77)
	)
	(segment
		(start 50.313814 87.136188)
		(end 50.313814 87.136185)
		(width 0.125)
		(layer "In5.Cu")
		(net 77)
	)
	(segment
		(start 45.25 103.005)
		(end 44.145 103.005)
		(width 0.125)
		(layer "In5.Cu")
		(net 77)
	)
	(segment
		(start 47.782369 89.420143)
		(end 45.375 91.827512)
		(width 0.125)
		(layer "In5.Cu")
		(net 77)
	)
	(segment
		(start 44.2 109.07)
		(end 44.802512 109.07)
		(width 0.125)
		(layer "In5.Cu")
		(net 77)
	)
	(arc
		(start 44.145 104.505)
		(mid 43.809124 104.644124)
		(end 43.67 104.98)
		(width 0.125)
		(layer "In5.Cu")
		(net 77)
	)
	(arc
		(start 54.057949 84.947684)
		(mid 54.117992 84.802727)
		(end 54.057949 84.65777)
		(width 0.125)
		(layer "In5.Cu")
		(net 77)
	)
	(arc
		(start 45.25 105.605)
		(mid 45.338388 105.641612)
		(end 45.375 105.73)
		(width 0.125)
		(layer "In5.Cu")
		(net 77)
	)
	(arc
		(start 45.375 105.88)
		(mid 45.338388 105.968388)
		(end 45.25 106.005)
		(width 0.125)
		(layer "In5.Cu")
		(net 77)
	)
	(arc
		(start 52.714444 86.291189)
		(mid 52.774487 86.146232)
		(end 52.714444 86.001275)
		(width 0.125)
		(layer "In5.Cu")
		(net 77)
	)
	(arc
		(start 45.375 108.252283)
		(mid 45.333995 108.153288)
		(end 45.235 108.112283)
		(width 0.125)
		(layer "In5.Cu")
		(net 77)
	)
	(arc
		(start 48.896065 86.503327)
		(mid 49.288509 86.340771)
		(end 49.680953 86.503327)
		(width 0.125)
		(layer "In5.Cu")
		(net 77)
	)
	(arc
		(start 45.25 107.105)
		(mid 45.338388 107.141612)
		(end 45.375 107.23)
		(width 0.125)
		(layer "In5.Cu")
		(net 77)
	)
	(arc
		(start 50.946675 87.769045)
		(mid 51.091632 87.829088)
		(end 51.236589 87.769045)
		(width 0.125)
		(layer "In5.Cu")
		(net 77)
	)
	(arc
		(start 53.693789 84.29361)
		(mid 53.531233 83.901166)
		(end 53.693789 83.508721)
		(width 0.125)
		(layer "In5.Cu")
		(net 77)
	)
	(arc
		(start 43.67 106.63)
		(mid 43.809124 106.965876)
		(end 44.145 107.105)
		(width 0.125)
		(layer "In5.Cu")
		(net 77)
	)
	(arc
		(start 53.633685 85.082035)
		(mid 53.778642 85.142078)
		(end 53.923599 85.082035)
		(width 0.125)
		(layer "In5.Cu")
		(net 77)
	)
	(arc
		(start 47.78237 89.420144)
		(mid 47.842413 89.275187)
		(end 47.78237 89.13023)
		(width 0.125)
		(layer "In5.Cu")
		(net 77)
	)
	(arc
		(start 44.145 106.005)
		(mid 43.809124 106.144124)
		(end 43.67 106.48)
		(width 0.125)
		(layer "In5.Cu")
		(net 77)
	)
	(arc
		(start 47.552562 87.846832)
		(mid 47.945006 87.684276)
		(end 48.33745 87.846832)
		(width 0.125)
		(layer "In5.Cu")
		(net 77)
	)
	(arc
		(start 45.375 102.88)
		(mid 45.338388 102.968388)
		(end 45.25 103.005)
		(width 0.125)
		(layer "In5.Cu")
		(net 77)
	)
	(arc
		(start 50.105219 86.079061)
		(mid 49.942664 85.686616)
		(end 50.10522 85.294171)
		(width 0.125)
		(layer "In5.Cu")
		(net 77)
	)
	(arc
		(start 51.583075 83.816317)
		(mid 51.975519 83.653761)
		(end 52.367963 83.816317)
		(width 0.125)
		(layer "In5.Cu")
		(net 77)
	)
	(arc
		(start 43.67 105.13)
		(mid 43.809124 105.465876)
		(end 44.145 105.605)
		(width 0.125)
		(layer "In5.Cu")
		(net 77)
	)
	(arc
		(start 49.60317 89.11255)
		(mid 49.748127 89.172593)
		(end 49.893084 89.11255)
		(width 0.125)
		(layer "In5.Cu")
		(net 77)
	)
	(arc
		(start 47.418211 88.766071)
		(mid 47.255656 88.373626)
		(end 47.418212 87.981181)
		(width 0.125)
		(layer "In5.Cu")
		(net 77)
	)
	(arc
		(start 45.083746 107.902283)
		(mid 45.124751 107.803288)
		(end 45.223746 107.762283)
		(width 0.125)
		(layer "In5.Cu")
		(net 77)
	)
	(arc
		(start 45.375 104.38)
		(mid 45.338388 104.468388)
		(end 45.25 104.505)
		(width 0.125)
		(layer "In5.Cu")
		(net 77)
	)
	(arc
		(start 50.027434 88.978199)
		(mid 50.087477 88.833242)
		(end 50.027434 88.688285)
		(width 0.125)
		(layer "In5.Cu")
		(net 77)
	)
	(arc
		(start 51.448724 84.735556)
		(mid 51.286169 84.343111)
		(end 51.448725 83.950666)
		(width 0.125)
		(layer "In5.Cu")
		(net 77)
	)
	(arc
		(start 43.67 103.63)
		(mid 43.809124 103.965876)
		(end 44.145 104.105)
		(width 0.125)
		(layer "In5.Cu")
		(net 77)
	)
	(arc
		(start 52.29018 86.42554)
		(mid 52.435137 86.485583)
		(end 52.580094 86.42554)
		(width 0.125)
		(layer "In5.Cu")
		(net 77)
	)
	(arc
		(start 45.223746 108.112283)
		(mid 45.124751 108.071278)
		(end 45.083746 107.972283)
		(width 0.125)
		(layer "In5.Cu")
		(net 77)
	)
	(arc
		(start 45.25 104.105)
		(mid 45.338388 104.141612)
		(end 45.375 104.23)
		(width 0.125)
		(layer "In5.Cu")
		(net 77)
	)
	(arc
		(start 51.370939 87.634694)
		(mid 51.430982 87.489737)
		(end 51.370939 87.34478)
		(width 0.125)
		(layer "In5.Cu")
		(net 77)
	)
	(arc
		(start 48.761714 87.422566)
		(mid 48.599159 87.030121)
		(end 48.761715 86.637676)
		(width 0.125)
		(layer "In5.Cu")
		(net 77)
	)
	(arc
		(start 50.23957 85.159822)
		(mid 50.632014 84.997266)
		(end 51.024458 85.159822)
		(width 0.125)
		(layer "In5.Cu")
		(net 77)
	)
	(arc
		(start 45.235 107.762283)
		(mid 45.333995 107.721278)
		(end 45.375 107.622283)
		(width 0.125)
		(layer "In5.Cu")
		(net 77)
	)
	(arc
		(start 44.145 103.005)
		(mid 43.809124 103.144124)
		(end 43.67 103.48)
		(width 0.125)
		(layer "In5.Cu")
		(net 77)
	)
	(segment
		(start 136.23 97.73)
		(end 136.47 97.97)
		(width 0.15)
		(layer "F.Cu")
		(net 78)
	)
	(segment
		(start 71.6 70.06)
		(end 71.597323 70.062677)
		(width 0.15)
		(layer "F.Cu")
		(net 78)
	)
	(segment
		(start 71.597323 70.062677)
		(end 71.597323 72.005136)
		(width 0.15)
		(layer "F.Cu")
		(net 78)
	)
	(segment
		(start 71.6 69.95)
		(end 71.6 70.06)
		(width 0.15)
		(layer "F.Cu")
		(net 78)
	)
	(segment
		(start 136.47 97.97)
		(end 136.95 97.97)
		(width 0.15)
		(layer "F.Cu")
		(net 78)
	)
	(segment
		(start 136.23 96.91)
		(end 136.23 97.73)
		(width 0.15)
		(layer "F.Cu")
		(net 78)
	)
	(via
		(at 136.23 96.91)
		(size 0.45)
		(drill 0.1)
		(layers "F.Cu" "B.Cu")
		(net 78)
	)
	(via
		(at 137.6 100.53)
		(size 0.45)
		(drill 0.1)
		(layers "F.Cu" "B.Cu")
		(net 78)
	)
	(via
		(at 71.6 69.95)
		(size 0.45)
		(drill 0.1)
		(layers "F.Cu" "B.Cu")
		(net 78)
	)
	(segment
		(start 68.1 72.35)
		(end 69.49 70.96)
		(width 0.125)
		(layer "In3.Cu")
		(net 78)
	)
	(segment
		(start 67.042892 92.45)
		(end 66.15 91.557107)
		(width 0.125)
		(layer "In3.Cu")
		(net 78)
	)
	(segment
		(start 101.028554 104.728554)
		(end 90.778554 104.728554)
		(width 0.125)
		(layer "In3.Cu")
		(net 78)
	)
	(segment
		(start 105.57 111.37)
		(end 105.57 109.27)
		(width 0.125)
		(layer "In3.Cu")
		(net 78)
	)
	(segment
		(start 68.1 78.435784)
		(end 68.1 72.35)
		(width 0.125)
		(layer "In3.Cu")
		(net 78)
	)
	(segment
		(start 105.57 109.27)
		(end 101.028554 104.728554)
		(width 0.125)
		(layer "In3.Cu")
		(net 78)
	)
	(segment
		(start 67.8 78.735784)
		(end 68.1 78.435784)
		(width 0.125)
		(layer "In3.Cu")
		(net 78)
	)
	(segment
		(start 136.95 103.39)
		(end 135.87 103.39)
		(width 0.125)
		(layer "In3.Cu")
		(net 78)
	)
	(segment
		(start 137.63 102.71)
		(end 136.95 103.39)
		(width 0.125)
		(layer "In3.Cu")
		(net 78)
	)
	(segment
		(start 89.807108 105.7)
		(end 85.4 105.7)
		(width 0.125)
		(layer "In3.Cu")
		(net 78)
	)
	(segment
		(start 85.4 105.7)
		(end 84.25 104.55)
		(width 0.125)
		(layer "In3.Cu")
		(net 78)
	)
	(segment
		(start 69.7 93.614216)
		(end 68.535784 92.45)
		(width 0.125)
		(layer "In3.Cu")
		(net 78)
	)
	(segment
		(start 137.63 100.56)
		(end 137.63 102.71)
		(width 0.125)
		(layer "In3.Cu")
		(net 78)
	)
	(segment
		(start 125.41 113.85)
		(end 108.05 113.85)
		(width 0.125)
		(layer "In3.Cu")
		(net 78)
	)
	(segment
		(start 77.55 104.55)
		(end 72.375 99.375)
		(width 0.125)
		(layer "In3.Cu")
		(net 78)
	)
	(segment
		(start 68.535784 92.45)
		(end 67.042892 92.45)
		(width 0.125)
		(layer "In3.Cu")
		(net 78)
	)
	(segment
		(start 66.15 91.557107)
		(end 66.15 88.19)
		(width 0.125)
		(layer "In3.Cu")
		(net 78)
	)
	(segment
		(start 67.8 86.54)
		(end 67.8 78.735784)
		(width 0.125)
		(layer "In3.Cu")
		(net 78)
	)
	(segment
		(start 84.25 104.55)
		(end 77.55 104.55)
		(width 0.125)
		(layer "In3.Cu")
		(net 78)
	)
	(segment
		(start 72.375 99.375)
		(end 72.375 98.775)
		(width 0.125)
		(layer "In3.Cu")
		(net 78)
	)
	(segment
		(start 70.59 70.96)
		(end 71.6 69.95)
		(width 0.125)
		(layer "In3.Cu")
		(net 78)
	)
	(segment
		(start 108.05 113.85)
		(end 105.57 111.37)
		(width 0.125)
		(layer "In3.Cu")
		(net 78)
	)
	(segment
		(start 72.375 98.775)
		(end 69.7 96.1)
		(width 0.125)
		(layer "In3.Cu")
		(net 78)
	)
	(segment
		(start 90.778554 104.728554)
		(end 89.807108 105.7)
		(width 0.125)
		(layer "In3.Cu")
		(net 78)
	)
	(segment
		(start 135.87 103.39)
		(end 125.41 113.85)
		(width 0.125)
		(layer "In3.Cu")
		(net 78)
	)
	(segment
		(start 69.7 96.1)
		(end 69.7 93.614216)
		(width 0.125)
		(layer "In3.Cu")
		(net 78)
	)
	(segment
		(start 66.15 88.19)
		(end 67.8 86.54)
		(width 0.125)
		(layer "In3.Cu")
		(net 78)
	)
	(segment
		(start 137.6 100.53)
		(end 137.63 100.56)
		(width 0.125)
		(layer "In3.Cu")
		(net 78)
	)
	(segment
		(start 69.49 70.96)
		(end 70.59 70.96)
		(width 0.125)
		(layer "In3.Cu")
		(net 78)
	)
	(segment
		(start 134.24 102.05)
		(end 134.88 102.05)
		(width 0.15)
		(layer "B.Cu")
		(net 78)
	)
	(segment
		(start 133.58 98.36)
		(end 133.58 101.39)
		(width 0.15)
		(layer "B.Cu")
		(net 78)
	)
	(segment
		(start 136.23 96.91)
		(end 135.03 96.91)
		(width 0.15)
		(layer "B.Cu")
		(net 78)
	)
	(segment
		(start 134.88 102.05)
		(end 136.4 100.53)
		(width 0.15)
		(layer "B.Cu")
		(net 78)
	)
	(segment
		(start 136.4 100.53)
		(end 137.6 100.53)
		(width 0.15)
		(layer "B.Cu")
		(net 78)
	)
	(segment
		(start 133.58 101.39)
		(end 134.24 102.05)
		(width 0.15)
		(layer "B.Cu")
		(net 78)
	)
	(segment
		(start 135.03 96.91)
		(end 133.58 98.36)
		(width 0.15)
		(layer "B.Cu")
		(net 78)
	)
	(segment
		(start 94.95 101.115)
		(end 95.665 100.4)
		(width 0.125)
		(layer "F.Cu")
		(net 79)
	)
	(segment
		(start 70.59 73.25)
		(end 70.597323 73.242677)
		(width 0.15)
		(layer "F.Cu")
		(net 79)
	)
	(segment
		(start 94.95 102.075)
		(end 94.95 101.115)
		(width 0.125)
		(layer "F.Cu")
		(net 79)
	)
	(segment
		(start 70.597323 73.242677)
		(end 70.597323 72.005136)
		(width 0.15)
		(layer "F.Cu")
		(net 79)
	)
	(via
		(at 70.59 73.25)
		(size 0.45)
		(drill 0.1)
		(layers "F.Cu" "B.Cu")
		(net 79)
	)
	(via
		(at 94.95 102.075)
		(size 0.45)
		(drill 0.1)
		(layers "F.Cu" "B.Cu")
		(net 79)
	)
	(segment
		(start 70.5 74.3)
		(end 71.1 74.3)
		(width 0.125)
		(layer "In3.Cu")
		(net 79)
	)
	(segment
		(start 72.4 95)
		(end 72.4 89.043614)
		(width 0.125)
		(layer "In3.Cu")
		(net 79)
	)
	(segment
		(start 77.18 99.22)
		(end 76.62 99.22)
		(width 0.125)
		(layer "In3.Cu")
		(net 79)
	)
	(segment
		(start 70.69 87.333614)
		(end 70.69 83.97)
		(width 0.125)
		(layer "In3.Cu")
		(net 79)
	)
	(segment
		(start 85.07 102.17)
		(end 80.13 102.17)
		(width 0.125)
		(layer "In3.Cu")
		(net 79)
	)
	(segment
		(start 71.1 74.3)
		(end 71.3 74.1)
		(width 0.125)
		(layer "In3.Cu")
		(net 79)
	)
	(segment
		(start 94.125 101.25)
		(end 90.27 101.25)
		(width 0.125)
		(layer "In3.Cu")
		(net 79)
	)
	(segment
		(start 90.27 101.25)
		(end 87.82 103.7)
		(width 0.125)
		(layer "In3.Cu")
		(net 79)
	)
	(segment
		(start 80.13 102.17)
		(end 77.18 99.22)
		(width 0.125)
		(layer "In3.Cu")
		(net 79)
	)
	(segment
		(start 72.4 89.043614)
		(end 70.69 87.333614)
		(width 0.125)
		(layer "In3.Cu")
		(net 79)
	)
	(segment
		(start 94.95 102.075)
		(end 94.125 101.25)
		(width 0.125)
		(layer "In3.Cu")
		(net 79)
	)
	(segment
		(start 70.2875 74.5125)
		(end 70.5 74.3)
		(width 0.125)
		(layer "In3.Cu")
		(net 79)
	)
	(segment
		(start 86.6 103.7)
		(end 85.07 102.17)
		(width 0.125)
		(layer "In3.Cu")
		(net 79)
	)
	(segment
		(start 76.62 99.22)
		(end 72.4 95)
		(width 0.125)
		(layer "In3.Cu")
		(net 79)
	)
	(segment
		(start 70.69 83.97)
		(end 70.2875 83.5675)
		(width 0.125)
		(layer "In3.Cu")
		(net 79)
	)
	(segment
		(start 71.3 73.5)
		(end 71.05 73.25)
		(width 0.125)
		(layer "In3.Cu")
		(net 79)
	)
	(segment
		(start 70.2875 83.5675)
		(end 70.2875 74.5125)
		(width 0.125)
		(layer "In3.Cu")
		(net 79)
	)
	(segment
		(start 71.3 74.1)
		(end 71.3 73.5)
		(width 0.125)
		(layer "In3.Cu")
		(net 79)
	)
	(segment
		(start 71.05 73.25)
		(end 70.59 73.25)
		(width 0.125)
		(layer "In3.Cu")
		(net 79)
	)
	(segment
		(start 87.82 103.7)
		(end 86.6 103.7)
		(width 0.125)
		(layer "In3.Cu")
		(net 79)
	)
	(segment
		(start 70.9 78.775)
		(end 70.847323 78.827677)
		(width 0.15)
		(layer "F.Cu")
		(net 80)
	)
	(segment
		(start 102.15 123.95)
		(end 102.15 124.902)
		(width 0.125)
		(layer "F.Cu")
		(net 80)
	)
	(segment
		(start 105.55 125.6)
		(end 106.05 125.1)
		(width 0.155)
		(layer "F.Cu")
		(net 80)
	)
	(segment
		(start 101.952 125.1)
		(end 102.452 125.6)
		(width 0.155)
		(layer "F.Cu")
		(net 80)
	)
	(segment
		(start 70.847323 78.827677)
		(end 70.847323 80.205136)
		(width 0.15)
		(layer "F.Cu")
		(net 80)
	)
	(segment
		(start 102.452 125.6)
		(end 105.55 125.6)
		(width 0.155)
		(layer "F.Cu")
		(net 80)
	)
	(segment
		(start 102.15 124.902)
		(end 101.952 125.1)
		(width 0.125)
		(layer "F.Cu")
		(net 80)
	)
	(via
		(at 86.7755 116.55)
		(size 0.45)
		(drill 0.1)
		(layers "F.Cu" "B.Cu")
		(net 80)
	)
	(via
		(at 82.164182 92.435818)
		(size 0.45)
		(drill 0.1)
		(layers "F.Cu" "B.Cu")
		(net 80)
	)
	(via
		(at 102.15 123.95)
		(size 0.45)
		(drill 0.1)
		(layers "F.Cu" "B.Cu")
		(net 80)
	)
	(via
		(at 70.9 78.775)
		(size 0.45)
		(drill 0.1)
		(layers "F.Cu" "B.Cu")
		(net 80)
	)
	(segment
		(start 70.225 79.45)
		(end 70.9 78.775)
		(width 0.15)
		(layer "In1.Cu")
		(net 80)
	)
	(segment
		(start 82.164182 92.435818)
		(end 81.995818 92.435818)
		(width 0.15)
		(layer "In1.Cu")
		(net 80)
	)
	(segment
		(start 71.65 84.15)
		(end 70.425 84.15)
		(width 0.15)
		(layer "In1.Cu")
		(net 80)
	)
	(segment
		(start 75.18 87.04)
		(end 75.18 85.09)
		(width 0.15)
		(layer "In1.Cu")
		(net 80)
	)
	(segment
		(start 75.59 87.45)
		(end 75.18 87.04)
		(width 0.15)
		(layer "In1.Cu")
		(net 80)
	)
	(segment
		(start 70.425 84.15)
		(end 70.225 83.95)
		(width 0.15)
		(layer "In1.Cu")
		(net 80)
	)
	(segment
		(start 77.01 87.45)
		(end 75.59 87.45)
		(width 0.15)
		(layer "In1.Cu")
		(net 80)
	)
	(segment
		(start 75.18 85.09)
		(end 74.52 84.43)
		(width 0.15)
		(layer "In1.Cu")
		(net 80)
	)
	(segment
		(start 74.52 84.43)
		(end 71.93 84.43)
		(width 0.15)
		(layer "In1.Cu")
		(net 80)
	)
	(segment
		(start 70.225 83.95)
		(end 70.225 79.45)
		(width 0.15)
		(layer "In1.Cu")
		(net 80)
	)
	(segment
		(start 81.995818 92.435818)
		(end 77.01 87.45)
		(width 0.15)
		(layer "In1.Cu")
		(net 80)
	)
	(segment
		(start 71.93 84.43)
		(end 71.65 84.15)
		(width 0.15)
		(layer "In1.Cu")
		(net 80)
	)
	(segment
		(start 101 123.55)
		(end 101.4 123.95)
		(width 0.125)
		(layer "In5.Cu")
		(net 80)
	)
	(segment
		(start 101.4 123.95)
		(end 102.15 123.95)
		(width 0.125)
		(layer "In5.Cu")
		(net 80)
	)
	(segment
		(start 101 120.3)
		(end 101 123.55)
		(width 0.125)
		(layer "In5.Cu")
		(net 80)
	)
	(segment
		(start 87.65 117.4245)
		(end 87.65 119.75)
		(width 0.125)
		(layer "In5.Cu")
		(net 80)
	)
	(segment
		(start 87.65 119.75)
		(end 87.9 120)
		(width 0.125)
		(layer "In5.Cu")
		(net 80)
	)
	(segment
		(start 87.9 120)
		(end 100.7 120)
		(width 0.125)
		(layer "In5.Cu")
		(net 80)
	)
	(segment
		(start 100.7 120)
		(end 101 120.3)
		(width 0.125)
		(layer "In5.Cu")
		(net 80)
	)
	(segment
		(start 86.7755 116.55)
		(end 87.65 117.4245)
		(width 0.125)
		(layer "In5.Cu")
		(net 80)
	)
	(segment
		(start 83.2 93.42)
		(end 83.2 96.57)
		(width 0.125)
		(layer "B.Cu")
		(net 80)
	)
	(segment
		(start 102 123.8)
		(end 102.15 123.95)
		(width 0.125)
		(layer "B.Cu")
		(net 80)
	)
	(segment
		(start 83 102.55)
		(end 83 108.125)
		(width 0.125)
		(layer "B.Cu")
		(net 80)
	)
	(segment
		(start 86.25 112.175)
		(end 86.25 115.9)
		(width 0.125)
		(layer "B.Cu")
		(net 80)
	)
	(segment
		(start 82.765 102.315)
		(end 83 102.55)
		(width 0.125)
		(layer "B.Cu")
		(net 80)
	)
	(segment
		(start 101.85 123.8)
		(end 102 123.8)
		(width 0.125)
		(layer "B.Cu")
		(net 80)
	)
	(segment
		(start 83.2 96.57)
		(end 82.765 97.005)
		(width 0.125)
		(layer "B.Cu")
		(net 80)
	)
	(segment
		(start 82.215818 92.435818)
		(end 83.2 93.42)
		(width 0.125)
		(layer "B.Cu")
		(net 80)
	)
	(segment
		(start 84.05 109.175)
		(end 84.05 109.975)
		(width 0.125)
		(layer "B.Cu")
		(net 80)
	)
	(segment
		(start 83 108.125)
		(end 84.05 109.175)
		(width 0.125)
		(layer "B.Cu")
		(net 80)
	)
	(segment
		(start 84.05 109.975)
		(end 86.25 112.175)
		(width 0.125)
		(layer "B.Cu")
		(net 80)
	)
	(segment
		(start 82.765 97.005)
		(end 82.765 102.315)
		(width 0.125)
		(layer "B.Cu")
		(net 80)
	)
	(segment
		(start 86.7755 116.4255)
		(end 86.7755 116.55)
		(width 0.125)
		(layer "B.Cu")
		(net 80)
	)
	(segment
		(start 82.164182 92.435818)
		(end 82.215818 92.435818)
		(width 0.125)
		(layer "B.Cu")
		(net 80)
	)
	(segment
		(start 86.25 115.9)
		(end 86.7755 116.4255)
		(width 0.125)
		(layer "B.Cu")
		(net 80)
	)
	(segment
		(start 70.255523 73.742378)
		(end 70.322901 73.675)
		(width 0.15)
		(layer "F.Cu")
		(net 81)
	)
	(segment
		(start 95.525 101.54)
		(end 95.665 101.4)
		(width 0.125)
		(layer "F.Cu")
		(net 81)
	)
	(segment
		(start 70.766041 73.675)
		(end 71.097323 73.343718)
		(width 0.15)
		(layer "F.Cu")
		(net 81)
	)
	(segment
		(start 71.097323 73.343718)
		(end 71.097323 72.005136)
		(width 0.15)
		(layer "F.Cu")
		(net 81)
	)
	(segment
		(start 95.525 102.1)
		(end 95.525 101.54)
		(width 0.125)
		(layer "F.Cu")
		(net 81)
	)
	(segment
		(start 70.322901 73.675)
		(end 70.766041 73.675)
		(width 0.15)
		(layer "F.Cu")
		(net 81)
	)
	(via
		(at 95.525 102.1)
		(size 0.45)
		(drill 0.1)
		(layers "F.Cu" "B.Cu")
		(net 81)
	)
	(via
		(at 70.255523 73.742378)
		(size 0.45)
		(drill 0.1)
		(layers "F.Cu" "B.Cu")
		(net 81)
	)
	(segment
		(start 94.92 102.73)
		(end 95.5 102.15)
		(width 0.125)
		(layer "In3.Cu")
		(net 81)
	)
	(segment
		(start 76.47 99.47)
		(end 77.04 99.47)
		(width 0.125)
		(layer "In3.Cu")
		(net 81)
	)
	(segment
		(start 70.255523 73.744477)
		(end 69.97 74.03)
		(width 0.125)
		(layer "In3.Cu")
		(net 81)
	)
	(segment
		(start 69.97 83.61)
		(end 70.42 84.06)
		(width 0.125)
		(layer "In3.Cu")
		(net 81)
	)
	(segment
		(start 72.1 95.1)
		(end 76.47 99.47)
		(width 0.125)
		(layer "In3.Cu")
		(net 81)
	)
	(segment
		(start 70.42 84.06)
		(end 70.42 87.42)
		(width 0.125)
		(layer "In3.Cu")
		(net 81)
	)
	(segment
		(start 87.93 103.95)
		(end 90.27 101.61)
		(width 0.125)
		(layer "In3.Cu")
		(net 81)
	)
	(segment
		(start 90.27 101.61)
		(end 93.62 101.61)
		(width 0.125)
		(layer "In3.Cu")
		(net 81)
	)
	(segment
		(start 70.255523 73.742378)
		(end 70.255523 73.744477)
		(width 0.125)
		(layer "In3.Cu")
		(net 81)
	)
	(segment
		(start 80.05 102.48)
		(end 84.98 102.48)
		(width 0.125)
		(layer "In3.Cu")
		(net 81)
	)
	(segment
		(start 77.04 99.47)
		(end 80.05 102.48)
		(width 0.125)
		(layer "In3.Cu")
		(net 81)
	)
	(segment
		(start 69.97 74.03)
		(end 69.97 83.61)
		(width 0.125)
		(layer "In3.Cu")
		(net 81)
	)
	(segment
		(start 86.45 103.95)
		(end 87.93 103.95)
		(width 0.125)
		(layer "In3.Cu")
		(net 81)
	)
	(segment
		(start 94.74 102.73)
		(end 94.92 102.73)
		(width 0.125)
		(layer "In3.Cu")
		(net 81)
	)
	(segment
		(start 70.42 87.42)
		(end 72.1 89.1)
		(width 0.125)
		(layer "In3.Cu")
		(net 81)
	)
	(segment
		(start 72.1 89.1)
		(end 72.1 95.1)
		(width 0.125)
		(layer "In3.Cu")
		(net 81)
	)
	(segment
		(start 84.98 102.48)
		(end 86.45 103.95)
		(width 0.125)
		(layer "In3.Cu")
		(net 81)
	)
	(segment
		(start 93.62 101.61)
		(end 94.74 102.73)
		(width 0.125)
		(layer "In3.Cu")
		(net 81)
	)
	(segment
		(start 148.8 99.15)
		(end 149 99.35)
		(width 0.15)
		(layer "F.Cu")
		(net 82)
	)
	(segment
		(start 71.146 84.640472)
		(end 71.146 84.92)
		(width 0.15)
		(layer "F.Cu")
		(net 82)
	)
	(segment
		(start 148.3 99.15)
		(end 148.8 99.15)
		(width 0.15)
		(layer "F.Cu")
		(net 82)
	)
	(segment
		(start 70.25 83.744472)
		(end 71.146 84.640472)
		(width 0.15)
		(layer "F.Cu")
		(net 82)
	)
	(segment
		(start 70.347323 80.205136)
		(end 70.25 80.302459)
		(width 0.15)
		(layer "F.Cu")
		(net 82)
	)
	(segment
		(start 70.25 80.302459)
		(end 70.25 83.744472)
		(width 0.15)
		(layer "F.Cu")
		(net 82)
	)
	(via
		(at 149 99.35)
		(size 0.45)
		(drill 0.1)
		(layers "F.Cu" "B.Cu")
		(net 82)
	)
	(via
		(at 71.146 84.92)
		(size 0.45)
		(drill 0.1)
		(layers "F.Cu" "B.Cu")
		(net 82)
	)
	(segment
		(start 65.6 86.7)
		(end 65.16 86.26)
		(width 0.125)
		(layer "In5.Cu")
		(net 82)
	)
	(segment
		(start 71.3 95.496446)
		(end 70.043554 94.24)
		(width 0.125)
		(layer "In5.Cu")
		(net 82)
	)
	(segment
		(start 145.3 102.475)
		(end 142.7 102.475)
		(width 0.125)
		(layer "In5.Cu")
		(net 82)
	)
	(segment
		(start 72.453554 105.5)
		(end 71.3 104.346446)
		(width 0.125)
		(layer "In5.Cu")
		(net 82)
	)
	(segment
		(start 91.9 104.8)
		(end 83.05 104.8)
		(width 0.125)
		(layer "In5.Cu")
		(net 82)
	)
	(segment
		(start 82.35 105.5)
		(end 72.453554 105.5)
		(width 0.125)
		(layer "In5.Cu")
		(net 82)
	)
	(segment
		(start 65.6 91.5)
		(end 65.6 86.7)
		(width 0.125)
		(layer "In5.Cu")
		(net 82)
	)
	(segment
		(start 65.6 84.6)
		(end 68.3 84.6)
		(width 0.125)
		(layer "In5.Cu")
		(net 82)
	)
	(segment
		(start 71.016 85.05)
		(end 71.146 84.92)
		(width 0.125)
		(layer "In5.Cu")
		(net 82)
	)
	(segment
		(start 65.16 86.26)
		(end 65.16 85.04)
		(width 0.125)
		(layer "In5.Cu")
		(net 82)
	)
	(segment
		(start 65.16 85.04)
		(end 65.6 84.6)
		(width 0.125)
		(layer "In5.Cu")
		(net 82)
	)
	(segment
		(start 71.3 104.346446)
		(end 71.3 95.496446)
		(width 0.125)
		(layer "In5.Cu")
		(net 82)
	)
	(segment
		(start 148.425 99.35)
		(end 145.3 102.475)
		(width 0.125)
		(layer "In5.Cu")
		(net 82)
	)
	(segment
		(start 139.2 105.975)
		(end 136.55 105.975)
		(width 0.125)
		(layer "In5.Cu")
		(net 82)
	)
	(segment
		(start 70.043554 94.24)
		(end 68.34 94.24)
		(width 0.125)
		(layer "In5.Cu")
		(net 82)
	)
	(segment
		(start 149 99.35)
		(end 148.425 99.35)
		(width 0.125)
		(layer "In5.Cu")
		(net 82)
	)
	(segment
		(start 68.75 85.05)
		(end 71.016 85.05)
		(width 0.125)
		(layer "In5.Cu")
		(net 82)
	)
	(segment
		(start 128.05 108.25)
		(end 124.1 112.2)
		(width 0.125)
		(layer "In5.Cu")
		(net 82)
	)
	(segment
		(start 134.275 108.25)
		(end 128.05 108.25)
		(width 0.125)
		(layer "In5.Cu")
		(net 82)
	)
	(segment
		(start 136.55 105.975)
		(end 134.275 108.25)
		(width 0.125)
		(layer "In5.Cu")
		(net 82)
	)
	(segment
		(start 99.3 112.2)
		(end 91.9 104.8)
		(width 0.125)
		(layer "In5.Cu")
		(net 82)
	)
	(segment
		(start 124.1 112.2)
		(end 99.3 112.2)
		(width 0.125)
		(layer "In5.Cu")
		(net 82)
	)
	(segment
		(start 83.05 104.8)
		(end 82.35 105.5)
		(width 0.125)
		(layer "In5.Cu")
		(net 82)
	)
	(segment
		(start 68.34 94.24)
		(end 65.6 91.5)
		(width 0.125)
		(layer "In5.Cu")
		(net 82)
	)
	(segment
		(start 68.3 84.6)
		(end 68.75 85.05)
		(width 0.125)
		(layer "In5.Cu")
		(net 82)
	)
	(segment
		(start 142.7 102.475)
		(end 139.2 105.975)
		(width 0.125)
		(layer "In5.Cu")
		(net 82)
	)
	(segment
		(start 69.05 87)
		(end 67.48 87)
		(width 0.125)
		(layer "F.Cu")
		(net 83)
	)
	(segment
		(start 68.74 82.79)
		(end 68.74 84.48)
		(width 0.125)
		(layer "F.Cu")
		(net 83)
	)
	(segment
		(start 69.89 85.67)
		(end 69.3 86.26)
		(width 0.125)
		(layer "F.Cu")
		(net 83)
	)
	(segment
		(start 69.89 85.22)
		(end 69.89 85.67)
		(width 0.125)
		(layer "F.Cu")
		(net 83)
	)
	(segment
		(start 69.57 84.9)
		(end 69.89 85.22)
		(width 0.125)
		(layer "F.Cu")
		(net 83)
	)
	(segment
		(start 148.975 98.75)
		(end 148.825 98.6)
		(width 0.15)
		(layer "F.Cu")
		(net 83)
	)
	(segment
		(start 69.16 84.9)
		(end 69.57 84.9)
		(width 0.125)
		(layer "F.Cu")
		(net 83)
	)
	(segment
		(start 69.3 86.26)
		(end 69.3 86.75)
		(width 0.125)
		(layer "F.Cu")
		(net 83)
	)
	(segment
		(start 68.74 84.48)
		(end 69.16 84.9)
		(width 0.125)
		(layer "F.Cu")
		(net 83)
	)
	(segment
		(start 69.3 86.75)
		(end 69.05 87)
		(width 0.125)
		(layer "F.Cu")
		(net 83)
	)
	(segment
		(start 148.825 98.6)
		(end 148.3 98.6)
		(width 0.15)
		(layer "F.Cu")
		(net 83)
	)
	(segment
		(start 67.48 87)
		(end 66.67 86.19)
		(width 0.125)
		(layer "F.Cu")
		(net 83)
	)
	(segment
		(start 66.67 86.19)
		(end 65.91 86.19)
		(width 0.125)
		(layer "F.Cu")
		(net 83)
	)
	(via
		(at 65.91 86.19)
		(size 0.45)
		(drill 0.1)
		(layers "F.Cu" "B.Cu")
		(net 83)
	)
	(via
		(at 148.975 98.75)
		(size 0.45)
		(drill 0.1)
		(layers "F.Cu" "B.Cu")
		(net 83)
	)
	(segment
		(start 71.55 95.392892)
		(end 71.55 104.242892)
		(width 0.125)
		(layer "In5.Cu")
		(net 83)
	)
	(segment
		(start 92 104.5)
		(end 99.4 111.9)
		(width 0.125)
		(layer "In5.Cu")
		(net 83)
	)
	(segment
		(start 145.125 102.175)
		(end 148.55 98.75)
		(width 0.125)
		(layer "In5.Cu")
		(net 83)
	)
	(segment
		(start 123.85 111.9)
		(end 127.9 107.85)
		(width 0.125)
		(layer "In5.Cu")
		(net 83)
	)
	(segment
		(start 65.91 86.19)
		(end 65.9 86.2)
		(width 0.125)
		(layer "In5.Cu")
		(net 83)
	)
	(segment
		(start 99.4 111.9)
		(end 123.85 111.9)
		(width 0.125)
		(layer "In5.Cu")
		(net 83)
	)
	(segment
		(start 65.9 91.35)
		(end 68.54 93.99)
		(width 0.125)
		(layer "In5.Cu")
		(net 83)
	)
	(segment
		(start 140.15 103.225)
		(end 141.2 102.175)
		(width 0.125)
		(layer "In5.Cu")
		(net 83)
	)
	(segment
		(start 136.35 105.6)
		(end 139 105.6)
		(width 0.125)
		(layer "In5.Cu")
		(net 83)
	)
	(segment
		(start 82.9 104.5)
		(end 92 104.5)
		(width 0.125)
		(layer "In5.Cu")
		(net 83)
	)
	(segment
		(start 68.54 93.99)
		(end 70.147107 93.99)
		(width 0.125)
		(layer "In5.Cu")
		(net 83)
	)
	(segment
		(start 72.507108 105.2)
		(end 82.2 105.2)
		(width 0.125)
		(layer "In5.Cu")
		(net 83)
	)
	(segment
		(start 140.15 104.45)
		(end 140.15 103.225)
		(width 0.125)
		(layer "In5.Cu")
		(net 83)
	)
	(segment
		(start 70.147107 93.99)
		(end 71.55 95.392892)
		(width 0.125)
		(layer "In5.Cu")
		(net 83)
	)
	(segment
		(start 71.55 104.242892)
		(end 72.507108 105.2)
		(width 0.125)
		(layer "In5.Cu")
		(net 83)
	)
	(segment
		(start 82.2 105.2)
		(end 82.9 104.5)
		(width 0.125)
		(layer "In5.Cu")
		(net 83)
	)
	(segment
		(start 148.55 98.75)
		(end 148.975 98.75)
		(width 0.125)
		(layer "In5.Cu")
		(net 83)
	)
	(segment
		(start 134.1 107.85)
		(end 136.35 105.6)
		(width 0.125)
		(layer "In5.Cu")
		(net 83)
	)
	(segment
		(start 141.2 102.175)
		(end 145.125 102.175)
		(width 0.125)
		(layer "In5.Cu")
		(net 83)
	)
	(segment
		(start 65.9 86.2)
		(end 65.9 91.35)
		(width 0.125)
		(layer "In5.Cu")
		(net 83)
	)
	(segment
		(start 127.9 107.85)
		(end 134.1 107.85)
		(width 0.125)
		(layer "In5.Cu")
		(net 83)
	)
	(segment
		(start 139 105.6)
		(end 140.15 104.45)
		(width 0.125)
		(layer "In5.Cu")
		(net 83)
	)
	(segment
		(start 67 85.68)
		(end 66.33 85.68)
		(width 0.125)
		(layer "F.Cu")
		(net 84)
	)
	(segment
		(start 148.825 96.675)
		(end 148.45 96.3)
		(width 0.15)
		(layer "F.Cu")
		(net 84)
	)
	(segment
		(start 148.45 96.3)
		(end 148.25 96.3)
		(width 0.15)
		(layer "F.Cu")
		(net 84)
	)
	(segment
		(start 66.366776 85.643224)
		(end 66.366776 85.583224)
		(width 0.125)
		(layer "F.Cu")
		(net 84)
	)
	(segment
		(start 66.33 85.68)
		(end 66.366776 85.643224)
		(width 0.125)
		(layer "F.Cu")
		(net 84)
	)
	(segment
		(start 67.79 86.47)
		(end 67 85.68)
		(width 0.125)
		(layer "F.Cu")
		(net 84)
	)
	(via
		(at 66.33 85.68)
		(size 0.45)
		(drill 0.1)
		(layers "F.Cu" "B.Cu")
		(net 84)
	)
	(via
		(at 148.825 96.675)
		(size 0.45)
		(drill 0.1)
		(layers "F.Cu" "B.Cu")
		(net 84)
	)
	(segment
		(start 127.625 107.525)
		(end 134.025 107.525)
		(width 0.125)
		(layer "In5.Cu")
		(net 84)
	)
	(segment
		(start 136.25 105.3)
		(end 138.725 105.3)
		(width 0.125)
		(layer "In5.Cu")
		(net 84)
	)
	(segment
		(start 71.8 104.139338)
		(end 72.560662 104.9)
		(width 0.125)
		(layer "In5.Cu")
		(net 84)
	)
	(segment
		(start 148.025 98.575)
		(end 148.025 97.475)
		(width 0.125)
		(layer "In5.Cu")
		(net 84)
	)
	(segment
		(start 71.8 95.25)
		(end 71.8 104.139338)
		(width 0.125)
		(layer "In5.Cu")
		(net 84)
	)
	(segment
		(start 140.9 101.85)
		(end 144.75 101.85)
		(width 0.125)
		(layer "In5.Cu")
		(net 84)
	)
	(segment
		(start 72.560662 104.9)
		(end 82.05 104.9)
		(width 0.125)
		(layer "In5.Cu")
		(net 84)
	)
	(segment
		(start 82.75 104.2)
		(end 92.1 104.2)
		(width 0.125)
		(layer "In5.Cu")
		(net 84)
	)
	(segment
		(start 82.05 104.9)
		(end 82.75 104.2)
		(width 0.125)
		(layer "In5.Cu")
		(net 84)
	)
	(segment
		(start 123.55 111.6)
		(end 127.625 107.525)
		(width 0.125)
		(layer "In5.Cu")
		(net 84)
	)
	(segment
		(start 92.1 104.2)
		(end 99.5 111.6)
		(width 0.125)
		(layer "In5.Cu")
		(net 84)
	)
	(segment
		(start 66.2 86.74)
		(end 66.2 91.25)
		(width 0.125)
		(layer "In5.Cu")
		(net 84)
	)
	(segment
		(start 99.5 111.6)
		(end 123.55 111.6)
		(width 0.125)
		(layer "In5.Cu")
		(net 84)
	)
	(segment
		(start 134.025 107.525)
		(end 136.25 105.3)
		(width 0.125)
		(layer "In5.Cu")
		(net 84)
	)
	(segment
		(start 66.33 85.68)
		(end 66.58 85.93)
		(width 0.125)
		(layer "In5.Cu")
		(net 84)
	)
	(segment
		(start 66.58 85.93)
		(end 66.58 86.36)
		(width 0.125)
		(layer "In5.Cu")
		(net 84)
	)
	(segment
		(start 66.58 86.36)
		(end 66.2 86.74)
		(width 0.125)
		(layer "In5.Cu")
		(net 84)
	)
	(segment
		(start 148.025 97.475)
		(end 148.825 96.675)
		(width 0.125)
		(layer "In5.Cu")
		(net 84)
	)
	(segment
		(start 138.725 105.3)
		(end 139.8 104.225)
		(width 0.125)
		(layer "In5.Cu")
		(net 84)
	)
	(segment
		(start 139.8 102.95)
		(end 140.9 101.85)
		(width 0.125)
		(layer "In5.Cu")
		(net 84)
	)
	(segment
		(start 68.65 93.7)
		(end 70.25 93.7)
		(width 0.125)
		(layer "In5.Cu")
		(net 84)
	)
	(segment
		(start 139.8 104.225)
		(end 139.8 102.95)
		(width 0.125)
		(layer "In5.Cu")
		(net 84)
	)
	(segment
		(start 66.2 91.25)
		(end 68.65 93.7)
		(width 0.125)
		(layer "In5.Cu")
		(net 84)
	)
	(segment
		(start 144.75 101.85)
		(end 148.025 98.575)
		(width 0.125)
		(layer "In5.Cu")
		(net 84)
	)
	(segment
		(start 70.25 93.7)
		(end 71.8 95.25)
		(width 0.125)
		(layer "In5.Cu")
		(net 84)
	)
	(segment
		(start 65.597323 70.102677)
		(end 65.597323 72.005136)
		(width 0.15)
		(layer "F.Cu")
		(net 85)
	)
	(segment
		(start 65.3 69.8)
		(end 57.2 69.8)
		(width 0.15)
		(layer "F.Cu")
		(net 85)
	)
	(segment
		(start 65.6 70.1)
		(end 65.3 69.8)
		(width 0.15)
		(layer "F.Cu")
		(net 85)
	)
	(segment
		(start 57.2 69.8)
		(end 55.7245 71.2755)
		(width 0.15)
		(layer "F.Cu")
		(net 85)
	)
	(segment
		(start 55.7245 71.2755)
		(end 55.7245 81.6)
		(width 0.15)
		(layer "F.Cu")
		(net 85)
	)
	(segment
		(start 65.6 70.1)
		(end 65.597323 70.102677)
		(width 0.15)
		(layer "F.Cu")
		(net 85)
	)
	(via
		(at 55.7245 81.6)
		(size 0.45)
		(drill 0.1)
		(layers "F.Cu" "B.Cu")
		(net 85)
	)
	(via
		(at 110.95 70.2245)
		(size 0.45)
		(drill 0.1)
		(layers "F.Cu" "B.Cu")
		(net 85)
	)
	(via
		(at 65.6 70.1)
		(size 0.45)
		(drill 0.1)
		(layers "F.Cu" "B.Cu")
		(net 85)
	)
	(segment
		(start 110.6255 69.9)
		(end 101.5 69.9)
		(width 0.15)
		(layer "In2.Cu")
		(net 85)
	)
	(segment
		(start 77.5 71.25)
		(end 65.9 71.25)
		(width 0.15)
		(layer "In2.Cu")
		(net 85)
	)
	(segment
		(start 65.6 70.95)
		(end 65.6 70.1)
		(width 0.15)
		(layer "In2.Cu")
		(net 85)
	)
	(segment
		(start 100.825 69.225)
		(end 79.525 69.225)
		(width 0.15)
		(layer "In2.Cu")
		(net 85)
	)
	(segment
		(start 79.525 69.225)
		(end 77.5 71.25)
		(width 0.15)
		(layer "In2.Cu")
		(net 85)
	)
	(segment
		(start 101.5 69.9)
		(end 100.825 69.225)
		(width 0.15)
		(layer "In2.Cu")
		(net 85)
	)
	(segment
		(start 110.95 70.2245)
		(end 110.6255 69.9)
		(width 0.15)
		(layer "In2.Cu")
		(net 85)
	)
	(segment
		(start 65.9 71.25)
		(end 65.6 70.95)
		(width 0.15)
		(layer "In2.Cu")
		(net 85)
	)
	(segment
		(start 111.3745 69.8)
		(end 124.9 69.8)
		(width 0.15)
		(layer "B.Cu")
		(net 85)
	)
	(segment
		(start 124.9 69.8)
		(end 125.25 70.15)
		(width 0.15)
		(layer "B.Cu")
		(net 85)
	)
	(segment
		(start 125.25 70.9)
		(end 127.25 72.9)
		(width 0.15)
		(layer "B.Cu")
		(net 85)
	)
	(segment
		(start 110.95 70.2245)
		(end 111.3745 69.8)
		(width 0.15)
		(layer "B.Cu")
		(net 85)
	)
	(segment
		(start 125.25 70.15)
		(end 125.25 70.9)
		(width 0.15)
		(layer "B.Cu")
		(net 85)
	)
	(segment
		(start 55.25 81.451)
		(end 55.399 81.6)
		(width 0.15)
		(layer "B.Cu")
		(net 85)
	)
	(segment
		(start 130.8 71.215)
		(end 131.115 70.9)
		(width 0.15)
		(layer "B.Cu")
		(net 85)
	)
	(segment
		(start 129.55 73.6)
		(end 130.45 73.6)
		(width 0.15)
		(layer "B.Cu")
		(net 85)
	)
	(segment
		(start 130.8 73.25)
		(end 130.8 71.215)
		(width 0.15)
		(layer "B.Cu")
		(net 85)
	)
	(segment
		(start 128.85 72.9)
		(end 129.55 73.6)
		(width 0.15)
		(layer "B.Cu")
		(net 85)
	)
	(segment
		(start 55.399 81.6)
		(end 55.7245 81.6)
		(width 0.15)
		(layer "B.Cu")
		(net 85)
	)
	(segment
		(start 127.25 72.9)
		(end 128.85 72.9)
		(width 0.15)
		(layer "B.Cu")
		(net 85)
	)
	(segment
		(start 130.45 73.6)
		(end 130.8 73.25)
		(width 0.15)
		(layer "B.Cu")
		(net 85)
	)
	(segment
		(start 64.597323 70.522823)
		(end 64.597323 72.005136)
		(width 0.15)
		(layer "F.Cu")
		(net 86)
	)
	(segment
		(start 64.55 70.4755)
		(end 64.597323 70.522823)
		(width 0.15)
		(layer "F.Cu")
		(net 86)
	)
	(segment
		(start 78.17 84.32)
		(end 78.17 85.4)
		(width 0.15)
		(layer "F.Cu")
		(net 86)
	)
	(via
		(at 59.075 86.925)
		(size 0.45)
		(drill 0.1)
		(layers "F.Cu" "B.Cu")
		(net 86)
	)
	(via
		(at 46.41 115.84)
		(size 0.45)
		(drill 0.1)
		(layers "F.Cu" "B.Cu")
		(net 86)
	)
	(via
		(at 46.62 119.86201)
		(size 0.45)
		(drill 0.1)
		(layers "F.Cu" "B.Cu")
		(net 86)
	)
	(via
		(at 72.64 74.24)
		(size 0.45)
		(drill 0.1)
		(layers "F.Cu" "B.Cu")
		(net 86)
	)
	(via
		(at 64.55 70.4755)
		(size 0.45)
		(drill 0.1)
		(layers "F.Cu" "B.Cu")
		(net 86)
	)
	(via
		(at 78.17 84.32)
		(size 0.45)
		(drill 0.1)
		(layers "F.Cu" "B.Cu")
		(net 86)
	)
	(segment
		(start 47.45 116.26)
		(end 47.03 115.84)
		(width 0.15)
		(layer "In3.Cu")
		(net 86)
	)
	(segment
		(start 47.45 116.87)
		(end 47.45 116.26)
		(width 0.15)
		(layer "In3.Cu")
		(net 86)
	)
	(segment
		(start 59.075 86.925)
		(end 59.56 86.44)
		(width 0.15)
		(layer "In3.Cu")
		(net 86)
	)
	(segment
		(start 46.95 119.28)
		(end 46.95 117.37)
		(width 0.15)
		(layer "In3.Cu")
		(net 86)
	)
	(segment
		(start 59.56 86.44)
		(end 59.56 77.615)
		(width 0.15)
		(layer "In3.Cu")
		(net 86)
	)
	(segment
		(start 61.265 75.91)
		(end 64.465 75.91)
		(width 0.15)
		(layer "In3.Cu")
		(net 86)
	)
	(segment
		(start 65.75 74.625)
		(end 65.75 71.6755)
		(width 0.15)
		(layer "In3.Cu")
		(net 86)
	)
	(segment
		(start 46.62 119.86201)
		(end 46.62 119.61)
		(width 0.15)
		(layer "In3.Cu")
		(net 86)
	)
	(segment
		(start 47.03 115.84)
		(end 46.41 115.84)
		(width 0.15)
		(layer "In3.Cu")
		(net 86)
	)
	(segment
		(start 46.62 119.61)
		(end 46.95 119.28)
		(width 0.15)
		(layer "In3.Cu")
		(net 86)
	)
	(segment
		(start 64.465 75.91)
		(end 65.75 74.625)
		(width 0.15)
		(layer "In3.Cu")
		(net 86)
	)
	(segment
		(start 59.56 77.615)
		(end 61.265 75.91)
		(width 0.15)
		(layer "In3.Cu")
		(net 86)
	)
	(segment
		(start 65.75 71.6755)
		(end 64.55 70.4755)
		(width 0.15)
		(layer "In3.Cu")
		(net 86)
	)
	(segment
		(start 46.95 117.37)
		(end 47.45 116.87)
		(width 0.15)
		(layer "In3.Cu")
		(net 86)
	)
	(segment
		(start 64.55 70.4755)
		(end 64.5755 70.4755)
		(width 0.15)
		(layer "In5.Cu")
		(net 86)
	)
	(segment
		(start 57.45 88.275)
		(end 58.8 86.925)
		(width 0.13)
		(layer "In5.Cu")
		(net 86)
	)
	(segment
		(start 58.8 86.925)
		(end 59.075 86.925)
		(width 0.13)
		(layer "In5.Cu")
		(net 86)
	)
	(segment
		(start 47.76 101.01)
		(end 47.35 100.6)
		(width 0.13)
		(layer "In5.Cu")
		(net 86)
	)
	(segment
		(start 47.56 115.84)
		(end 47.57 115.85)
		(width 0.13)
		(layer "In5.Cu")
		(net 86)
	)
	(segment
		(start 57.45 88.886899)
		(end 57.45 88.275)
		(width 0.13)
		(layer "In5.Cu")
		(net 86)
	)
	(segment
		(start 47.57 115.85)
		(end 48.42 115)
		(width 0.13)
		(layer "In5.Cu")
		(net 86)
	)
	(segment
		(start 48.42 113.53)
		(end 47.76 112.87)
		(width 0.13)
		(layer "In5.Cu")
		(net 86)
	)
	(segment
		(start 47.35 98.375)
		(end 54.2625 91.4625)
		(width 0.13)
		(layer "In5.Cu")
		(net 86)
	)
	(segment
		(start 46.41 115.84)
		(end 47.56 115.84)
		(width 0.13)
		(layer "In5.Cu")
		(net 86)
	)
	(segment
		(start 47.76 112.87)
		(end 47.76 101.01)
		(width 0.13)
		(layer "In5.Cu")
		(net 86)
	)
	(segment
		(start 47.35 100.6)
		(end 47.35 98.375)
		(width 0.13)
		(layer "In5.Cu")
		(net 86)
	)
	(segment
		(start 54.874399 91.4625)
		(end 57.45 88.886899)
		(width 0.13)
		(layer "In5.Cu")
		(net 86)
	)
	(segment
		(start 68.34 74.24)
		(end 72.64 74.24)
		(width 0.15)
		(layer "In5.Cu")
		(net 86)
	)
	(segment
		(start 64.5755 70.4755)
		(end 68.34 74.24)
		(width 0.15)
		(layer "In5.Cu")
		(net 86)
	)
	(segment
		(start 48.42 115)
		(end 48.42 113.53)
		(width 0.13)
		(layer "In5.Cu")
		(net 86)
	)
	(segment
		(start 54.2625 91.4625)
		(end 54.874399 91.4625)
		(width 0.13)
		(layer "In5.Cu")
		(net 86)
	)
	(segment
		(start 76.9 79.55)
		(end 78.17 80.82)
		(width 0.15)
		(layer "B.Cu")
		(net 86)
	)
	(segment
		(start 47.325 116.1)
		(end 46.67 116.1)
		(width 0.15)
		(layer "B.Cu")
		(net 86)
	)
	(segment
		(start 58.86 87.89)
		(end 58.65 87.68)
		(width 0.15)
		(layer "B.Cu")
		(net 86)
	)
	(segment
		(start 74.59 76.55)
		(end 75.04 77)
		(width 0.15)
		(layer "B.Cu")
		(net 86)
	)
	(segment
		(start 58.86 88.25)
		(end 58.86 87.89)
		(width 0.15)
		(layer "B.Cu")
		(net 86)
	)
	(segment
		(start 72.44 74.24)
		(end 71.4 73.2)
		(width 0.15)
		(layer "B.Cu")
		(net 86)
	)
	(segment
		(start 45.63 119.925)
		(end 46.55701 119.925)
		(width 0.15)
		(layer "B.Cu")
		(net 86)
	)
	(segment
		(start 59.075 86.925)
		(end 58.75 87.25)
		(width 0.15)
		(layer "B.Cu")
		(net 86)
	)
	(segment
		(start 74.12 75.01)
		(end 74.12 76.55)
		(width 0.15)
		(layer "B.Cu")
		(net 86)
	)
	(segment
		(start 72.64 74.24)
		(end 73.35 74.24)
		(width 0.15)
		(layer "B.Cu")
		(net 86)
	)
	(segment
		(start 64.55 70.4755)
		(end 64.2445 70.17)
		(width 0.125)
		(layer "B.Cu")
		(net 86)
	)
	(segment
		(start 74.12 76.55)
		(end 74.59 76.55)
		(width 0.15)
		(layer "B.Cu")
		(net 86)
	)
	(segment
		(start 75.69 79.55)
		(end 76.9 79.55)
		(width 0.15)
		(layer "B.Cu")
		(net 86)
	)
	(segment
		(start 58.75 87.25)
		(end 58.65 87.25)
		(width 0.15)
		(layer "B.Cu")
		(net 86)
	)
	(segment
		(start 64.2445 70.17)
		(end 63.205 70.17)
		(width 0.125)
		(layer "B.Cu")
		(net 86)
	)
	(segment
		(start 75.04 77)
		(end 75.04 78.9)
		(width 0.15)
		(layer "B.Cu")
		(net 86)
	)
	(segment
		(start 46.67 116.1)
		(end 46.41 115.84)
		(width 0.15)
		(layer "B.Cu")
		(net 86)
	)
	(segment
		(start 58.65 87.68)
		(end 58.65 87.25)
		(width 0.15)
		(layer "B.Cu")
		(net 86)
	)
	(segment
		(start 78.17 80.82)
		(end 78.17 84.32)
		(width 0.15)
		(layer "B.Cu")
		(net 86)
	)
	(segment
		(start 71.4 73.2)
		(end 71.4 71.852)
		(width 0.15)
		(layer "B.Cu")
		(net 86)
	)
	(segment
		(start 73.35 74.24)
		(end 74.12 75.01)
		(width 0.15)
		(layer "B.Cu")
		(net 86)
	)
	(segment
		(start 46.55701 119.925)
		(end 46.62 119.86201)
		(width 0.15)
		(layer "B.Cu")
		(net 86)
	)
	(segment
		(start 72.64 74.24)
		(end 72.44 74.24)
		(width 0.15)
		(layer "B.Cu")
		(net 86)
	)
	(segment
		(start 75.04 78.9)
		(end 75.69 79.55)
		(width 0.15)
		(layer "B.Cu")
		(net 86)
	)
	(segment
		(start 113.85 96.175)
		(end 112.925 96.175)
		(width 0.15)
		(layer "F.Cu")
		(net 87)
	)
	(segment
		(start 127.45 98.6)
		(end 127.95 98.1)
		(width 0.15)
		(layer "F.Cu")
		(net 87)
	)
	(segment
		(start 133.6 119.05)
		(end 133.7 119.15)
		(width 0.2)
		(layer "F.Cu")
		(net 87)
	)
	(segment
		(start 106.6 110.888)
		(end 106.888 110.888)
		(width 0.15)
		(layer "F.Cu")
		(net 87)
	)
	(segment
		(start 94.1 92.05)
		(end 93.435 92.05)
		(width 0.125)
		(layer "F.Cu")
		(net 87)
	)
	(segment
		(start 133.7 119.15)
		(end 133.7 120.615)
		(width 0.2)
		(layer "F.Cu")
		(net 87)
	)
	(segment
		(start 105.2 116.485)
		(end 105.685 116.485)
		(width 0.3)
		(layer "F.Cu")
		(net 87)
	)
	(segment
		(start 106.888 110.888)
		(end 107.11 111.11)
		(width 0.15)
		(layer "F.Cu")
		(net 87)
	)
	(segment
		(start 70.385 109.365)
		(end 70.385 108.7)
		(width 0.3)
		(layer "F.Cu")
		(net 87)
	)
	(segment
		(start 89.235 116.6)
		(end 89.3 116.535)
		(width 0.2)
		(layer "F.Cu")
		(net 87)
	)
	(segment
		(start 87.95 115.85)
		(end 88.7 116.6)
		(width 0.2)
		(layer "F.Cu")
		(net 87)
	)
	(segment
		(start 132.5 112.1)
		(end 133.9 110.7)
		(width 0.15)
		(layer "F.Cu")
		(net 87)
	)
	(segment
		(start 77.65 108.4)
		(end 77.65 108.267469)
		(width 0.2)
		(layer "F.Cu")
		(net 87)
	)
	(segment
		(start 129.3 112.1)
		(end 132.5 112.1)
		(width 0.15)
		(layer "F.Cu")
		(net 87)
	)
	(segment
		(start 87.95 114.85)
		(end 87.95 115.85)
		(width 0.2)
		(layer "F.Cu")
		(net 87)
	)
	(segment
		(start 72.235 103.835)
		(end 71.7 103.835)
		(width 0.2)
		(layer "F.Cu")
		(net 87)
	)
	(segment
		(start 77.65 106.267469)
		(end 78.195531 106.267469)
		(width 0.2)
		(layer "F.Cu")
		(net 87)
	)
	(segment
		(start 71.85 108.267469)
		(end 71.382531 108.267469)
		(width 0.2)
		(layer "F.Cu")
		(net 87)
	)
	(segment
		(start 133.9 110.7)
		(end 133.9 110.1)
		(width 0.15)
		(layer "F.Cu")
		(net 87)
	)
	(segment
		(start 86.05 105.662)
		(end 86.5 106.112)
		(width 0.15)
		(layer "F.Cu")
		(net 87)
	)
	(segment
		(start 112.925 96.175)
		(end 112.75 96.35)
		(width 0.15)
		(layer "F.Cu")
		(net 87)
	)
	(segment
		(start 86.85 99.7)
		(end 86.17 99.7)
		(width 0.15)
		(layer "F.Cu")
		(net 87)
	)
	(segment
		(start 89.85 116.75)
		(end 89.515 116.75)
		(width 0.155)
		(layer "F.Cu")
		(net 87)
	)
	(segment
		(start 70.95 108.7)
		(end 70.385 108.7)
		(width 0.2)
		(layer "F.Cu")
		(net 87)
	)
	(segment
		(start 72.55 104.967469)
		(end 72.55 104.685)
		(width 0.2)
		(layer "F.Cu")
		(net 87)
	)
	(segment
		(start 93.435 92.05)
		(end 93.285 92.2)
		(width 0.125)
		(layer "F.Cu")
		(net 87)
	)
	(segment
		(start 72.55 104.685)
		(end 71.7 103.835)
		(width 0.2)
		(layer "F.Cu")
		(net 87)
	)
	(segment
		(start 78.5 109.25)
		(end 77.65 108.4)
		(width 0.2)
		(layer "F.Cu")
		(net 87)
	)
	(segment
		(start 90.895 116.75)
		(end 89.515 116.75)
		(width 0.2)
		(layer "F.Cu")
		(net 87)
	)
	(segment
		(start 86.17 99.7)
		(end 86.05 99.82)
		(width 0.15)
		(layer "F.Cu")
		(net 87)
	)
	(segment
		(start 133.6 118.3875)
		(end 133.6 119.05)
		(width 0.2)
		(layer "F.Cu")
		(net 87)
	)
	(segment
		(start 105.635 120.75)
		(end 105.635 121.615)
		(width 0.125)
		(layer "F.Cu")
		(net 87)
	)
	(segment
		(start 113.9 90.235)
		(end 114.065 90.4)
		(width 0.15)
		(layer "F.Cu")
		(net 87)
	)
	(segment
		(start 101.835 91.4)
		(end 103.5755 91.4)
		(width 0.15)
		(layer "F.Cu")
		(net 87)
	)
	(segment
		(start 105.685 116.485)
		(end 105.7 116.5)
		(width 0.3)
		(layer "F.Cu")
		(net 87)
	)
	(segment
		(start 70.3232 109.4268)
		(end 70.3232 109.4468)
		(width 0.3)
		(layer "F.Cu")
		(net 87)
	)
	(segment
		(start 128.9 111.7)
		(end 129.3 112.1)
		(width 0.15)
		(layer "F.Cu")
		(net 87)
	)
	(segment
		(start 78.62 109.37)
		(end 78.62 109.855)
		(width 0.2)
		(layer "F.Cu")
		(net 87)
	)
	(segment
		(start 133.7 120.615)
		(end 134.7 120.615)
		(width 0.2)
		(layer "F.Cu")
		(net 87)
	)
	(segment
		(start 105.635 121.615)
		(end 105.55 121.7)
		(width 0.125)
		(layer "F.Cu")
		(net 87)
	)
	(segment
		(start 134.85 111.815)
		(end 134.85 110.6)
		(width 0.125)
		(layer "F.Cu")
		(net 87)
	)
	(segment
		(start 78.213 106.25)
		(end 79.415 106.25)
		(width 0.15)
		(layer "F.Cu")
		(net 87)
	)
	(segment
		(start 103.5755 91.4)
		(end 103.8755 91.1)
		(width 0.15)
		(layer "F.Cu")
		(net 87)
	)
	(segment
		(start 67.2 107.715)
		(end 67.2 107.222917)
		(width 0.15)
		(layer "F.Cu")
		(net 87)
	)
	(segment
		(start 78.2 106.263)
		(end 78.213 106.25)
		(width 0.15)
		(layer "F.Cu")
		(net 87)
	)
	(segment
		(start 112.75 96.35)
		(end 112.75 96.8)
		(width 0.15)
		(layer "F.Cu")
		(net 87)
	)
	(segment
		(start 78.195531 106.267469)
		(end 78.2 106.263)
		(width 0.2)
		(layer "F.Cu")
		(net 87)
	)
	(segment
		(start 90.895 116.75)
		(end 89.85 116.75)
		(width 0.155)
		(layer "F.Cu")
		(net 87)
	)
	(segment
		(start 89.515 116.75)
		(end 89.3 116.535)
		(width 0.2)
		(layer "F.Cu")
		(net 87)
	)
	(segment
		(start 72.25 103.82)
		(end 72.235 103.835)
		(width 0.2)
		(layer "F.Cu")
		(net 87)
	)
	(segment
		(start 128.9 108.385)
		(end 128.9 111.7)
		(width 0.15)
		(layer "F.Cu")
		(net 87)
	)
	(segment
		(start 113.9 89.5)
		(end 113.9 90.235)
		(width 0.15)
		(layer "F.Cu")
		(net 87)
	)
	(segment
		(start 112.75 96.8)
		(end 113.95 98)
		(width 0.15)
		(layer "F.Cu")
		(net 87)
	)
	(segment
		(start 67.2 107.222917)
		(end 67.15 107.172917)
		(width 0.15)
		(layer "F.Cu")
		(net 87)
	)
	(segment
		(start 88.7 116.6)
		(end 89.235 116.6)
		(width 0.2)
		(layer "F.Cu")
		(net 87)
	)
	(segment
		(start 71.382531 108.267469)
		(end 70.95 108.7)
		(width 0.2)
		(layer "F.Cu")
		(net 87)
	)
	(segment
		(start 70.35 109.4)
		(end 70.385 109.365)
		(width 0.3)
		(layer "F.Cu")
		(net 87)
	)
	(segment
		(start 86.05 99.82)
		(end 86.05 105.662)
		(width 0.15)
		(layer "F.Cu")
		(net 87)
	)
	(segment
		(start 127.9 108.385)
		(end 129.9 108.385)
		(width 0.15)
		(layer "F.Cu")
		(net 87)
	)
	(segment
		(start 70.35 109.4)
		(end 70.3232 109.4268)
		(width 0.3)
		(layer "F.Cu")
		(net 87)
	)
	(segment
		(start 78.5 109.25)
		(end 78.62 109.37)
		(width 0.2)
		(layer "F.Cu")
		(net 87)
	)
	(via
		(at 94.8 86)
		(size 0.45)
		(drill 0.1)
		(layers "F.Cu" "B.Cu")
		(free yes)
		(net 87)
	)
	(via
		(at 68.35 89.85)
		(size 0.45)
		(drill 0.1)
		(layers "F.Cu" "B.Cu")
		(net 87)
	)
	(via
		(at 138.5875 97.1625)
		(size 0.45)
		(drill 0.1)
		(layers "F.Cu" "B.Cu")
		(net 87)
	)
	(via
		(at 96.8 114)
		(size 0.45)
		(drill 0.1)
		(layers "F.Cu" "B.Cu")
		(net 87)
	)
	(via
		(at 127.95 98.1)
		(size 0.45)
		(drill 0.1)
		(layers "F.Cu" "B.Cu")
		(net 87)
	)
	(via
		(at 119 103.7)
		(size 0.45)
		(drill 0.1)
		(layers "F.Cu" "B.Cu")
		(free yes)
		(net 87)
	)
	(via
		(at 68.89 88.82)
		(size 0.45)
		(drill 0.1)
		(layers "F.Cu" "B.Cu")
		(net 87)
	)
	(via
		(at 118.498213 87.346684)
		(size 0.45)
		(drill 0.1)
		(layers "F.Cu" "B.Cu")
		(free yes)
		(net 87)
	)
	(via
		(at 68.39 88.83)
		(size 0.45)
		(drill 0.1)
		(layers "F.Cu" "B.Cu")
		(net 87)
	)
	(via
		(at 141.3 126)
		(size 0.45)
		(drill 0.1)
		(layers "F.Cu" "B.Cu")
		(net 87)
	)
	(via
		(at 78.2 106.263)
		(size 0.45)
		(drill 0.1)
		(layers "F.Cu" "B.Cu")
		(net 87)
	)
	(via
		(at 67.15 107.172917)
		(size 0.45)
		(drill 0.1)
		(layers "F.Cu" "B.Cu")
		(net 87)
	)
	(via
		(at 118.877023 87.720854)
		(size 0.45)
		(drill 0.1)
		(layers "F.Cu" "B.Cu")
		(free yes)
		(net 87)
	)
	(via
		(at 67.4125 93.9)
		(size 0.45)
		(drill 0.1)
		(layers "F.Cu" "B.Cu")
		(net 87)
	)
	(via
		(at 68.35 90.35)
		(size 0.45)
		(drill 0.1)
		(layers "F.Cu" "B.Cu")
		(net 87)
	)
	(via
		(at 134.3 109.8)
		(size 0.45)
		(drill 0.1)
		(layers "F.Cu" "B.Cu")
		(free yes)
		(net 87)
	)
	(via
		(at 67.7 90.95)
		(size 0.45)
		(drill 0.1)
		(layers "F.Cu" "B.Cu")
		(net 87)
	)
	(via
		(at 96.8 115.2)
		(size 0.45)
		(drill 0.1)
		(layers "F.Cu" "B.Cu")
		(net 87)
	)
	(via
		(at 68.38 89.36)
		(size 0.45)
		(drill 0.1)
		(layers "F.Cu" "B.Cu")
		(net 87)
	)
	(via
		(at 107.04 87.06)
		(size 0.45)
		(drill 0.1)
		(layers "F.Cu" "B.Cu")
		(net 87)
	)
	(via
		(at 69.45 85.48)
		(size 0.45)
		(drill 0.1)
		(layers "F.Cu" "B.Cu")
		(net 87)
	)
	(via
		(at 70.2 114.3)
		(size 0.45)
		(drill 0.1)
		(layers "F.Cu" "B.Cu")
		(net 87)
	)
	(via
		(at 67.825 90.375)
		(size 0.45)
		(drill 0.1)
		(layers "F.Cu" "B.Cu")
		(net 87)
	)
	(via
		(at 134.3 109.2)
		(size 0.45)
		(drill 0.1)
		(layers "F.Cu" "B.Cu")
		(free yes)
		(net 87)
	)
	(via
		(at 141 122.2)
		(size 0.45)
		(drill 0.1)
		(layers "F.Cu" "B.Cu")
		(net 87)
	)
	(via
		(at 105.55 121.7)
		(size 0.45)
		(drill 0.1)
		(layers "F.Cu" "B.Cu")
		(net 87)
	)
	(via
		(at 96.8 114.6)
		(size 0.45)
		(drill 0.1)
		(layers "F.Cu" "B.Cu")
		(net 87)
	)
	(via
		(at 86.5 106.112)
		(size 0.45)
		(drill 0.1)
		(layers "F.Cu" "B.Cu")
		(net 87)
	)
	(via
		(at 118.4 104)
		(size 0.45)
		(drill 0.1)
		(layers "F.Cu" "B.Cu")
		(free yes)
		(net 87)
	)
	(via
		(at 119.83 103.97)
		(size 0.45)
		(drill 0.1)
		(layers "F.Cu" "B.Cu")
		(free yes)
		(net 87)
	)
	(via
		(at 69.845 126.46)
		(size 0.45)
		(drill 0.1)
		(layers "F.Cu" "B.Cu")
		(net 87)
	)
	(via
		(at 103.8755 91.1)
		(size 0.45)
		(drill 0.1)
		(layers "F.Cu" "B.Cu")
		(free yes)
		(net 87)
	)
	(via
		(at 133.9 109.5)
		(size 0.45)
		(drill 0.1)
		(layers "F.Cu" "B.Cu")
		(free yes)
		(net 87)
	)
	(via
		(at 95.3 85.4285)
		(size 0.45)
		(drill 0.1)
		(layers "F.Cu" "B.Cu")
		(free yes)
		(net 87)
	)
	(via
		(at 133 118.3875)
		(size 0.45)
		(drill 0.1)
		(layers "F.Cu" "B.Cu")
		(free yes)
		(net 87)
	)
	(via
		(at 78.5 109.25)
		(size 0.45)
		(drill 0.1)
		(layers "F.Cu" "B.Cu")
		(net 87)
	)
	(via
		(at 68.87 89.35)
		(size 0.45)
		(drill 0.1)
		(layers "F.Cu" "B.Cu")
		(net 87)
	)
	(via
		(at 106.6 93.8)
		(size 0.45)
		(drill 0.1)
		(layers "F.Cu" "B.Cu")
		(net 87)
	)
	(via
		(at 65.565315 78.983087)
		(size 0.45)
		(drill 0.1)
		(layers "F.Cu" "B.Cu")
		(net 87)
	)
	(via
		(at 106.95 107.6)
		(size 0.45)
		(drill 0.1)
		(layers "F.Cu" "B.Cu")
		(net 87)
	)
	(via
		(at 70.35 109.4)
		(size 0.45)
		(drill 0.1)
		(layers "F.Cu" "B.Cu")
		(net 87)
	)
	(via
		(at 96.3 114)
		(size 0.45)
		(drill 0.1)
		(layers "F.Cu" "B.Cu")
		(net 87)
	)
	(via
		(at 133.9 110.1)
		(size 0.45)
		(drill 0.1)
		(layers "F.Cu" "B.Cu")
		(free yes)
		(net 87)
	)
	(via
		(at 106.6 110.888)
		(size 0.45)
		(drill 0.1)
		(layers "F.Cu" "B.Cu")
		(net 87)
	)
	(via
		(at 134.351293 95.804742)
		(size 0.45)
		(drill 0.1)
		(layers "F.Cu" "B.Cu")
		(net 87)
	)
	(via
		(at 68.85 89.85)
		(size 0.45)
		(drill 0.1)
		(layers "F.Cu" "B.Cu")
		(net 87)
	)
	(via
		(at 95.3 86)
		(size 0.45)
		(drill 0.1)
		(layers "F.Cu" "B.Cu")
		(free yes)
		(net 87)
	)
	(via
		(at 94.8 85.4285)
		(size 0.45)
		(drill 0.1)
		(layers "F.Cu" "B.Cu")
		(free yes)
		(net 87)
	)
	(via
		(at 113.9 89.5)
		(size 0.45)
		(drill 0.1)
		(layers "F.Cu" "B.Cu")
		(net 87)
	)
	(via
		(at 72.25 103.82)
		(size 0.45)
		(drill 0.1)
		(layers "F.Cu" "B.Cu")
		(net 87)
	)
	(via
		(at 96.3 114.6)
		(size 0.45)
		(drill 0.1)
		(layers "F.Cu" "B.Cu")
		(net 87)
	)
	(via
		(at 105.7 116.5)
		(size 0.45)
		(drill 0.1)
		(layers "F.Cu" "B.Cu")
		(net 87)
	)
	(via
		(at 68.85 90.35)
		(size 0.45)
		(drill 0.1)
		(layers "F.Cu" "B.Cu")
		(net 87)
	)
	(via
		(at 113.85 96.175)
		(size 0.45)
		(drill 0.1)
		(layers "F.Cu" "B.Cu")
		(net 87)
	)
	(via
		(at 118.4 103.4)
		(size 0.45)
		(drill 0.1)
		(layers "F.Cu" "B.Cu")
		(free yes)
		(net 87)
	)
	(via
		(at 96.3 115.2)
		(size 0.45)
		(drill 0.1)
		(layers "F.Cu" "B.Cu")
		(net 87)
	)
	(via
		(at 87.95 114.85)
		(size 0.45)
		(drill 0.1)
		(layers "F.Cu" "B.Cu")
		(net 87)
	)
	(via
		(at 119.55 103.45)
		(size 0.45)
		(drill 0.1)
		(layers "F.Cu" "B.Cu")
		(free yes)
		(net 87)
	)
	(via
		(at 118.15 86.95)
		(size 0.45)
		(drill 0.1)
		(layers "F.Cu" "B.Cu")
		(free yes)
		(net 87)
	)
	(via
		(at 110.8 84.7)
		(size 0.45)
		(drill 0.1)
		(layers "F.Cu" "B.Cu")
		(net 87)
	)
	(via
		(at 133.6 118.3875)
		(size 0.45)
		(drill 0.1)
		(layers "F.Cu" "B.Cu")
		(free yes)
		(net 87)
	)
	(via
		(at 94.1 92.05)
		(size 0.45)
		(drill 0.1)
		(layers "F.Cu" "B.Cu")
		(net 87)
	)
	(via
		(at 111.3 108.05)
		(size 0.45)
		(drill 0.1)
		(layers "F.Cu" "B.Cu")
		(net 87)
	)
	(via
		(at 132.4 118.3875)
		(size 0.45)
		(drill 0.1)
		(layers "F.Cu" "B.Cu")
		(free yes)
		(net 87)
	)
	(via
		(at 87 108.8695)
		(size 0.45)
		(drill 0.1)
		(layers "F.Cu" "B.Cu")
		(net 87)
	)
	(segment
		(start 113.9 89.5)
		(end 113.9 88.75)
		(width 0.15)
		(layer "In1.Cu")
		(net 87)
	)
	(segment
		(start 126.75 100.05)
		(end 118.55 100.05)
		(width 0.3)
		(layer "In1.Cu")
		(net 87)
	)
	(segment
		(start 94.25 86)
		(end 94.8 86)
		(width 0.125)
		(layer "In1.Cu")
		(net 87)
	)
	(segment
		(start 68.15 126.46)
		(end 68.15 117.725)
		(width 0.3)
		(layer "In1.Cu")
		(net 87)
	)
	(segment
		(start 108.975 96.175)
		(end 113.85 96.175)
		(width 0.15)
		(layer "In1.Cu")
		(net 87)
	)
	(segment
		(start 43.7 128)
		(end 43.2 128)
		(width 0.3)
		(layer "In1.Cu")
		(net 87)
	)
	(segment
		(start 68.15 127.04)
		(end 68.15 126.46)
		(width 0.3)
		(layer "In1.Cu")
		(net 87)
	)
	(segment
		(start 43.6 128)
		(end 43.3 127.7)
		(width 0.3)
		(layer "In1.Cu")
		(net 87)
	)
	(segment
		(start 43.7 128)
		(end 67.19 128)
		(width 0.3)
		(layer "In1.Cu")
		(net 87)
	)
	(segment
		(start 141 122.2)
		(end 139.9 121.1)
		(width 0.3)
		(layer "In1.Cu")
		(net 87)
	)
	(segment
		(start 32.509998 121.576396)
		(end 32.509998 127.409998)
		(width 0.3)
		(layer "In1.Cu")
		(net 87)
	)
	(segment
		(start 69.845 126.46)
		(end 68.15 126.46)
		(width 0.15)
		(layer "In1.Cu")
		(net 87)
	)
	(segment
		(start 67.19 128)
		(end 68.15 127.04)
		(width 0.3)
		(layer "In1.Cu")
		(net 87)
	)
	(segment
		(start 127.95 98.85)
		(end 126.75 100.05)
		(width 0.3)
		(layer "In1.Cu")
		(net 87)
	)
	(segment
		(start 32.509998 127.409998)
		(end 33.1 128)
		(width 0.3)
		(layer "In1.Cu")
		(net 87)
	)
	(segment
		(start 105.55 121.7)
		(end 105 121.15)
		(width 0.3)
		(layer "In1.Cu")
		(net 87)
	)
	(segment
		(start 43.7 128)
		(end 43.6 128)
		(width 0.3)
		(layer "In1.Cu")
		(net 87)
	)
	(segment
		(start 43.3 127.7)
		(end 43 128)
		(width 0.3)
		(layer "In1.Cu")
		(net 87)
	)
	(segment
		(start 43.3 121.626394)
		(end 43.3 127.7)
		(width 0.3)
		(layer "In1.Cu")
		(net 87)
	)
	(segment
		(start 105 117.2)
		(end 105.7 116.5)
		(width 0.3)
		(layer "In1.Cu")
		(net 87)
	)
	(segment
		(start 94.1 92.05)
		(end 94.1 86.15)
		(width 0.125)
		(layer "In1.Cu")
		(net 87)
	)
	(segment
		(start 110.8 84.7)
		(end 110.25 85.25)
		(width 0.15)
		(layer "In1.Cu")
		(net 87)
	)
	(segment
		(start 43.2 128)
		(end 43 128)
		(width 0.3)
		(layer "In1.Cu")
		(net 87)
	)
	(segment
		(start 43.3 127.9)
		(end 43.2 128)
		(width 0.3)
		(layer "In1.Cu")
		(net 87)
	)
	(segment
		(start 68.15 117.725)
		(end 70.2 115.675)
		(width 0.3)
		(layer "In1.Cu")
		(net 87)
	)
	(segment
		(start 43.3 127.7)
		(end 43.3 127.9)
		(width 0.3)
		(layer "In1.Cu")
		(net 87)
	)
	(segment
		(start 106.6 93.8)
		(end 108.975 96.175)
		(width 0.15)
		(layer "In1.Cu")
		(net 87)
	)
	(segment
		(start 70.2 115.675)
		(end 70.2 114.3)
		(width 0.3)
		(layer "In1.Cu")
		(net 87)
	)
	(segment
		(start 94.1 86.15)
		(end 94.25 86)
		(width 0.125)
		(layer "In1.Cu")
		(net 87)
	)
	(segment
		(start 33.1 128)
		(end 43 128)
		(width 0.3)
		(layer "In1.Cu")
		(net 87)
	)
	(segment
		(start 139.9 121.1)
		(end 133.4 121.1)
		(width 0.3)
		(layer "In1.Cu")
		(net 87)
	)
	(segment
		(start 105 121.15)
		(end 105 117.2)
		(width 0.3)
		(layer "In1.Cu")
		(net 87)
	)
	(segment
		(start 127.95 98.1)
		(end 127.95 98.85)
		(width 0.3)
		(layer "In1.Cu")
		(net 87)
	)
	(segment
		(start 69.45 85.48)
		(end 69.38 85.55)
		(width 0.15)
		(layer "In2.Cu")
		(net 87)
	)
	(segment
		(start 67.4 85.7)
		(end 67.55 85.55)
		(width 0.15)
		(layer "In2.Cu")
		(net 87)
	)
	(segment
		(start 68.675 88.775)
		(end 67.4 87.5)
		(width 0.15)
		(layer "In2.Cu")
		(net 87)
	)
	(segment
		(start 67.55 85.55)
		(end 67.4 85.4)
		(width 0.15)
		(layer "In2.Cu")
		(net 87)
	)
	(segment
		(start 68.675 89.275)
		(end 68.65 89.3)
		(width 0.15)
		(layer "In2.Cu")
		(net 87)
	)
	(segment
		(start 67.4 80.1)
		(end 67.4 85.4)
		(width 0.15)
		(layer "In2.Cu")
		(net 87)
	)
	(segment
		(start 68.675 88.775)
		(end 68.675 89.275)
		(width 0.15)
		(layer "In2.Cu")
		(net 87)
	)
	(segment
		(start 86.5 106.7)
		(end 87.1 106.7)
		(width 0.155)
		(layer "In2.Cu")
		(net 87)
	)
	(segment
		(start 66.283087 78.983087)
		(end 67.4 80.1)
		(width 0.15)
		(layer "In2.Cu")
		(net 87)
	)
	(segment
		(start 67.4 85.4)
		(end 67.4 85.7)
		(width 0.15)
		(layer "In2.Cu")
		(net 87)
	)
	(segment
		(start 67.4 87.5)
		(end 67.4 85.7)
		(width 0.15)
		(layer "In2.Cu")
		(net 87)
	)
	(segment
		(start 86.5 106.112)
		(end 86.5 106.7)
		(width 0.155)
		(layer "In2.Cu")
		(net 87)
	)
	(segment
		(start 65.565315 78.983087)
		(end 66.283087 78.983087)
		(width 0.15)
		(layer "In2.Cu")
		(net 87)
	)
	(segment
		(start 69.38 85.55)
		(end 67.55 85.55)
		(width 0.15)
		(layer "In2.Cu")
		(net 87)
	)
	(segment
		(start 138.5875 97.0875)
		(end 138.5875 97.1625)
		(width 0.3)
		(layer "In3.Cu")
		(net 87)
	)
	(segment
		(start 134.871551 96.325)
		(end 137.825 96.325)
		(width 0.3)
		(layer "In3.Cu")
		(net 87)
	)
	(segment
		(start 137.825 96.325)
		(end 138.5875 97.0875)
		(width 0.3)
		(layer "In3.Cu")
		(net 87)
	)
	(segment
		(start 134.351293 95.804742)
		(end 134.871551 96.325)
		(width 0.3)
		(layer "In3.Cu")
		(net 87)
	)
	(segment
		(start 105.15 92)
		(end 105.2 92)
		(width 0.15)
		(layer "In5.Cu")
		(net 87)
	)
	(segment
		(start 141.3 126)
		(end 141 125.7)
		(width 0.3)
		(layer "In5.Cu")
		(net 87)
	)
	(segment
		(start 105.15 91.8)
		(end 105.2 91.8)
		(width 0.15)
		(layer "In5.Cu")
		(net 87)
	)
	(segment
		(start 107.4 108.05)
		(end 106.95 107.6)
		(width 0.125)
		(layer "In5.Cu")
		(net 87)
	)
	(segment
		(start 106.6 93.8)
		(end 105.2 92.4)
		(width 0.15)
		(layer "In5.Cu")
		(net 87)
	)
	(segment
		(start 105.2 91.9)
		(end 105.05 91.9)
		(width 0.15)
		(layer "In5.Cu")
		(net 87)
	)
	(segment
		(start 103.8755 91.1)
		(end 104.6755 91.9)
		(width 0.15)
		(layer "In5.Cu")
		(net 87)
	)
	(segment
		(start 106.1 89)
		(end 106.7 88.4)
		(width 0.15)
		(layer "In5.Cu")
		(net 87)
	)
	(segment
		(start 141 125.7)
		(end 141 122.2)
		(width 0.3)
		(layer "In5.Cu")
		(net 87)
	)
	(segment
		(start 104.6755 91.9)
		(end 105.05 91.9)
		(width 0.15)
		(layer "In5.Cu")
		(net 87)
	)
	(segment
		(start 105.05 91.9)
		(end 105.15 91.8)
		(width 0.15)
		(layer "In5.Cu")
		(net 87)
	)
	(segment
		(start 105.2 91.9)
		(end 105.2 91.8)
		(width 0.15)
		(layer "In5.Cu")
		(net 87)
	)
	(segment
		(start 105.2 92)
		(end 105.2 91.9)
		(width 0.15)
		(layer "In5.Cu")
		(net 87)
	)
	(segment
		(start 105.05 91.9)
		(end 105.15 92)
		(width 0.15)
		(layer "In5.Cu")
		(net 87)
	)
	(segment
		(start 106.7 88.4)
		(end 106.7 87.4)
		(width 0.15)
		(layer "In5.Cu")
		(net 87)
	)
	(segment
		(start 105.2 90.7)
		(end 106.1 89.8)
		(width 0.15)
		(layer "In5.Cu")
		(net 87)
	)
	(segment
		(start 105.2 92.4)
		(end 105.2 92)
		(width 0.15)
		(layer "In5.Cu")
		(net 87)
	)
	(segment
		(start 111.3 108.05)
		(end 107.4 108.05)
		(width 0.125)
		(layer "In5.Cu")
		(net 87)
	)
	(segment
		(start 106.7 87.4)
		(end 107.04 87.06)
		(width 0.15)
		(layer "In5.Cu")
		(net 87)
	)
	(segment
		(start 106.1 89.8)
		(end 106.1 89)
		(width 0.15)
		(layer "In5.Cu")
		(net 87)
	)
	(segment
		(start 105.2 91.8)
		(end 105.2 90.7)
		(width 0.15)
		(layer "In5.Cu")
		(net 87)
	)
	(segment
		(start 91.865 116.585)
		(end 92.35 116.1)
		(width 0.155)
		(layer "B.Cu")
		(net 87)
	)
	(segment
		(start 86.5 106.112)
		(end 86.503 106.115)
		(width 0.2)
		(layer "B.Cu")
		(net 87)
	)
	(segment
		(start 87.3 105.515)
		(end 87.715 105.1)
		(width 0.15)
		(layer "B.Cu")
		(net 87)
	)
	(segment
		(start 69.4 85.53)
		(end 69.4 85.815)
		(width 0.155)
		(layer "B.Cu")
		(net 87)
	)
	(segment
		(start 78.2 106.6)
		(end 78.2 106.263)
		(width 0.155)
		(layer "B.Cu")
		(net 87)
	)
	(segment
		(start 67.05 79.695)
		(end 67.05 78.855)
		(width 0.3)
		(layer "B.Cu")
		(net 87)
	)
	(segment
		(start 134.2 109.8)
		(end 133.9 109.5)
		(width 0.3)
		(layer "B.Cu")
		(net 87)
	)
	(segment
		(start 92.6 85.765)
		(end 93 85.365)
		(width 0.2)
		(layer "B.Cu")
		(net 87)
	)
	(segment
		(start 68.84 123.07)
		(end 68.165 123.07)
		(width 0.15)
		(layer "B.Cu")
		(net 87)
	)
	(segment
		(start 61.16 97.15)
		(end 61.16 97.68)
		(width 0.125)
		(layer "B.Cu")
		(net 87)
	)
	(segment
		(start 109.315 105.4)
		(end 109.315 105.665)
		(width 0.125)
		(layer "B.Cu")
		(net 87)
	)
	(segment
		(start 88.7 107.085)
		(end 88.27 107.085)
		(width 0.15)
		(layer "B.Cu")
		(net 87)
	)
	(segment
		(start 134.3 109.2)
		(end 134.2 109.2)
		(width 0.3)
		(layer "B.Cu")
		(net 87)
	)
	(segment
		(start 112.022 84.7)
		(end 110.8 84.7)
		(width 0.15)
		(layer "B.Cu")
		(net 87)
	)
	(segment
		(start 106.9 115.3245)
		(end 106.8755 115.3245)
		(width 0.3)
		(layer "B.Cu")
		(net 87)
	)
	(segment
		(start 140.49 126.6)
		(end 140.49 125.99)
		(width 0.3)
		(layer "B.Cu")
		(net 87)
	)
	(segment
		(start 67.2 107.222917)
		(end 67.2 107.715)
		(width 0.15)
		(layer "B.Cu")
		(net 87)
	)
	(segment
		(start 69.45 85.48)
		(end 69.4 85.53)
		(width 0.155)
		(layer "B.Cu")
		(net 87)
	)
	(segment
		(start 140.49 125.99)
		(end 140.58 125.9)
		(width 0.3)
		(layer "B.Cu")
		(net 87)
	)
	(segment
		(start 91.3 116.585)
		(end 91.865 116.585)
		(width 0.155)
		(layer "B.Cu")
		(net 87)
	)
	(segment
		(start 65.716913 78.983087)
		(end 66 78.7)
		(width 0.155)
		(layer "B.Cu")
		(net 87)
	)
	(segment
		(start 69.525 123.755)
		(end 68.84 123.07)
		(width 0.15)
		(layer "B.Cu")
		(net 87)
	)
	(segment
		(start 139.25 98.5075)
		(end 139.25 97.8)
		(width 0.3)
		(layer "B.Cu")
		(net 87)
	)
	(segment
		(start 114.4 81.2)
		(end 114.115 80.915)
		(width 0.3)
		(layer "B.Cu")
		(net 87)
	)
	(segment
		(start 132.7508 115.1008)
		(end 132.95 115.3)
		(width 0.2)
		(layer "B.Cu")
		(net 87)
	)
	(segment
		(start 134.3 109.7)
		(end 134.3 109.8)
		(width 0.3)
		(layer "B.Cu")
		(net 87)
	)
	(segment
		(start 95.325 111.05)
		(end 95.725 111.45)
		(width 0.15)
		(layer "B.Cu")
		(net 87)
	)
	(segment
		(start 106.9 110.588)
		(end 106.9 109.2)
		(width 0.3)
		(layer "B.Cu")
		(net 87)
	)
	(segment
		(start 60.17 97.15)
		(end 60.17 97.185)
		(width 0.13)
		(layer "B.Cu")
		(net 87)
	)
	(segment
		(start 107.15175 94.39825)
		(end 107.15175 95.04)
		(width 0.15)
		(layer "B.Cu")
		(net 87)
	)
	(segment
		(start 139.25 97.8)
		(end 139.135 97.685)
		(width 0.3)
		(layer "B.Cu")
		(net 87)
	)
	(segment
		(start 106.6 93.8)
		(end 106.6 93.8465)
		(width 0.15)
		(layer "B.Cu")
		(net 87)
	)
	(segment
		(start 140.58 125.9)
		(end 140.58 125.472)
		(width 0.3)
		(layer "B.Cu")
		(net 87)
	)
	(segment
		(start 69.6 93.915)
		(end 67.405 93.915)
		(width 0.13)
		(layer "B.Cu")
		(net 87)
	)
	(segment
		(start 74.05 103.01)
		(end 74.05 102.915)
		(width 0.2)
		(layer "B.Cu")
		(net 87)
	)
	(segment
		(start 110.7 108.05)
		(end 111.3 108.05)
		(width 0.125)
		(layer "B.Cu")
		(net 87)
	)
	(segment
		(start 78.435012 106.835012)
		(end 78.2 106.6)
		(width 0.155)
		(layer "B.Cu")
		(net 87)
	)
	(segment
		(start 112.939 83.783)
		(end 112.022 84.7)
		(width 0.15)
		(layer "B.Cu")
		(net 87)
	)
	(segment
		(start 67.15 107.172917)
		(end 67.3 107.022917)
		(width 0.155)
		(layer "B.Cu")
		(net 87)
	)
	(segment
		(start 88.1 109.25)
		(end 87.5 109.25)
		(width 0.155)
		(layer "B.Cu")
		(net 87)
	)
	(segment
		(start 72.25 103.82)
		(end 72.235 103.835)
		(width 0.2)
		(layer "B.Cu")
		(net 87)
	)
	(segment
		(start 133.9 109.6)
		(end 134.3 109.2)
		(width 0.3)
		(layer "B.Cu")
		(net 87)
	)
	(segment
		(start 134.3 109.8)
		(end 134.2 109.8)
		(width 0.3)
		(layer "B.Cu")
		(net 87)
	)
	(segment
		(start 65.04 95.43)
		(end 64.61 95.86)
		(width 0.13)
		(layer "B.Cu")
		(net 87)
	)
	(segment
		(start 106.6 93.8465)
		(end 107.15175 94.39825)
		(width 0.15)
		(layer "B.Cu")
		(net 87)
	)
	(segment
		(start 141 122.2)
		(end 141.185 122.385)
		(width 0.3)
		(layer "B.Cu")
		(net 87)
	)
	(segment
		(start 134.2 109.2)
		(end 133.9 109.5)
		(width 0.3)
		(layer "B.Cu")
		(net 87)
	)
	(segment
		(start 93 87.35)
		(end 92.6 86.95)
		(width 0.2)
		(layer "B.Cu")
		(net 87)
	)
	(segment
		(start 69.165 86.05)
		(end 68.395 86.05)
		(width 0.155)
		(layer "B.Cu")
		(net 87)
	)
	(segment
		(start 134.351293 95.998707)
		(end 132.45 97.9)
		(width 0.3)
		(layer "B.Cu")
		(net 87)
	)
	(segment
		(start 79.985 107.405)
		(end 79.415012 106.835012)
		(width 0.155)
		(layer "B.Cu")
		(net 87)
	)
	(segment
		(start 62.78 96.86)
		(end 62.49 97.15)
		(width 0.13)
		(layer "B.Cu")
		(net 87)
	)
	(segment
		(start 69.525 126.14)
		(end 69.525 123.755)
		(width 0.15)
		(layer "B.Cu")
		(net 87)
	)
	(segment
		(start 64.61 95.86)
		(end 63.15 95.86)
		(width 0.13)
		(layer "B.Cu")
		(net 87)
	)
	(segment
		(start 132.45 97.9)
		(end 132.45 101.75)
		(width 0.3)
		(layer "B.Cu")
		(net 87)
	)
	(segment
		(start 67.15 107.172917)
		(end 67.2 107.222917)
		(width 0.15)
		(layer "B.Cu")
		(net 87)
	)
	(segment
		(start 86.503 106.115)
		(end 87.3 106.115)
		(width 0.2)
		(layer "B.Cu")
		(net 87)
	)
	(segment
		(start 78.5 109.9)
		(end 77.715 110.685)
		(width 0.125)
		(layer "B.Cu")
		(net 87)
	)
	(segment
		(start 132.45 101.75)
		(end 134.3 103.6)
		(width 0.3)
		(layer "B.Cu")
		(net 87)
	)
	(segment
		(start 106.4 88.355)
		(end 106.845 88.355)
		(width 0.3)
		(layer "B.Cu")
		(net 87)
	)
	(segment
		(start 92.35 116.1)
		(end 92.35 115.685)
		(width 0.155)
		(layer "B.Cu")
		(net 87)
	)
	(segment
		(start 87.95 114.85)
		(end 87.95 116.25)
		(width 0.155)
		(layer "B.Cu")
		(net 87)
	)
	(segment
		(start 62.49 97.15)
		(end 60.17 97.15)
		(width 0.13)
		(layer "B.Cu")
		(net 87)
	)
	(segment
		(start 112.155 88.505)
		(end 111.6 88.505)
		(width 0.15)
		(layer "B.Cu")
		(net 87)
	)
	(segment
		(start 72.25 103.82)
		(end 73.24 103.82)
		(width 0.2)
		(layer "B.Cu")
		(net 87)
	)
	(segment
		(start 113.767 82.333)
		(end 114.4 81.7)
		(width 0.3)
		(layer "B.Cu")
		(net 87)
	)
	(segment
		(start 76 102.915)
		(end 74.05 102.915)
		(width 0.155)
		(layer "B.Cu")
		(net 87)
	)
	(segment
		(start 87.95 116.25)
		(end 88.285 116.585)
		(width 0.155)
		(layer "B.Cu")
		(net 87)
	)
	(segment
		(start 134.351293 95.804742)
		(end 134.351293 95.998707)
		(width 0.3)
		(layer "B.Cu")
		(net 87)
	)
	(segment
		(start 106.8755 115.3245)
		(end 105.7 116.5)
		(width 0.3)
		(layer "B.Cu")
		(net 87)
	)
	(segment
		(start 96.8 111.985)
		(end 96.2 111.385)
		(width 0.155)
		(layer "B.Cu")
		(net 87)
	)
	(segment
		(start 107.15 88.05)
		(end 107.18 88.02)
		(width 0.3)
		(layer "B.Cu")
		(net 87)
	)
	(segment
		(start 133.9 110.1)
		(end 133.9 109.6)
		(width 0.3)
		(layer "B.Cu")
		(net 87)
	)
	(segment
		(start 96.45 87.15)
		(end 95.3 86)
		(width 0.15)
		(layer "B.Cu")
		(net 87)
	)
	(segment
		(start 133.9 110.1)
		(end 133.9 109.5)
		(width 0.3)
		(layer "B.Cu")
		(net 87)
	)
	(segment
		(start 85.844053 106.767947)
		(end 86.5 106.112)
		(width 0.15)
		(layer "B.Cu")
		(net 87)
	)
	(segment
		(start 105.515 93.02)
		(end 106.295 93.8)
		(width 0.15)
		(layer "B.Cu")
		(net 87)
	)
	(segment
		(start 133.9 110.1)
		(end 134.3 109.7)
		(width 0.3)
		(layer "B.Cu")
		(net 87)
	)
	(segment
		(start 112.939 82.333)
		(end 113.767 82.333)
		(width 0.3)
		(layer "B.Cu")
		(net 87)
	)
	(segment
		(start 67.405 93.915)
		(end 66.86 94.46)
		(width 0.13)
		(layer "B.Cu")
		(net 87)
	)
	(segment
		(start 78.5 109.25)
		(end 78.5 109.9)
		(width 0.125)
		(layer "B.Cu")
		(net 87)
	)
	(segment
		(start 73.24 103.82)
		(end 74.05 103.01)
		(width 0.2)
		(layer "B.Cu")
		(net 87)
	)
	(segment
		(start 109.315 105.665)
		(end 110.5 106.85)
		(width 0.125)
		(layer "B.Cu")
		(net 87)
	)
	(segment
		(start 107.04 87.06)
		(end 107.04 87.94)
		(width 0.3)
		(layer "B.Cu")
		(net 87)
	)
	(segment
		(start 69.845 126.46)
		(end 69.525 126.14)
		(width 0.15)
		(layer "B.Cu")
		(net 87)
	)
	(segment
		(start 66.86 95.14)
		(end 66.57 95.43)
		(width 0.13)
		(layer "B.Cu")
		(net 87)
	)
	(segment
		(start 66.86 94.46)
		(end 66.86 95.14)
		(width 0.13)
		(layer "B.Cu")
		(net 87)
	)
	(segment
		(start 66.57 95.43)
		(end 65.04 95.43)
		(width 0.13)
		(layer "B.Cu")
		(net 87)
	)
	(segment
		(start 66 78.7)
		(end 67.185 78.7)
		(width 0.155)
		(layer "B.Cu")
		(net 87)
	)
	(segment
		(start 106.295 93.8)
		(end 106.6 93.8)
		(width 0.15)
		(layer "B.Cu")
		(net 87)
	)
	(segment
		(start 108.415 104.4)
		(end 108.415 104.415)
		(width 0.125)
		(layer "B.Cu")
		(net 87)
	)
	(segment
		(start 93.0075 87.95)
		(end 93 87.9425)
		(width 0.2)
		(layer "B.Cu")
		(net 87)
	)
	(segment
		(start 134.3 103.6)
		(end 134.3 109.2)
		(width 0.3)
		(layer "B.Cu")
		(net 87)
	)
	(segment
		(start 106.9 107.65)
		(end 106.95 107.6)
		(width 0.3)
		(layer "B.Cu")
		(net 87)
	)
	(segment
		(start 106.845 88.355)
		(end 107.15 88.05)
		(width 0.3)
		(layer "B.Cu")
		(net 87)
	)
	(segment
		(start 113.15 89.5)
		(end 112.155 88.505)
		(width 0.15)
		(layer "B.Cu")
		(net 87)
	)
	(segment
		(start 108.415 104.415)
		(end 109.315 105.315)
		(width 0.125)
		(layer "B.Cu")
		(net 87)
	)
	(segment
		(start 114.4 81.7)
		(end 114.4 81.2)
		(width 0.3)
		(layer "B.Cu")
		(net 87)
	)
	(segment
		(start 138.5875 97.1625)
		(end 138.965 97.54)
		(width 0.3)
		(layer "B.Cu")
		(net 87)
	)
	(segment
		(start 67.3 107.022917)
		(end 67.3 106.45)
		(width 0.155)
		(layer "B.Cu")
		(net 87)
	)
	(segment
		(start 87 108.8695)
		(end 87 109.815)
		(width 0.155)
		(layer "B.Cu")
		(net 87)
	)
	(segment
		(start 77.715 110.685)
		(end 75 110.685)
		(width 0.125)
		(layer "B.Cu")
		(net 87)
	)
	(segment
		(start 106.9 109.2)
		(end 106.9 111.2)
		(width 0.3)
		(layer "B.Cu")
		(net 87)
	)
	(segment
		(start 88.285 116.585)
		(end 91.3 116.585)
		(width 0.155)
		(layer "B.Cu")
		(net 87)
	)
	(segment
		(start 138.965 97.54)
		(end 139.135 97.54)
		(width 0.3)
		(layer "B.Cu")
		(net 87)
	)
	(segment
		(start 96.8 114)
		(end 96.8 111.985)
		(width 0.155)
		(layer "B.Cu")
		(net 87)
	)
	(segment
		(start 65.565315 78.983087)
		(end 65.716913 78.983087)
		(width 0.155)
		(layer "B.Cu")
		(net 87)
	)
	(segment
		(start 140.49 126.6)
		(end 141.02 126.6)
		(width 0.3)
		(layer "B.Cu")
		(net 87)
	)
	(segment
		(start 106.9 110.588)
		(end 106.6 110.888)
		(width 0.3)
		(layer "B.Cu")
		(net 87)
	)
	(segment
		(start 141.3 126.32)
		(end 141.3 126)
		(width 0.3)
		(layer "B.Cu")
		(net 87)
	)
	(segment
		(start 106.9 111.2)
		(end 106.9 115.3245)
		(width 0.3)
		(layer "B.Cu")
		(net 87)
	)
	(segment
		(start 69.4 85.815)
		(end 69.165 86.05)
		(width 0.155)
		(layer "B.Cu")
		(net 87)
	)
	(segment
		(start 95.725 111.45)
		(end 96.135 111.45)
		(width 0.15)
		(layer "B.Cu")
		(net 87)
	)
	(segment
		(start 113.9 89.5)
		(end 113.15 89.5)
		(width 0.15)
		(layer "B.Cu")
		(net 87)
	)
	(segment
		(start 95.325 103.575)
		(end 95.325 111.05)
		(width 0.15)
		(layer "B.Cu")
		(net 87)
	)
	(segment
		(start 141.185 122.385)
		(end 141.185 123)
		(width 0.3)
		(layer "B.Cu")
		(net 87)
	)
	(segment
		(start 109.315 105.315)
		(end 109.315 105.4)
		(width 0.125)
		(layer "B.Cu")
		(net 87)
	)
	(segment
		(start 79.415012 106.835012)
		(end 78.435012 106.835012)
		(width 0.155)
		(layer "B.Cu")
		(net 87)
	)
	(segment
		(start 92.9 98.985)
		(end 92.9 101.15)
		(width 0.15)
		(layer "B.Cu")
		(net 87)
	)
	(segment
		(start 141.02 126.6)
		(end 141.3 126.32)
		(width 0.3)
		(layer "B.Cu")
		(net 87)
	)
	(segment
		(start 87.5 109.25)
		(end 87 109.75)
		(width 0.155)
		(layer "B.Cu")
		(net 87)
	)
	(segment
		(start 88.27 107.085)
		(end 87.3 106.115)
		(width 0.15)
		(layer "B.Cu")
		(net 87)
	)
	(segment
		(start 87.3 106.115)
		(end 87.3 105.515)
		(width 0.15)
		(layer "B.Cu")
		(net 87)
	)
	(segment
		(start 110.5 107.85)
		(end 110.7 108.05)
		(width 0.125)
		(layer "B.Cu")
		(net 87)
	)
	(segment
		(start 93 87.9425)
		(end 93 87.35)
		(width 0.2)
		(layer "B.Cu")
		(net 87)
	)
	(segment
		(start 106.9 109.2)
		(end 106.9 107.65)
		(width 0.3)
		(layer "B.Cu")
		(net 87)
	)
	(segment
		(start 67.185 78.7)
		(end 67.195 78.71)
		(width 0.155)
		(layer "B.Cu")
		(net 87)
	)
	(segment
		(start 106.9 111.188)
		(end 106.6 110.888)
		(width 0.3)
		(layer "B.Cu")
		(net 87)
	)
	(segment
		(start 107.18 88.02)
		(end 107.8 88.02)
		(width 0.3)
		(layer "B.Cu")
		(net 87)
	)
	(segment
		(start 134.3 109.8)
		(end 134.3 109.2)
		(width 0.3)
		(layer "B.Cu")
		(net 87)
	)
	(segment
		(start 88.1 109.75)
		(end 87.065 109.75)
		(width 0.155)
		(layer "B.Cu")
		(net 87)
	)
	(segment
		(start 87 109.75)
		(end 87 109.815)
		(width 0.155)
		(layer "B.Cu")
		(net 87)
	)
	(segment
		(start 96.135 111.45)
		(end 96.2 111.385)
		(width 0.15)
		(layer "B.Cu")
		(net 87)
	)
	(segment
		(start 112.939 83.783)
		(end 112.939 82.333)
		(width 0.3)
		(layer "B.Cu")
		(net 87)
	)
	(segment
		(start 106.9 111.2)
		(end 106.9 111.188)
		(width 0.3)
		(layer "B.Cu")
		(net 87)
	)
	(segment
		(start 87.065 109.75)
		(end 87 109.815)
		(width 0.155)
		(layer "B.Cu")
		(net 87)
	)
	(segment
		(start 79.985 108.4)
		(end 79.985 107.405)
		(width 0.155)
		(layer "B.Cu")
		(net 87)
	)
	(segment
		(start 114.115 80.915)
		(end 114.115 80.4)
		(width 0.3)
		(layer "B.Cu")
		(net 87)
	)
	(segment
		(start 72.235 103.835)
		(end 71.7 103.835)
		(width 0.2)
		(layer "B.Cu")
		(net 87)
	)
	(segment
		(start 110.5 106.85)
		(end 110.5 107.85)
		(width 0.125)
		(layer "B.Cu")
		(net 87)
	)
	(segment
		(start 92.9 101.15)
		(end 95.325 103.575)
		(width 0.15)
		(layer "B.Cu")
		(net 87)
	)
	(segment
		(start 62.78 96.23)
		(end 62.78 96.86)
		(width 0.13)
		(layer "B.Cu")
		(net 87)
	)
	(segment
		(start 92.6 86.95)
		(end 92.6 85.765)
		(width 0.2)
		(layer "B.Cu")
		(net 87)
	)
	(segment
		(start 107.04 87.94)
		(end 107.15 88.05)
		(width 0.3)
		(layer "B.Cu")
		(net 87)
	)
	(segment
		(start 63.15 95.86)
		(end 62.78 96.23)
		(width 0.13)
		(layer "B.Cu")
		(net 87)
	)
	(segment
		(start 125.604633 84.105)
		(end 125.832868 84.105)
		(width 0.155)
		(layer "B.Cu")
		(net 88)
	)
	(segment
		(start 125.481435 84.043934)
		(end 125.498567 84.061066)
		(width 0.155)
		(layer "B.Cu")
		(net 88)
	)
	(segment
		(start 125.938934 84.061066)
		(end 126.25 83.75)
		(width 0.155)
		(layer "B.Cu")
		(net 88)
	)
	(segment
		(start 124.275 84)
		(end 125.375369 84)
		(width 0.155)
		(layer "B.Cu")
		(net 88)
	)
	(arc
		(start 125.481435 84.043934)
		(mid 125.432772 84.011418)
		(end 125.375369 84)
		(width 0.155)
		(layer "B.Cu")
		(net 88)
	)
	(arc
		(start 125.832868 84.105)
		(mid 125.890271 84.093582)
		(end 125.938934 84.061066)
		(width 0.155)
		(layer "B.Cu")
		(net 88)
	)
	(arc
		(start 125.604633 84.105)
		(mid 125.54723 84.093582)
		(end 125.498567 84.061066)
		(width 0.155)
		(layer "B.Cu")
		(net 88)
	)
	(segment
		(start 125.604633 84.395)
		(end 125.832868 84.395)
		(width 0.155)
		(layer "B.Cu")
		(net 89)
	)
	(segment
		(start 125.938934 84.438934)
		(end 126.25 84.75)
		(width 0.155)
		(layer "B.Cu")
		(net 89)
	)
	(segment
		(start 124.275 84.5)
		(end 125.375369 84.5)
		(width 0.155)
		(layer "B.Cu")
		(net 89)
	)
	(segment
		(start 125.481435 84.456066)
		(end 125.498567 84.438934)
		(width 0.155)
		(layer "B.Cu")
		(net 89)
	)
	(arc
		(start 125.832868 84.395)
		(mid 125.890271 84.406418)
		(end 125.938934 84.438934)
		(width 0.155)
		(layer "B.Cu")
		(net 89)
	)
	(arc
		(start 125.375369 84.5)
		(mid 125.432772 84.488582)
		(end 125.481435 84.456066)
		(width 0.155)
		(layer "B.Cu")
		(net 89)
	)
	(arc
		(start 125.604633 84.395)
		(mid 125.54723 84.406418)
		(end 125.498567 84.438934)
		(width 0.155)
		(layer "B.Cu")
		(net 89)
	)
	(segment
		(start 124.275 87)
		(end 125.375369 87)
		(width 0.155)
		(layer "B.Cu")
		(net 90)
	)
	(segment
		(start 125.938934 87.061066)
		(end 126.25 86.75)
		(width 0.155)
		(layer "B.Cu")
		(net 90)
	)
	(segment
		(start 125.604633 87.105)
		(end 125.832868 87.105)
		(width 0.155)
		(layer "B.Cu")
		(net 90)
	)
	(segment
		(start 125.481435 87.043934)
		(end 125.498567 87.061066)
		(width 0.155)
		(layer "B.Cu")
		(net 90)
	)
	(arc
		(start 125.375369 87)
		(mid 125.432772 87.011418)
		(end 125.481435 87.043934)
		(width 0.155)
		(layer "B.Cu")
		(net 90)
	)
	(arc
		(start 125.604633 87.105)
		(mid 125.54723 87.093582)
		(end 125.498567 87.061066)
		(width 0.155)
		(layer "B.Cu")
		(net 90)
	)
	(arc
		(start 125.938934 87.061066)
		(mid 125.890271 87.093582)
		(end 125.832868 87.105)
		(width 0.155)
		(layer "B.Cu")
		(net 90)
	)
	(segment
		(start 124.275 87.5)
		(end 125.375369 87.5)
		(width 0.155)
		(layer "B.Cu")
		(net 91)
	)
	(segment
		(start 125.938934 87.438934)
		(end 126.25 87.75)
		(width 0.155)
		(layer "B.Cu")
		(net 91)
	)
	(segment
		(start 125.604633 87.395)
		(end 125.832868 87.395)
		(width 0.155)
		(layer "B.Cu")
		(net 91)
	)
	(segment
		(start 125.481435 87.456066)
		(end 125.498567 87.438934)
		(width 0.155)
		(layer "B.Cu")
		(net 91)
	)
	(arc
		(start 125.938934 87.438934)
		(mid 125.890271 87.406418)
		(end 125.832868 87.395)
		(width 0.155)
		(layer "B.Cu")
		(net 91)
	)
	(arc
		(start 125.375369 87.5)
		(mid 125.432772 87.488582)
		(end 125.481435 87.456066)
		(width 0.155)
		(layer "B.Cu")
		(net 91)
	)
	(arc
		(start 125.604633 87.395)
		(mid 125.54723 87.406418)
		(end 125.498567 87.438934)
		(width 0.155)
		(layer "B.Cu")
		(net 91)
	)
	(segment
		(start 125.604633 90.105)
		(end 125.832868 90.105)
		(width 0.155)
		(layer "B.Cu")
		(net 92)
	)
	(segment
		(start 125.481435 90.043934)
		(end 125.498567 90.061066)
		(width 0.155)
		(layer "B.Cu")
		(net 92)
	)
	(segment
		(start 125.938934 90.061066)
		(end 126.25 89.75)
		(width 0.155)
		(layer "B.Cu")
		(net 92)
	)
	(segment
		(start 124.275 90)
		(end 125.375369 90)
		(width 0.155)
		(layer "B.Cu")
		(net 92)
	)
	(arc
		(start 125.832868 90.105)
		(mid 125.890271 90.093582)
		(end 125.938934 90.061066)
		(width 0.155)
		(layer "B.Cu")
		(net 92)
	)
	(arc
		(start 125.604633 90.105)
		(mid 125.54723 90.093582)
		(end 125.498567 90.061066)
		(width 0.155)
		(layer "B.Cu")
		(net 92)
	)
	(arc
		(start 125.481435 90.043934)
		(mid 125.432772 90.011418)
		(end 125.375369 90)
		(width 0.155)
		(layer "B.Cu")
		(net 92)
	)
	(segment
		(start 125.938934 90.438934)
		(end 126.25 90.75)
		(width 0.155)
		(layer "B.Cu")
		(net 93)
	)
	(segment
		(start 125.481435 90.456066)
		(end 125.498567 90.438934)
		(width 0.155)
		(layer "B.Cu")
		(net 93)
	)
	(segment
		(start 124.275 90.5)
		(end 125.375369 90.5)
		(width 0.155)
		(layer "B.Cu")
		(net 93)
	)
	(segment
		(start 125.604633 90.395)
		(end 125.832868 90.395)
		(width 0.155)
		(layer "B.Cu")
		(net 93)
	)
	(arc
		(start 125.938934 90.438934)
		(mid 125.890271 90.406418)
		(end 125.832868 90.395)
		(width 0.155)
		(layer "B.Cu")
		(net 93)
	)
	(arc
		(start 125.481435 90.456066)
		(mid 125.432772 90.488582)
		(end 125.375369 90.5)
		(width 0.155)
		(layer "B.Cu")
		(net 93)
	)
	(arc
		(start 125.498567 90.438934)
		(mid 125.54723 90.406418)
		(end 125.604633 90.395)
		(width 0.155)
		(layer "B.Cu")
		(net 93)
	)
	(segment
		(start 125.604633 93.105)
		(end 125.847868 93.105)
		(width 0.155)
		(layer "B.Cu")
		(net 94)
	)
	(segment
		(start 124.275 93)
		(end 125.375369 93)
		(width 0.155)
		(layer "B.Cu")
		(net 94)
	)
	(segment
		(start 125.953934 93.061066)
		(end 126.265 92.75)
		(width 0.155)
		(layer "B.Cu")
		(net 94)
	)
	(segment
		(start 125.481435 93.043934)
		(end 125.498567 93.061066)
		(width 0.155)
		(layer "B.Cu")
		(net 94)
	)
	(arc
		(start 125.604633 93.105)
		(mid 125.54723 93.093582)
		(end 125.498567 93.061066)
		(width 0.155)
		(layer "B.Cu")
		(net 94)
	)
	(arc
		(start 125.375369 93)
		(mid 125.432772 93.011418)
		(end 125.481435 93.043934)
		(width 0.155)
		(layer "B.Cu")
		(net 94)
	)
	(arc
		(start 125.847868 93.105)
		(mid 125.905271 93.093582)
		(end 125.953934 93.061066)
		(width 0.155)
		(layer "B.Cu")
		(net 94)
	)
	(segment
		(start 124.275 93.5)
		(end 125.375369 93.5)
		(width 0.155)
		(layer "B.Cu")
		(net 95)
	)
	(segment
		(start 125.604633 93.395)
		(end 125.847868 93.395)
		(width 0.155)
		(layer "B.Cu")
		(net 95)
	)
	(segment
		(start 125.953934 93.438934)
		(end 126.265 93.75)
		(width 0.155)
		(layer "B.Cu")
		(net 95)
	)
	(segment
		(start 125.481435 93.456066)
		(end 125.498567 93.438934)
		(width 0.155)
		(layer "B.Cu")
		(net 95)
	)
	(arc
		(start 125.375369 93.5)
		(mid 125.432772 93.488582)
		(end 125.481435 93.456066)
		(width 0.155)
		(layer "B.Cu")
		(net 95)
	)
	(arc
		(start 125.604633 93.395)
		(mid 125.54723 93.406418)
		(end 125.498567 93.438934)
		(width 0.155)
		(layer "B.Cu")
		(net 95)
	)
	(arc
		(start 125.847868 93.395)
		(mid 125.905271 93.406418)
		(end 125.953934 93.438934)
		(width 0.155)
		(layer "B.Cu")
		(net 95)
	)
	(segment
		(start 125.2255 94.5005)
		(end 125.125 94.4)
		(width 0.155)
		(layer "F.Cu")
		(net 96)
	)
	(segment
		(start 126.57 94.2)
		(end 126.372013 94.397987)
		(width 0.155)
		(layer "F.Cu")
		(net 96)
	)
	(segment
		(start 126.124525 94.5005)
		(end 125.2255 94.5005)
		(width 0.155)
		(layer "F.Cu")
		(net 96)
	)
	(segment
		(start 125.125 94.4)
		(end 124.5 94.4)
		(width 0.155)
		(layer "F.Cu")
		(net 96)
	)
	(arc
		(start 126.372013 94.397987)
		(mid 126.258465 94.473858)
		(end 126.124525 94.5005)
		(width 0.155)
		(layer "F.Cu")
		(net 96)
	)
	(segment
		(start 125.2255 94.7995)
		(end 126.024525 94.7995)
		(width 0.155)
		(layer "F.Cu")
		(net 97)
	)
	(segment
		(start 125.125 94.9)
		(end 125.2255 94.7995)
		(width 0.155)
		(layer "F.Cu")
		(net 97)
	)
	(segment
		(start 126.272013 94.902013)
		(end 126.57 95.2)
		(width 0.155)
		(layer "F.Cu")
		(net 97)
	)
	(segment
		(start 124.5 94.9)
		(end 125.125 94.9)
		(width 0.155)
		(layer "F.Cu")
		(net 97)
	)
	(arc
		(start 126.024525 94.7995)
		(mid 126.158465 94.826142)
		(end 126.272013 94.902013)
		(width 0.155)
		(layer "F.Cu")
		(net 97)
	)
	(segment
		(start 82.36 115.96)
		(end 82.51 115.96)
		(width 0.15)
		(layer "F.Cu")
		(net 98)
	)
	(segment
		(start 82.27 116.05)
		(end 82.18 115.96)
		(width 0.15)
		(layer "F.Cu")
		(net 98)
	)
	(segment
		(start 80.08 115.79)
		(end 80.97 115.79)
		(width 0.15)
		(layer "F.Cu")
		(net 98)
	)
	(segment
		(start 81.14 115.96)
		(end 82.18 115.96)
		(width 0.15)
		(layer "F.Cu")
		(net 98)
	)
	(segment
		(start 81.55 114.87)
		(end 81.11 114.87)
		(width 0.15)
		(layer "F.Cu")
		(net 98)
	)
	(segment
		(start 82.27 116.05)
		(end 82.36 115.96)
		(width 0.15)
		(layer "F.Cu")
		(net 98)
	)
	(segment
		(start 82.18 115.96)
		(end 82.36 115.96)
		(width 0.15)
		(layer "F.Cu")
		(net 98)
	)
	(segment
		(start 80.97 115.79)
		(end 81.14 115.96)
		(width 0.15)
		(layer "F.Cu")
		(net 98)
	)
	(segment
		(start 80.95 115.77)
		(end 81.14 115.96)
		(width 0.15)
		(layer "F.Cu")
		(net 98)
	)
	(segment
		(start 80.95 115.03)
		(end 80.95 115.77)
		(width 0.15)
		(layer "F.Cu")
		(net 98)
	)
	(segment
		(start 81.77 113.38)
		(end 80.8 113.38)
		(width 0.15)
		(layer "F.Cu")
		(net 98)
	)
	(segment
		(start 81.772 114.127)
		(end 81.772 114.648)
		(width 0.15)
		(layer "F.Cu")
		(net 98)
	)
	(segment
		(start 81.77 113.38)
		(end 81.772 113.382)
		(width 0.15)
		(layer "F.Cu")
		(net 98)
	)
	(segment
		(start 82.27 116.676)
		(end 82.27 116.05)
		(width 0.15)
		(layer "F.Cu")
		(net 98)
	)
	(segment
		(start 81.77 113.44)
		(end 81.77 113.38)
		(width 0.15)
		(layer "F.Cu")
		(net 98)
	)
	(segment
		(start 82.51 115.96)
		(end 82.77 116.22)
		(width 0.15)
		(layer "F.Cu")
		(net 98)
	)
	(segment
		(start 81.772 114.648)
		(end 81.55 114.87)
		(width 0.15)
		(layer "F.Cu")
		(net 98)
	)
	(segment
		(start 81.11 114.87)
		(end 80.95 115.03)
		(width 0.15)
		(layer "F.Cu")
		(net 98)
	)
	(segment
		(start 81.772 113.382)
		(end 81.772 114.127)
		(width 0.15)
		(layer "F.Cu")
		(net 98)
	)
	(segment
		(start 82.77 116.22)
		(end 82.77 116.676)
		(width 0.15)
		(layer "F.Cu")
		(net 98)
	)
	(segment
		(start 80.8 113.38)
		(end 80.22 112.8)
		(width 0.15)
		(layer "F.Cu")
		(net 98)
	)
	(via
		(at 83.65 111.2)
		(size 0.45)
		(drill 0.1)
		(layers "F.Cu" "B.Cu")
		(net 98)
	)
	(via
		(at 81.77 113.38)
		(size 0.45)
		(drill 0.1)
		(layers "F.Cu" "B.Cu")
		(net 98)
	)
	(segment
		(start 81.77 112.48)
		(end 82.25 112)
		(width 0.15)
		(layer "In1.Cu")
		(net 98)
	)
	(segment
		(start 82.25 112)
		(end 82.85 112)
		(width 0.15)
		(layer "In1.Cu")
		(net 98)
	)
	(segment
		(start 82.85 112)
		(end 83.65 111.2)
		(width 0.15)
		(layer "In1.Cu")
		(net 98)
	)
	(segment
		(start 81.77 113.44)
		(end 81.77 112.48)
		(width 0.15)
		(layer "In1.Cu")
		(net 98)
	)
	(segment
		(start 84.81 123.46)
		(end 85.41 123.46)
		(width 0.15)
		(layer "B.Cu")
		(net 98)
	)
	(segment
		(start 85.81 123.86)
		(end 85.81 125.2495)
		(width 0.15)
		(layer "B.Cu")
		(net 98)
	)
	(segment
		(start 84.71 121.05)
		(end 84.312 121.448)
		(width 0.15)
		(layer "B.Cu")
		(net 98)
	)
	(segment
		(start 81.8 103.7)
		(end 75.81 97.71)
		(width 0.125)
		(layer "B.Cu")
		(net 98)
	)
	(segment
		(start 84.312 122.962)
		(end 84.81 123.46)
		(width 0.15)
		(layer "B.Cu")
		(net 98)
	)
	(segment
		(start 85.4 112.95)
		(end 85.4 120.7)
		(width 0.15)
		(layer "B.Cu")
		(net 98)
	)
	(segment
		(start 84.312 121.448)
		(end 84.312 122.962)
		(width 0.15)
		(layer "B.Cu")
		(net 98)
	)
	(segment
		(start 83.65 111.2)
		(end 85.4 112.95)
		(width 0.15)
		(layer "B.Cu")
		(net 98)
	)
	(segment
		(start 75.81 97.71)
		(end 69.551 97.71)
		(width 0.125)
		(layer "B.Cu")
		(net 98)
	)
	(segment
		(start 81.8 109.35)
		(end 81.8 103.7)
		(width 0.125)
		(layer "B.Cu")
		(net 98)
	)
	(segment
		(start 85.05 121.05)
		(end 84.71 121.05)
		(width 0.15)
		(layer "B.Cu")
		(net 98)
	)
	(segment
		(start 83.65 111.2)
		(end 81.8 109.35)
		(width 0.125)
		(layer "B.Cu")
		(net 98)
	)
	(segment
		(start 85.41 123.46)
		(end 85.81 123.86)
		(width 0.15)
		(layer "B.Cu")
		(net 98)
	)
	(segment
		(start 85.81 125.2495)
		(end 86.449 125.8885)
		(width 0.15)
		(layer "B.Cu")
		(net 98)
	)
	(segment
		(start 85.4 120.7)
		(end 85.05 121.05)
		(width 0.15)
		(layer "B.Cu")
		(net 98)
	)
	(segment
		(start 104.665 104.1)
		(end 104.665 103.435)
		(width 0.3)
		(layer "F.Cu")
		(net 99)
	)
	(segment
		(start 69.98 101.67)
		(end 69.6 102.05)
		(width 0.2)
		(layer "F.Cu")
		(net 99)
	)
	(segment
		(start 55.63 107.8)
		(end 54.105 109.325)
		(width 0.2)
		(layer "F.Cu")
		(net 99)
	)
	(segment
		(start 105.7 103.135)
		(end 106.035 103.135)
		(width 0.3)
		(layer "F.Cu")
		(net 99)
	)
	(segment
		(start 107.18 104.28)
		(end 107.245 104.345)
		(width 0.3)
		(layer "F.Cu")
		(net 99)
	)
	(segment
		(start 60.15 107.561258)
		(end 59.999258 107.712)
		(width 0.125)
		(layer "F.Cu")
		(net 99)
	)
	(segment
		(start 60.15 107.035)
		(end 60.15 107.561258)
		(width 0.125)
		(layer "F.Cu")
		(net 99)
	)
	(segment
		(start 61.84 102.24)
		(end 62.011763 102.411763)
		(width 0.3)
		(layer "F.Cu")
		(net 99)
	)
	(segment
		(start 106.035 103.135)
		(end 106.88 103.98)
		(width 0.3)
		(layer "F.Cu")
		(net 99)
	)
	(segment
		(start 55.34 103.22)
		(end 54.95 103.61)
		(width 0.155)
		(layer "F.Cu")
		(net 99)
	)
	(segment
		(start 58 107.8)
		(end 55.63 107.8)
		(width 0.2)
		(layer "F.Cu")
		(net 99)
	)
	(segment
		(start 70.59 101.67)
		(end 69.98 101.67)
		(width 0.2)
		(layer "F.Cu")
		(net 99)
	)
	(segment
		(start 107.245 104.345)
		(end 108.089938 104.345)
		(width 0.3)
		(layer "F.Cu")
		(net 99)
	)
	(segment
		(start 64.05 113.6)
		(end 65.035 113.6)
		(width 0.15)
		(layer "F.Cu")
		(net 99)
	)
	(segment
		(start 57.2 103)
		(end 56.08 103)
		(width 0.155)
		(layer "F.Cu")
		(net 99)
	)
	(segment
		(start 60.7 108.915)
		(end 61.885 108.915)
		(width 0.3)
		(layer "F.Cu")
		(net 99)
	)
	(segment
		(start 61.31 102.24)
		(end 61.84 102.24)
		(width 0.3)
		(layer "F.Cu")
		(net 99)
	)
	(segment
		(start 55.86 103.22)
		(end 55.34 103.22)
		(width 0.155)
		(layer "F.Cu")
		(net 99)
	)
	(segment
		(start 63.634503 113.218276)
		(end 63.9 113.483773)
		(width 0.15)
		(layer "F.Cu")
		(net 99)
	)
	(segment
		(start 54.95 105.21)
		(end 55.09 105.35)
		(width 0.155)
		(layer "F.Cu")
		(net 99)
	)
	(segment
		(start 57.715 103.515)
		(end 57.2 103)
		(width 0.155)
		(layer "F.Cu")
		(net 99)
	)
	(segment
		(start 105.565 103)
		(end 105.05 103)
		(width 0.2)
		(layer "F.Cu")
		(net 99)
	)
	(segment
		(start 86.05 118.55)
		(end 85.8 118.55)
		(width 0.2)
		(layer "F.Cu")
		(net 99)
	)
	(segment
		(start 62.065 103.515)
		(end 57.715 103.515)
		(width 0.155)
		(layer "F.Cu")
		(net 99)
	)
	(segment
		(start 106.887107 103.98)
		(end 107.18 104.272893)
		(width 0.3)
		(layer "F.Cu")
		(net 99)
	)
	(segment
		(start 63.9 113.483773)
		(end 63.9 113.6)
		(width 0.15)
		(layer "F.Cu")
		(net 99)
	)
	(segment
		(start 55.09 105.35)
		(end 56.605 105.35)
		(width 0.155)
		(layer "F.Cu")
		(net 99)
	)
	(segment
		(start 104.665 103.435)
		(end 105 103.1)
		(width 0.3)
		(layer "F.Cu")
		(net 99)
	)
	(segment
		(start 62.065 103.515)
		(end 62.065 102.8)
		(width 0.2)
		(layer "F.Cu")
		(net 99)
	)
	(segment
		(start 105.7 103.135)
		(end 105.565 103)
		(width 0.2)
		(layer "F.Cu")
		(net 99)
	)
	(segment
		(start 54.105 109.325)
		(end 53.55 109.325)
		(width 0.2)
		(layer "F.Cu")
		(net 99)
	)
	(segment
		(start 104.665 105.05)
		(end 104.665 104.1)
		(width 0.3)
		(layer "F.Cu")
		(net 99)
	)
	(segment
		(start 107.18 104.272893)
		(end 107.18 104.28)
		(width 0.3)
		(layer "F.Cu")
		(net 99)
	)
	(segment
		(start 85.8 118.55)
		(end 85.2 117.95)
		(width 0.2)
		(layer "F.Cu")
		(net 99)
	)
	(segment
		(start 68.45 103.75)
		(end 62.3 103.75)
		(width 0.2)
		(layer "F.Cu")
		(net 99)
	)
	(segment
		(start 56.08 103)
		(end 55.86 103.22)
		(width 0.155)
		(layer "F.Cu")
		(net 99)
	)
	(segment
		(start 62.011763 102.411763)
		(end 62.011763 102.746763)
		(width 0.3)
		(layer "F.Cu")
		(net 99)
	)
	(segment
		(start 106.88 103.98)
		(end 106.887107 103.98)
		(width 0.3)
		(layer "F.Cu")
		(net 99)
	)
	(segment
		(start 62.011763 102.746763)
		(end 62.065 102.8)
		(width 0.3)
		(layer "F.Cu")
		(net 99)
	)
	(segment
		(start 62.3 103.75)
		(end 62.065 103.515)
		(width 0.2)
		(layer "F.Cu")
		(net 99)
	)
	(segment
		(start 65.035 113.6)
		(end 65.05 113.585)
		(width 0.15)
		(layer "F.Cu")
		(net 99)
	)
	(segment
		(start 69.6 102.05)
		(end 69.6 102.6)
		(width 0.2)
		(layer "F.Cu")
		(net 99)
	)
	(segment
		(start 54.95 103.61)
		(end 54.95 105.21)
		(width 0.155)
		(layer "F.Cu")
		(net 99)
	)
	(segment
		(start 69.6 102.6)
		(end 68.45 103.75)
		(width 0.2)
		(layer "F.Cu")
		(net 99)
	)
	(via
		(at 58.7 92.2)
		(size 0.45)
		(drill 0.1)
		(layers "F.Cu" "B.Cu")
		(free yes)
		(net 99)
	)
	(via
		(at 100.25 118.6)
		(size 0.45)
		(drill 0.1)
		(layers "F.Cu" "B.Cu")
		(free yes)
		(net 99)
	)
	(via
		(at 70 118.27)
		(size 0.45)
		(drill 0.1)
		(layers "F.Cu" "B.Cu")
		(free yes)
		(net 99)
	)
	(via
		(at 100.25 117.6)
		(size 0.45)
		(drill 0.1)
		(layers "F.Cu" "B.Cu")
		(free yes)
		(net 99)
	)
	(via
		(at 69.4 118.77)
		(size 0.45)
		(drill 0.1)
		(layers "F.Cu" "B.Cu")
		(free yes)
		(net 99)
	)
	(via
		(at 59.999258 107.712)
		(size 0.45)
		(drill 0.1)
		(layers "F.Cu" "B.Cu")
		(free yes)
		(net 99)
	)
	(via
		(at 58.7 93)
		(size 0.45)
		(drill 0.1)
		(layers "F.Cu" "B.Cu")
		(free yes)
		(net 99)
	)
	(via
		(at 70.59 101.67)
		(size 0.45)
		(drill 0.1)
		(layers "F.Cu" "B.Cu")
		(net 99)
	)
	(via
		(at 100.75 118.6)
		(size 0.45)
		(drill 0.1)
		(layers "F.Cu" "B.Cu")
		(free yes)
		(net 99)
	)
	(via
		(at 60.5 108.2)
		(size 0.45)
		(drill 0.1)
		(layers "F.Cu" "B.Cu")
		(free yes)
		(net 99)
	)
	(via
		(at 70 118.77)
		(size 0.45)
		(drill 0.1)
		(layers "F.Cu" "B.Cu")
		(free yes)
		(net 99)
	)
	(via
		(at 136.9 118.4)
		(size 0.45)
		(drill 0.1)
		(layers "F.Cu" "B.Cu")
		(free yes)
		(net 99)
	)
	(via
		(at 97.112 86.55)
		(size 0.45)
		(drill 0.1)
		(layers "F.Cu" "B.Cu")
		(free yes)
		(net 99)
	)
	(via
		(at 59.3 93)
		(size 0.45)
		(drill 0.1)
		(layers "F.Cu" "B.Cu")
		(free yes)
		(net 99)
	)
	(via
		(at 60 108.2)
		(size 0.45)
		(drill 0.1)
		(layers "F.Cu" "B.Cu")
		(free yes)
		(net 99)
	)
	(via
		(at 135.1 118.4)
		(size 0.45)
		(drill 0.1)
		(layers "F.Cu" "B.Cu")
		(free yes)
		(net 99)
	)
	(via
		(at 105.7 103.135)
		(size 0.45)
		(drill 0.1)
		(layers "F.Cu" "B.Cu")
		(net 99)
	)
	(via
		(at 97.125 86.05)
		(size 0.45)
		(drill 0.1)
		(layers "F.Cu" "B.Cu")
		(free yes)
		(net 99)
	)
	(via
		(at 59.3 92.205)
		(size 0.45)
		(drill 0.1)
		(layers "F.Cu" "B.Cu")
		(free yes)
		(net 99)
	)
	(via
		(at 59.6 92.6)
		(size 0.45)
		(drill 0.1)
		(layers "F.Cu" "B.Cu")
		(free yes)
		(net 99)
	)
	(via
		(at 63.634503 113.218276)
		(size 0.45)
		(drill 0.1)
		(layers "F.Cu" "B.Cu")
		(net 99)
	)
	(via
		(at 69.4 117.77)
		(size 0.45)
		(drill 0.1)
		(layers "F.Cu" "B.Cu")
		(free yes)
		(net 99)
	)
	(via
		(at 86.05 118.55)
		(size 0.45)
		(drill 0.1)
		(layers "F.Cu" "B.Cu")
		(net 99)
	)
	(via
		(at 70 117.77)
		(size 0.45)
		(drill 0.1)
		(layers "F.Cu" "B.Cu")
		(free yes)
		(net 99)
	)
	(via
		(at 58 107.8)
		(size 0.45)
		(drill 0.1)
		(layers "F.Cu" "B.Cu")
		(net 99)
	)
	(via
		(at 69.4 118.27)
		(size 0.45)
		(drill 0.1)
		(layers "F.Cu" "B.Cu")
		(free yes)
		(net 99)
	)
	(via
		(at 100.75 117.6)
		(size 0.45)
		(drill 0.1)
		(layers "F.Cu" "B.Cu")
		(free yes)
		(net 99)
	)
	(via
		(at 136.3 118.4)
		(size 0.45)
		(drill 0.1)
		(layers "F.Cu" "B.Cu")
		(free yes)
		(net 99)
	)
	(via
		(at 59.9 92.205)
		(size 0.45)
		(drill 0.1)
		(layers "F.Cu" "B.Cu")
		(free yes)
		(net 99)
	)
	(via
		(at 135.7 118.4)
		(size 0.45)
		(drill 0.1)
		(layers "F.Cu" "B.Cu")
		(free yes)
		(net 99)
	)
	(via
		(at 61.31 102.24)
		(size 0.45)
		(drill 0.1)
		(layers "F.Cu" "B.Cu")
		(net 99)
	)
	(via
		(at 100.5 118.1)
		(size 0.45)
		(drill 0.1)
		(layers "F.Cu" "B.Cu")
		(free yes)
		(net 99)
	)
	(via
		(at 59.9 93)
		(size 0.45)
		(drill 0.1)
		(layers "F.Cu" "B.Cu")
		(free yes)
		(net 99)
	)
	(via
		(at 60.5 107.7)
		(size 0.45)
		(drill 0.1)
		(layers "F.Cu" "B.Cu")
		(free yes)
		(net 99)
	)
	(via
		(at 59 92.6)
		(size 0.45)
		(drill 0.1)
		(layers "F.Cu" "B.Cu")
		(free yes)
		(net 99)
	)
	(segment
		(start 100.25 118.6)
		(end 100.25 118.1)
		(width 0.3)
		(layer "B.Cu")
		(net 99)
	)
	(segment
		(start 70.56 101.7)
		(end 69.65 101.7)
		(width 0.3)
		(layer "B.Cu")
		(net 99)
	)
	(segment
		(start 100.5 118.35)
		(end 100.75 118.6)
		(width 0.3)
		(layer "B.Cu")
		(net 99)
	)
	(segment
		(start 70.59 101.67)
		(end 70.82 101.9)
		(width 0.3)
		(layer "B.Cu")
		(net 99)
	)
	(segment
		(start 71.445 119.925)
		(end 70.32 118.8)
		(width 0.15)
		(layer "B.Cu")
		(net 99)
	)
	(segment
		(start 100.25 118.1)
		(end 100.75 117.6)
		(width 0.3)
		(layer "B.Cu")
		(net 99)
	)
	(segment
		(start 100.25 118.6)
		(end 100.25 117.6)
		(width 0.3)
		(layer "B.Cu")
		(net 99)
	)
	(segment
		(start 114.05 103.1)
		(end 114.4 103.45)
		(width 0.13)
		(layer "B.Cu")
		(net 99)
	)
	(segment
		(start 105.565 103.135)
		(end 100.5 108.2)
		(width 0.3)
		(layer "B.Cu")
		(net 99)
	)
	(segment
		(start 112.65 102.4)
		(end 112.885 102.635)
		(width 0.13)
		(layer "B.Cu")
		(net 99)
	)
	(segment
		(start 70.82 101.9)
		(end 71.315 101.9)
		(width 0.3)
		(layer "B.Cu")
		(net 99)
	)
	(segment
		(start 100.25 117.6)
		(end 100.5 117.35)
		(width 0.3)
		(layer "B.Cu")
		(net 99)
	)
	(segment
		(start 112.885 102.635)
		(end 112.885 103.1)
		(width 0.13)
		(layer "B.Cu")
		(net 99)
	)
	(segment
		(start 100.75 118.6)
		(end 100.75 118.1)
		(width 0.3)
		(layer "B.Cu")
		(net 99)
	)
	(segment
		(start 60.55 87.22)
		(end 61.05 87.72)
		(width 0.5)
		(layer "B.Cu")
		(net 99)
	)
	(segment
		(start 113.95 106.1)
		(end 112.885 106.1)
		(width 0.13)
		(layer "B.Cu")
		(net 99)
	)
	(segment
		(start 136.0658 117.4008)
		(end 136.9 118.235)
		(width 0.3)
		(layer "B.Cu")
		(net 99)
	)
	(segment
		(start 100.75 118.6)
		(end 100.75 117.6)
		(width 0.3)
		(layer "B.Cu")
		(net 99)
	)
	(segment
		(start 105.7 103.135)
		(end 106.435 102.4)
		(width 0.13)
		(layer "B.Cu")
		(net 99)
	)
	(segment
		(start 100.75 118.6)
		(end 100.25 118.6)
		(width 0.3)
		(layer "B.Cu")
		(net 99)
	)
	(segment
		(start 60.55 85.2)
		(end 60.55 86.31)
		(width 0.5)
		(layer "B.Cu")
		(net 99)
	)
	(segment
		(start 100.5 118.1)
		(end 100.5 118.35)
		(width 0.3)
		(layer "B.Cu")
		(net 99)
	)
	(segment
		(start 61.85 101.7)
		(end 62.95 101.7)
		(width 0.2)
		(layer "B.Cu")
		(net 99)
	)
	(segment
		(start 100.75 117.6)
		(end 100.25 117.6)
		(width 0.3)
		(layer "B.Cu")
		(net 99)
	)
	(segment
		(start 60.55 86.31)
		(end 60.55 87.22)
		(width 0.5)
		(layer "B.Cu")
		(net 99)
	)
	(segment
		(start 71.445 121.255)
		(end 71.445 119.925)
		(width 0.15)
		(layer "B.Cu")
		(net 99)
	)
	(segment
		(start 68.66 122.065)
		(end 70.635 122.065)
		(width 0.15)
		(layer "B.Cu")
		(net 99)
	)
	(segment
		(start 100.55 117.4)
		(end 100.75 117.6)
		(width 0.3)
		(layer "B.Cu")
		(net 99)
	)
	(segment
		(start 70.59 101.67)
		(end 70.56 101.7)
		(width 0.3)
		(layer "B.Cu")
		(net 99)
	)
	(segment
		(start 61.05 87.72)
		(end 61.05 91.7)
		(width 0.5)
		(layer "B.Cu")
		(net 99)
	)
	(segment
		(start 68.165 121.57)
		(end 68.66 122.065)
		(width 0.15)
		(layer "B.Cu")
		(net 99)
	)
	(segment
		(start 114.4 103.45)
		(end 114.4 105.65)
		(width 0.13)
		(layer "B.Cu")
		(net 99)
	)
	(segment
		(start 100.5 117.35)
		(end 100.55 117.4)
		(width 0.3)
		(layer "B.Cu")
		(net 99)
	)
	(segment
		(start 70.635 122.065)
		(end 71.445 121.255)
		(width 0.15)
		(layer "B.Cu")
		(net 99)
	)
	(segment
		(start 61.31 102.24)
		(end 61.85 101.7)
		(width 0.2)
		(layer "B.Cu")
		(net 99)
	)
	(segment
		(start 105.7 103.135)
		(end 105.565 103.135)
		(width 0.3)
		(layer "B.Cu")
		(net 99)
	)
	(segment
		(start 114.4 105.65)
		(end 113.95 106.1)
		(width 0.13)
		(layer "B.Cu")
		(net 99)
	)
	(segment
		(start 70.32 118.8)
		(end 70 118.8)
		(width 0.15)
		(layer "B.Cu")
		(net 99)
	)
	(segment
		(start 59.775339 92.974661)
		(end 58.885127 92.974661)
		(width 0.5)
		(layer "B.Cu")
		(net 99)
	)
	(segment
		(start 112.885 103.1)
		(end 114.05 103.1)
		(width 0.13)
		(layer "B.Cu")
		(net 99)
	)
	(segment
		(start 100.5 108.2)
		(end 100.5 117.35)
		(width 0.3)
		(layer "B.Cu")
		(net 99)
	)
	(segment
		(start 61.05 91.7)
		(end 59.775339 92.974661)
		(width 0.5)
		(layer "B.Cu")
		(net 99)
	)
	(segment
		(start 136.9 118.235)
		(end 136.9 118.4)
		(width 0.3)
		(layer "B.Cu")
		(net 99)
	)
	(segment
		(start 100.75 118.1)
		(end 100.25 117.6)
		(width 0.3)
		(layer "B.Cu")
		(net 99)
	)
	(segment
		(start 106.435 102.4)
		(end 112.65 102.4)
		(width 0.13)
		(layer "B.Cu")
		(net 99)
	)
	(segment
		(start 149.05 110.5)
		(end 149.075 110.475)
		(width 0.15)
		(layer "F.Cu")
		(net 100)
	)
	(segment
		(start 89.4 73.45)
		(end 90.344646 73.45)
		(width 0.15)
		(layer "F.Cu")
		(net 100)
	)
	(segment
		(start 87.6 75.25)
		(end 89.4 73.45)
		(width 0.15)
		(layer "F.Cu")
		(net 100)
	)
	(segment
		(start 90.344646 73.45)
		(end 90.597323 73.197323)
		(width 0.15)
		(layer "F.Cu")
		(net 100)
	)
	(segment
		(start 87.6 77.3)
		(end 87.6 75.25)
		(width 0.15)
		(layer "F.Cu")
		(net 100)
	)
	(segment
		(start 90.597323 73.197323)
		(end 90.597323 72.902677)
		(width 0.15)
		(layer "F.Cu")
		(net 100)
	)
	(segment
		(start 148.485 110.5)
		(end 149.05 110.5)
		(width 0.15)
		(layer "F.Cu")
		(net 100)
	)
	(segment
		(start 90.597323 72.902677)
		(end 90.6 72.9)
		(width 0.15)
		(layer "F.Cu")
		(net 100)
	)
	(via
		(at 89.9 123.6)
		(size 0.45)
		(drill 0.1)
		(layers "F.Cu" "B.Cu")
		(net 100)
	)
	(via
		(at 79.374793 91.628001)
		(size 0.45)
		(drill 0.1)
		(layers "F.Cu" "B.Cu")
		(net 100)
	)
	(via
		(at 87.6 77.3)
		(size 0.45)
		(drill 0.1)
		(layers "F.Cu" "B.Cu")
		(net 100)
	)
	(via
		(at 80.18 84.72)
		(size 0.45)
		(drill 0.1)
		(layers "F.Cu" "B.Cu")
		(net 100)
	)
	(via
		(at 85.9 116.7)
		(size 0.45)
		(drill 0.1)
		(layers "F.Cu" "B.Cu")
		(net 100)
	)
	(via
		(at 149.075 110.475)
		(size 0.45)
		(drill 0.1)
		(layers "F.Cu" "B.Cu")
		(net 100)
	)
	(segment
		(start 85.9 116.7)
		(end 85.9 117.2)
		(width 0.155)
		(layer "In5.Cu")
		(net 100)
	)
	(segment
		(start 86.95 118.25)
		(end 85.9 117.2)
		(width 0.155)
		(layer "In5.Cu")
		(net 100)
	)
	(segment
		(start 90.1 123.4)
		(end 89.9 123.6)
		(width 0.155)
		(layer "In5.Cu")
		(net 100)
	)
	(segment
		(start 89.15 121.4)
		(end 90.1 122.35)
		(width 0.155)
		(layer "In5.Cu")
		(net 100)
	)
	(segment
		(start 86.95 118.95)
		(end 86.95 118.8)
		(width 0.155)
		(layer "In5.Cu")
		(net 100)
	)
	(segment
		(start 79.374793 91.628001)
		(end 79.374793 91.435207)
		(width 0.125)
		(layer "In5.Cu")
		(net 100)
	)
	(segment
		(start 80.02 84.88)
		(end 80.18 84.72)
		(width 0.125)
		(layer "In5.Cu")
		(net 100)
	)
	(segment
		(start 90.1 122.35)
		(end 90.1 123.4)
		(width 0.155)
		(layer "In5.Cu")
		(net 100)
	)
	(segment
		(start 86.95 119.7)
		(end 86.95 118.8)
		(width 0.125)
		(layer "In5.Cu")
		(net 100)
	)
	(segment
		(start 80.18 84.72)
		(end 80.2 84.74)
		(width 0.125)
		(layer "In5.Cu")
		(net 100)
	)
	(segment
		(start 86.95 120.85)
		(end 87.5 121.4)
		(width 0.155)
		(layer "In5.Cu")
		(net 100)
	)
	(segment
		(start 87.5 121.4)
		(end 89.15 121.4)
		(width 0.155)
		(layer "In5.Cu")
		(net 100)
	)
	(segment
		(start 80.02 90.79)
		(end 80.02 84.88)
		(width 0.125)
		(layer "In5.Cu")
		(net 100)
	)
	(segment
		(start 86.95 120)
		(end 86.95 118.95)
		(width 0.155)
		(layer "In5.Cu")
		(net 100)
	)
	(segment
		(start 86.95 120)
		(end 86.95 120.85)
		(width 0.155)
		(layer "In5.Cu")
		(net 100)
	)
	(segment
		(start 86.95 119.7)
		(end 86.95 120)
		(width 0.155)
		(layer "In5.Cu")
		(net 100)
	)
	(segment
		(start 79.374793 91.435207)
		(end 80.02 90.79)
		(width 0.125)
		(layer "In5.Cu")
		(net 100)
	)
	(segment
		(start 86.95 118.95)
		(end 86.95 118.25)
		(width 0.155)
		(layer "In5.Cu")
		(net 100)
	)
	(segment
		(start 149.075 112.175)
		(end 148.6 112.65)
		(width 0.15)
		(layer "B.Cu")
		(net 100)
	)
	(segment
		(start 86.65 80.25)
		(end 87.4 79.5)
		(width 0.15)
		(layer "B.Cu")
		(net 100)
	)
	(segment
		(start 108.42 127.38)
		(end 105.53 127.38)
		(width 0.155)
		(layer "B.Cu")
		(net 100)
	)
	(segment
		(start 77.460814 91.234186)
		(end 78.980978 91.234186)
		(width 0.125)
		(layer "B.Cu")
		(net 100)
	)
	(segment
		(start 87.4 77.5)
		(end 87.6 77.3)
		(width 0.15)
		(layer "B.Cu")
		(net 100)
	)
	(segment
		(start 104.25 126.1)
		(end 90.9 126.1)
		(width 0.155)
		(layer "B.Cu")
		(net 100)
	)
	(segment
		(start 149.075 110.475)
		(end 149.075 112.175)
		(width 0.15)
		(layer "B.Cu")
		(net 100)
	)
	(segment
		(start 87.4 79.5)
		(end 87.4 77.5)
		(width 0.15)
		(layer "B.Cu")
		(net 100)
	)
	(segment
		(start 80.18 84.72)
		(end 80.18 84.46)
		(width 0.15)
		(layer "B.Cu")
		(net 100)
	)
	(segment
		(start 75.31 96.79)
		(end 75.31 93.385)
		(width 0.125)
		(layer "B.Cu")
		(net 100)
	)
	(segment
		(start 90.1 125.3)
		(end 90.1 123.8)
		(width 0.155)
		(layer "B.Cu")
		(net 100)
	)
	(segment
		(start 78.980978 91.234186)
		(end 79.374793 91.628001)
		(width 0.125)
		(layer "B.Cu")
		(net 100)
	)
	(segment
		(start 80.1 80.25)
		(end 86.65 80.25)
		(width 0.15)
		(layer "B.Cu")
		(net 100)
	)
	(segment
		(start 90.9 126.1)
		(end 90.1 125.3)
		(width 0.155)
		(layer "B.Cu")
		(net 100)
	)
	(segment
		(start 90.1 123.8)
		(end 89.9 123.6)
		(width 0.155)
		(layer "B.Cu")
		(net 100)
	)
	(segment
		(start 135.95 128.2)
		(end 135.5 127.75)
		(width 0.15)
		(layer "B.Cu")
		(net 100)
	)
	(segment
		(start 82.1 103.58)
		(end 75.31 96.79)
		(width 0.125)
		(layer "B.Cu")
		(net 100)
	)
	(segment
		(start 80.18 84.46)
		(end 79.2 83.48)
		(width 0.15)
		(layer "B.Cu")
		(net 100)
	)
	(segment
		(start 85.9 116.7)
		(end 85.7 116.5)
		(width 0.125)
		(layer "B.Cu")
		(net 100)
	)
	(segment
		(start 145.765 128.2)
		(end 135.95 128.2)
		(width 0.15)
		(layer "B.Cu")
		(net 100)
	)
	(segment
		(start 135.5 126.45)
		(end 135.2 126.15)
		(width 0.15)
		(layer "B.Cu")
		(net 100)
	)
	(segment
		(start 135.2 126.15)
		(end 120.12 126.15)
		(width 0.15)
		(layer "B.Cu")
		(net 100)
	)
	(segment
		(start 85.7 116.5)
		(end 85.7 112.625)
		(width 0.125)
		(layer "B.Cu")
		(net 100)
	)
	(segment
		(start 120.12 126.15)
		(end 118.89 127.38)
		(width 0.15)
		(layer "B.Cu")
		(net 100)
	)
	(segment
		(start 148.6 125.365)
		(end 145.765 128.2)
		(width 0.15)
		(layer "B.Cu")
		(net 100)
	)
	(segment
		(start 148.6 112.65)
		(end 148.6 125.365)
		(width 0.15)
		(layer "B.Cu")
		(net 100)
	)
	(segment
		(start 79.2 83.48)
		(end 79.2 81.15)
		(width 0.15)
		(layer "B.Cu")
		(net 100)
	)
	(segment
		(start 82.1 109.025)
		(end 82.1 103.58)
		(width 0.125)
		(layer "B.Cu")
		(net 100)
	)
	(segment
		(start 75.31 93.385)
		(end 77.460814 91.234186)
		(width 0.125)
		(layer "B.Cu")
		(net 100)
	)
	(segment
		(start 135.5 127.75)
		(end 135.5 126.45)
		(width 0.15)
		(layer "B.Cu")
		(net 100)
	)
	(segment
		(start 105.53 127.38)
		(end 104.25 126.1)
		(width 0.155)
		(layer "B.Cu")
		(net 100)
	)
	(segment
		(start 118.89 127.38)
		(end 108.42 127.38)
		(width 0.15)
		(layer "B.Cu")
		(net 100)
	)
	(segment
		(start 85.7 112.625)
		(end 82.1 109.025)
		(width 0.125)
		(layer "B.Cu")
		(net 100)
	)
	(segment
		(start 79.2 81.15)
		(end 80.1 80.25)
		(width 0.15)
		(layer "B.Cu")
		(net 100)
	)
	(segment
		(start 87.025 75.2)
		(end 88.097323 74.127677)
		(width 0.15)
		(layer "F.Cu")
		(net 101)
	)
	(segment
		(start 88.097323 74.127677)
		(end 88.097323 72.005136)
		(width 0.15)
		(layer "F.Cu")
		(net 101)
	)
	(segment
		(start 148.485 111.5)
		(end 148.485 112.065)
		(width 0.15)
		(layer "F.Cu")
		(net 101)
	)
	(segment
		(start 148.485 112.065)
		(end 148.45 112.1)
		(width 0.15)
		(layer "F.Cu")
		(net 101)
	)
	(segment
		(start 87.025 76.825)
		(end 87.025 75.2)
		(width 0.15)
		(layer "F.Cu")
		(net 101)
	)
	(via
		(at 90.6 123.6)
		(size 0.45)
		(drill 0.1)
		(layers "F.Cu" "B.Cu")
		(net 101)
	)
	(via
		(at 78.760244 91.659186)
		(size 0.45)
		(drill 0.1)
		(layers "F.Cu" "B.Cu")
		(net 101)
	)
	(via
		(at 86.45 117.05)
		(size 0.45)
		(drill 0.1)
		(layers "F.Cu" "B.Cu")
		(net 101)
	)
	(via
		(at 79.58 84.73)
		(size 0.45)
		(drill 0.1)
		(layers "F.Cu" "B.Cu")
		(net 101)
	)
	(via
		(at 87.025 76.825)
		(size 0.45)
		(drill 0.1)
		(layers "F.Cu" "B.Cu")
		(net 101)
	)
	(via
		(at 148.45 112.1)
		(size 0.45)
		(drill 0.1)
		(layers "F.Cu" "B.Cu")
		(net 101)
	)
	(segment
		(start 90.4 122.2)
		(end 89.3 121.1)
		(width 0.155)
		(layer "In5.Cu")
		(net 101)
	)
	(segment
		(start 87.7 121.1)
		(end 87.3 120.7)
		(width 0.155)
		(layer "In5.Cu")
		(net 101)
	)
	(segment
		(start 89.3 121.1)
		(end 87.7 121.1)
		(width 0.155)
		(layer "In5.Cu")
		(net 101)
	)
	(segment
		(start 87.3 120.7)
		(end 87.3 117.9)
		(width 0.155)
		(layer "In5.Cu")
		(net 101)
	)
	(segment
		(start 90.4 123.4)
		(end 90.4 122.2)
		(width 0.155)
		(layer "In5.Cu")
		(net 101)
	)
	(segment
		(start 79.75 90.66943)
		(end 79.75 84.9)
		(width 0.125)
		(layer "In5.Cu")
		(net 101)
	)
	(segment
		(start 78.760244 91.659186)
		(end 79.75 90.66943)
		(width 0.125)
		(layer "In5.Cu")
		(net 101)
	)
	(segment
		(start 87.3 117.9)
		(end 86.45 117.05)
		(width 0.155)
		(layer "In5.Cu")
		(net 101)
	)
	(segment
		(start 90.6 123.6)
		(end 90.4 123.4)
		(width 0.155)
		(layer "In5.Cu")
		(net 101)
	)
	(segment
		(start 79.75 84.9)
		(end 79.58 84.73)
		(width 0.125)
		(layer "In5.Cu")
		(net 101)
	)
	(segment
		(start 136.05 127.9)
		(end 135.775 127.625)
		(width 0.15)
		(layer "B.Cu")
		(net 101)
	)
	(segment
		(start 78.9 83.62)
		(end 78.9 81)
		(width 0.15)
		(layer "B.Cu")
		(net 101)
	)
	(segment
		(start 82.4 103.47)
		(end 75.615 96.685)
		(width 0.125)
		(layer "B.Cu")
		(net 101)
	)
	(segment
		(start 90.4 125.1)
		(end 90.4 123.8)
		(width 0.155)
		(layer "B.Cu")
		(net 101)
	)
	(segment
		(start 86.5 79.9)
		(end 87.025 79.375)
		(width 0.15)
		(layer "B.Cu")
		(net 101)
	)
	(segment
		(start 91.1 125.8)
		(end 90.4 125.1)
		(width 0.155)
		(layer "B.Cu")
		(net 101)
	)
	(segment
		(start 118.67 127.03)
		(end 108.48 127.03)
		(width 0.15)
		(layer "B.Cu")
		(net 101)
	)
	(segment
		(start 80 79.9)
		(end 86.5 79.9)
		(width 0.15)
		(layer "B.Cu")
		(net 101)
	)
	(segment
		(start 86.45 116.967134)
		(end 86.35 116.867134)
		(width 0.125)
		(layer "B.Cu")
		(net 101)
	)
	(segment
		(start 78.9 81)
		(end 80 79.9)
		(width 0.15)
		(layer "B.Cu")
		(net 101)
	)
	(segment
		(start 108.48 127.03)
		(end 105.63 127.03)
		(width 0.155)
		(layer "B.Cu")
		(net 101)
	)
	(segment
		(start 86.35 116.867134)
		(end 86.35 116.45)
		(width 0.125)
		(layer "B.Cu")
		(net 101)
	)
	(segment
		(start 135.775 127.625)
		(end 135.775 126.336092)
		(width 0.15)
		(layer "B.Cu")
		(net 101)
	)
	(segment
		(start 148.27 112.28)
		(end 148.27 125.225)
		(width 0.15)
		(layer "B.Cu")
		(net 101)
	)
	(segment
		(start 86 116.1)
		(end 86 112.4)
		(width 0.125)
		(layer "B.Cu")
		(net 101)
	)
	(segment
		(start 75.615 96.685)
		(end 75.615 93.505)
		(width 0.125)
		(layer "B.Cu")
		(net 101)
	)
	(segment
		(start 90.4 123.8)
		(end 90.6 123.6)
		(width 0.155)
		(layer "B.Cu")
		(net 101)
	)
	(segment
		(start 87.025 79.375)
		(end 87.025 76.825)
		(width 0.15)
		(layer "B.Cu")
		(net 101)
	)
	(segment
		(start 135.288908 125.85)
		(end 119.85 125.85)
		(width 0.15)
		(layer "B.Cu")
		(net 101)
	)
	(segment
		(start 145.595 127.9)
		(end 136.05 127.9)
		(width 0.15)
		(layer "B.Cu")
		(net 101)
	)
	(segment
		(start 75.615 93.505)
		(end 77.460814 91.659186)
		(width 0.125)
		(layer "B.Cu")
		(net 101)
	)
	(segment
		(start 135.775 126.336092)
		(end 135.288908 125.85)
		(width 0.15)
		(layer "B.Cu")
		(net 101)
	)
	(segment
		(start 119.85 125.85)
		(end 118.67 127.03)
		(width 0.15)
		(layer "B.Cu")
		(net 101)
	)
	(segment
		(start 148.27 125.225)
		(end 145.595 127.9)
		(width 0.15)
		(layer "B.Cu")
		(net 101)
	)
	(segment
		(start 104.4 125.8)
		(end 91.1 125.8)
		(width 0.155)
		(layer "B.Cu")
		(net 101)
	)
	(segment
		(start 105.63 127.03)
		(end 104.4 125.8)
		(width 0.155)
		(layer "B.Cu")
		(net 101)
	)
	(segment
		(start 86.35 116.45)
		(end 86 116.1)
		(width 0.125)
		(layer "B.Cu")
		(net 101)
	)
	(segment
		(start 82.4 108.8)
		(end 82.4 103.47)
		(width 0.125)
		(layer "B.Cu")
		(net 101)
	)
	(segment
		(start 77.460814 91.659186)
		(end 78.760244 91.659186)
		(width 0.125)
		(layer "B.Cu")
		(net 101)
	)
	(segment
		(start 86.45 117.05)
		(end 86.45 116.967134)
		(width 0.125)
		(layer "B.Cu")
		(net 101)
	)
	(segment
		(start 79.58 84.73)
		(end 79.58 84.3)
		(width 0.15)
		(layer "B.Cu")
		(net 101)
	)
	(segment
		(start 148.45 112.1)
		(end 148.27 112.28)
		(width 0.15)
		(layer "B.Cu")
		(net 101)
	)
	(segment
		(start 79.58 84.3)
		(end 78.9 83.62)
		(width 0.15)
		(layer "B.Cu")
		(net 101)
	)
	(segment
		(start 86 112.4)
		(end 82.4 108.8)
		(width 0.125)
		(layer "B.Cu")
		(net 101)
	)
	(segment
		(start 136.45 95.6)
		(end 136.95 95.6)
		(width 0.15)
		(layer "F.Cu")
		(net 102)
	)
	(segment
		(start 72.847323 79.252677)
		(end 72.847323 80.205136)
		(width 0.15)
		(layer "F.Cu")
		(net 102)
	)
	(segment
		(start 73.2 78.9)
		(end 72.847323 79.252677)
		(width 0.15)
		(layer "F.Cu")
		(net 102)
	)
	(segment
		(start 134.95 95.8)
		(end 136.25 95.8)
		(width 0.15)
		(layer "F.Cu")
		(net 102)
	)
	(segment
		(start 134.2 95.25)
		(end 134.4 95.25)
		(width 0.15)
		(layer "F.Cu")
		(net 102)
	)
	(segment
		(start 136.25 95.8)
		(end 136.45 95.6)
		(width 0.15)
		(layer "F.Cu")
		(net 102)
	)
	(segment
		(start 134.4 95.25)
		(end 134.95 95.8)
		(width 0.15)
		(layer "F.Cu")
		(net 102)
	)
	(via
		(at 73.2 78.9)
		(size 0.45)
		(drill 0.1)
		(layers "F.Cu" "B.Cu")
		(net 102)
	)
	(via
		(at 131.5 110.25)
		(size 0.45)
		(drill 0.1)
		(layers "F.Cu" "B.Cu")
		(net 102)
	)
	(via
		(at 70.3 113)
		(size 0.45)
		(drill 0.1)
		(layers "F.Cu" "B.Cu")
		(net 102)
	)
	(via
		(at 65.058564 78.647074)
		(size 0.45)
		(drill 0.1)
		(layers "F.Cu" "B.Cu")
		(net 102)
	)
	(via
		(at 134.2 95.25)
		(size 0.45)
		(drill 0.1)
		(layers "F.Cu" "B.Cu")
		(net 102)
	)
	(segment
		(start 65.675 83.725)
		(end 64.9 84.5)
		(width 0.15)
		(layer "In3.Cu")
		(net 102)
	)
	(segment
		(start 67.025 113.725)
		(end 69.575 113.725)
		(width 0.15)
		(layer "In3.Cu")
		(net 102)
	)
	(segment
		(start 64.9 84.5)
		(end 64.9 86.6)
		(width 0.15)
		(layer "In3.Cu")
		(net 102)
	)
	(segment
		(start 63.6 97.51)
		(end 63 98.11)
		(width 0.15)
		(layer "In3.Cu")
		(net 102)
	)
	(segment
		(start 63 109.7)
		(end 67.025 113.725)
		(width 0.15)
		(layer "In3.Cu")
		(net 102)
	)
	(segment
		(start 63 98.11)
		(end 63 109.7)
		(width 0.15)
		(layer "In3.Cu")
		(net 102)
	)
	(segment
		(start 65.058564 79.208564)
		(end 65.675 79.825)
		(width 0.15)
		(layer "In3.Cu")
		(net 102)
	)
	(segment
		(start 69.575 113.725)
		(end 70.3 113)
		(width 0.15)
		(layer "In3.Cu")
		(net 102)
	)
	(segment
		(start 65.058564 78.647074)
		(end 65.058564 79.208564)
		(width 0.155)
		(layer "In3.Cu")
		(net 102)
	)
	(segment
		(start 63.6 87.9)
		(end 63.6 97.51)
		(width 0.15)
		(layer "In3.Cu")
		(net 102)
	)
	(segment
		(start 65.675 79.825)
		(end 65.675 83.725)
		(width 0.15)
		(layer "In3.Cu")
		(net 102)
	)
	(segment
		(start 64.9 86.6)
		(end 63.6 87.9)
		(width 0.15)
		(layer "In3.Cu")
		(net 102)
	)
	(segment
		(start 118.75 115.85)
		(end 119.1 116.2)
		(width 0.125)
		(layer "In5.Cu")
		(net 102)
	)
	(segment
		(start 70.3 113)
		(end 70.45 112.85)
		(width 0.125)
		(layer "In5.Cu")
		(net 102)
	)
	(segment
		(start 65.7495 78.5495)
		(end 65.156138 78.5495)
		(width 0.15)
		(layer "In5.Cu")
		(net 102)
	)
	(segment
		(start 100.3875 116.45)
		(end 100.9875 115.85)
		(width 0.125)
		(layer "In5.Cu")
		(net 102)
	)
	(segment
		(start 71.7 77.7)
		(end 70.6 77.7)
		(width 0.15)
		(layer "In5.Cu")
		(net 102)
	)
	(segment
		(start 65.156138 78.5495)
		(end 65.058564 78.647074)
		(width 0.15)
		(layer "In5.Cu")
		(net 102)
	)
	(segment
		(start 128 108.9)
		(end 130.15 108.9)
		(width 0.125)
		(layer "In5.Cu")
		(net 102)
	)
	(segment
		(start 70.45 112.85)
		(end 72.15 112.85)
		(width 0.125)
		(layer "In5.Cu")
		(net 102)
	)
	(segment
		(start 70.6 77.7)
		(end 69.5 78.8)
		(width 0.15)
		(layer "In5.Cu")
		(net 102)
	)
	(segment
		(start 119.1 116.2)
		(end 120.7 116.2)
		(width 0.125)
		(layer "In5.Cu")
		(net 102)
	)
	(segment
		(start 93.45 114.4)
		(end 95.5 116.45)
		(width 0.125)
		(layer "In5.Cu")
		(net 102)
	)
	(segment
		(start 86.983318 114.4)
		(end 93.45 114.4)
		(width 0.125)
		(layer "In5.Cu")
		(net 102)
	)
	(segment
		(start 72.9 78.9)
		(end 71.7 77.7)
		(width 0.15)
		(layer "In5.Cu")
		(net 102)
	)
	(segment
		(start 120.7 116.2)
		(end 128 108.9)
		(width 0.125)
		(layer "In5.Cu")
		(net 102)
	)
	(segment
		(start 69.5 78.8)
		(end 66 78.8)
		(width 0.15)
		(layer "In5.Cu")
		(net 102)
	)
	(segment
		(start 73.2 78.9)
		(end 72.9 78.9)
		(width 0.15)
		(layer "In5.Cu")
		(net 102)
	)
	(segment
		(start 95.5 116.45)
		(end 100.3875 116.45)
		(width 0.125)
		(layer "In5.Cu")
		(net 102)
	)
	(segment
		(start 72.15 112.85)
		(end 74.95 115.65)
		(width 0.125)
		(layer "In5.Cu")
		(net 102)
	)
	(segment
		(start 130.15 108.9)
		(end 131.5 110.25)
		(width 0.125)
		(layer "In5.Cu")
		(net 102)
	)
	(segment
		(start 85.733318 115.65)
		(end 86.983318 114.4)
		(width 0.125)
		(layer "In5.Cu")
		(net 102)
	)
	(segment
		(start 74.95 115.65)
		(end 85.733318 115.65)
		(width 0.125)
		(layer "In5.Cu")
		(net 102)
	)
	(segment
		(start 100.9875 115.85)
		(end 118.75 115.85)
		(width 0.125)
		(layer "In5.Cu")
		(net 102)
	)
	(segment
		(start 66 78.8)
		(end 65.7495 78.5495)
		(width 0.15)
		(layer "In5.Cu")
		(net 102)
	)
	(segment
		(start 132.05 97.75)
		(end 132.05 102)
		(width 0.15)
		(layer "B.Cu")
		(net 102)
	)
	(segment
		(start 133.5 105.15)
		(end 132 106.65)
		(width 0.15)
		(layer "B.Cu")
		(net 102)
	)
	(segment
		(start 134.2 95.25)
		(end 133.85 95.6)
		(width 0.15)
		(layer "B.Cu")
		(net 102)
	)
	(segment
		(start 132 106.65)
		(end 132 109.75)
		(width 0.15)
		(layer "B.Cu")
		(net 102)
	)
	(segment
		(start 133.85 95.6)
		(end 133.85 95.95)
		(width 0.15)
		(layer "B.Cu")
		(net 102)
	)
	(segment
		(start 132 109.75)
		(end 131.5 110.25)
		(width 0.15)
		(layer "B.Cu")
		(net 102)
	)
	(segment
		(start 132.05 102)
		(end 133.5 103.45)
		(width 0.15)
		(layer "B.Cu")
		(net 102)
	)
	(segment
		(start 133.5 103.45)
		(end 133.5 105.15)
		(width 0.15)
		(layer "B.Cu")
		(net 102)
	)
	(segment
		(start 133.85 95.95)
		(end 132.05 97.75)
		(width 0.15)
		(layer "B.Cu")
		(net 102)
	)
	(segment
		(start 135.4 94)
		(end 136.95 94)
		(width 0.15)
		(layer "F.Cu")
		(net 103)
	)
	(segment
		(start 134.65 94.75)
		(end 135.4 94)
		(width 0.15)
		(layer "F.Cu")
		(net 103)
	)
	(segment
		(start 69.6 70.95)
		(end 69.597323 70.952677)
		(width 0.15)
		(layer "F.Cu")
		(net 103)
	)
	(segment
		(start 69.6 70)
		(end 69.6 70.95)
		(width 0.15)
		(layer "F.Cu")
		(net 103)
	)
	(segment
		(start 69.597323 70.952677)
		(end 69.597323 72.005136)
		(width 0.15)
		(layer "F.Cu")
		(net 103)
	)
	(via
		(at 69.6 70)
		(size 0.45)
		(drill 0.1)
		(layers "F.Cu" "B.Cu")
		(net 103)
	)
	(via
		(at 134.65 94.75)
		(size 0.45)
		(drill 0.1)
		(layers "F.Cu" "B.Cu")
		(net 103)
	)
	(via
		(at 136.09 103.89)
		(size 0.45)
		(drill 0.1)
		(layers "F.Cu" "B.Cu")
		(net 103)
	)
	(segment
		(start 69.6 70)
		(end 69.6 70.65)
		(width 0.125)
		(layer "In5.Cu")
		(net 103)
	)
	(segment
		(start 91.8 83.2)
		(end 92.35 83.75)
		(width 0.125)
		(layer "In5.Cu")
		(net 103)
	)
	(segment
		(start 72.33 70.95)
		(end 74.29 72.91)
		(width 0.125)
		(layer "In5.Cu")
		(net 103)
	)
	(segment
		(start 93.14 98.54)
		(end 93.14 103.64)
		(width 0.125)
		(layer "In5.Cu")
		(net 103)
	)
	(segment
		(start 69.6 70.65)
		(end 69.9 70.95)
		(width 0.125)
		(layer "In5.Cu")
		(net 103)
	)
	(segment
		(start 79.7 83.2)
		(end 91.8 83.2)
		(width 0.125)
		(layer "In5.Cu")
		(net 103)
	)
	(segment
		(start 92.35 83.75)
		(end 92.35 97.75)
		(width 0.125)
		(layer "In5.Cu")
		(net 103)
	)
	(segment
		(start 74.29 72.91)
		(end 74.29 77.843554)
		(width 0.125)
		(layer "In5.Cu")
		(net 103)
	)
	(segment
		(start 79 82.5)
		(end 79.7 83.2)
		(width 0.125)
		(layer "In5.Cu")
		(net 103)
	)
	(segment
		(start 74.29 77.843554)
		(end 76.026446 79.58)
		(width 0.125)
		(layer "In5.Cu")
		(net 103)
	)
	(segment
		(start 133.36 106.23)
		(end 135.7 103.89)
		(width 0.125)
		(layer "In5.Cu")
		(net 103)
	)
	(segment
		(start 135.7 103.89)
		(end 136.09 103.89)
		(width 0.125)
		(layer "In5.Cu")
		(net 103)
	)
	(segment
		(start 123.41 109.85)
		(end 127.03 106.23)
		(width 0.125)
		(layer "In5.Cu")
		(net 103)
	)
	(segment
		(start 69.9 70.95)
		(end 72.33 70.95)
		(width 0.125)
		(layer "In5.Cu")
		(net 103)
	)
	(segment
		(start 99.35 109.85)
		(end 123.41 109.85)
		(width 0.125)
		(layer "In5.Cu")
		(net 103)
	)
	(segment
		(start 78.28 79.58)
		(end 79 80.3)
		(width 0.125)
		(layer "In5.Cu")
		(net 103)
	)
	(segment
		(start 76.026446 79.58)
		(end 78.28 79.58)
		(width 0.125)
		(layer "In5.Cu")
		(net 103)
	)
	(segment
		(start 79 80.3)
		(end 79 82.5)
		(width 0.125)
		(layer "In5.Cu")
		(net 103)
	)
	(segment
		(start 92.35 97.75)
		(end 93.14 98.54)
		(width 0.125)
		(layer "In5.Cu")
		(net 103)
	)
	(segment
		(start 93.14 103.64)
		(end 99.35 109.85)
		(width 0.125)
		(layer "In5.Cu")
		(net 103)
	)
	(segment
		(start 127.03 106.23)
		(end 133.36 106.23)
		(width 0.125)
		(layer "In5.Cu")
		(net 103)
	)
	(segment
		(start 135.53 95.98)
		(end 133.25 98.26)
		(width 0.15)
		(layer "B.Cu")
		(net 103)
	)
	(segment
		(start 133.25 98.26)
		(end 133.25 101.48)
		(width 0.15)
		(layer "B.Cu")
		(net 103)
	)
	(segment
		(start 133.25 101.48)
		(end 135.66 103.89)
		(width 0.15)
		(layer "B.Cu")
		(net 103)
	)
	(segment
		(start 134.672794 94.727206)
		(end 135.277206 94.727206)
		(width 0.15)
		(layer "B.Cu")
		(net 103)
	)
	(segment
		(start 135.53 94.98)
		(end 135.277206 94.727206)
		(width 0.15)
		(layer "B.Cu")
		(net 103)
	)
	(segment
		(start 135.53 95.98)
		(end 135.53 94.98)
		(width 0.15)
		(layer "B.Cu")
		(net 103)
	)
	(segment
		(start 134.65 94.75)
		(end 134.672794 94.727206)
		(width 0.15)
		(layer "B.Cu")
		(net 103)
	)
	(segment
		(start 135.66 103.89)
		(end 136.09 103.89)
		(width 0.15)
		(layer "B.Cu")
		(net 103)
	)
	(segment
		(start 135.97 94.53)
		(end 136.95 94.53)
		(width 0.15)
		(layer "F.Cu")
		(net 104)
	)
	(segment
		(start 69.1 69.6)
		(end 69.1 70.88)
		(width 0.15)
		(layer "F.Cu")
		(net 104)
	)
	(segment
		(start 69.1 70.88)
		(end 69.097323 70.882677)
		(width 0.15)
		(layer "F.Cu")
		(net 104)
	)
	(segment
		(start 69.097323 70.882677)
		(end 69.097323 72.005136)
		(width 0.15)
		(layer "F.Cu")
		(net 104)
	)
	(segment
		(start 135.250167 95.249833)
		(end 135.97 94.53)
		(width 0.15)
		(layer "F.Cu")
		(net 104)
	)
	(segment
		(start 135.000167 95.249833)
		(end 135.250167 95.249833)
		(width 0.15)
		(layer "F.Cu")
		(net 104)
	)
	(via
		(at 136.77 103.9)
		(size 0.45)
		(drill 0.1)
		(layers "F.Cu" "B.Cu")
		(net 104)
	)
	(via
		(at 69.1 69.6)
		(size 0.45)
		(drill 0.1)
		(layers "F.Cu" "B.Cu")
		(net 104)
	)
	(via
		(at 135.000167 95.249833)
		(size 0.45)
		(drill 0.1)
		(layers "F.Cu" "B.Cu")
		(net 104)
	)
	(segment
		(start 91.5 83.5)
		(end 92.1 84.1)
		(width 0.125)
		(layer "In5.Cu")
		(net 104)
	)
	(segment
		(start 69.1 71.1)
		(end 69.25 71.25)
		(width 0.125)
		(layer "In5.Cu")
		(net 104)
	)
	(segment
		(start 136.74 103.9)
		(end 136.77 103.9)
		(width 0.125)
		(layer "In5.Cu")
		(net 104)
	)
	(segment
		(start 135.73 104.38)
		(end 136.26 104.38)
		(width 0.125)
		(layer "In5.Cu")
		(net 104)
	)
	(segment
		(start 78.7 82.6)
		(end 79.6 83.5)
		(width 0.125)
		(layer "In5.Cu")
		(net 104)
	)
	(segment
		(start 127.14 106.55)
		(end 133.56 106.55)
		(width 0.125)
		(layer "In5.Cu")
		(net 104)
	)
	(segment
		(start 78.7 80.4)
		(end 78.7 82.6)
		(width 0.125)
		(layer "In5.Cu")
		(net 104)
	)
	(segment
		(start 92.1 84.1)
		(end 92.1 97.87)
		(width 0.125)
		(layer "In5.Cu")
		(net 104)
	)
	(segment
		(start 74 73.149665)
		(end 74 78)
		(width 0.125)
		(layer "In5.Cu")
		(net 104)
	)
	(segment
		(start 74 78)
		(end 75.86 79.86)
		(width 0.125)
		(layer "In5.Cu")
		(net 104)
	)
	(segment
		(start 136.26 104.38)
		(end 136.74 103.9)
		(width 0.125)
		(layer "In5.Cu")
		(net 104)
	)
	(segment
		(start 72.100335 71.25)
		(end 74 73.149665)
		(width 0.125)
		(layer "In5.Cu")
		(net 104)
	)
	(segment
		(start 92.1 97.87)
		(end 92.89 98.66)
		(width 0.125)
		(layer "In5.Cu")
		(net 104)
	)
	(segment
		(start 69.25 71.25)
		(end 72.100335 71.25)
		(width 0.125)
		(layer "In5.Cu")
		(net 104)
	)
	(segment
		(start 92.89 98.66)
		(end 92.89 103.82)
		(width 0.125)
		(layer "In5.Cu")
		(net 104)
	)
	(segment
		(start 133.56 106.55)
		(end 135.73 104.38)
		(width 0.125)
		(layer "In5.Cu")
		(net 104)
	)
	(segment
		(start 92.89 103.82)
		(end 99.22 110.15)
		(width 0.125)
		(layer "In5.Cu")
		(net 104)
	)
	(segment
		(start 123.54 110.15)
		(end 127.14 106.55)
		(width 0.125)
		(layer "In5.Cu")
		(net 104)
	)
	(segment
		(start 99.22 110.15)
		(end 123.54 110.15)
		(width 0.125)
		(layer "In5.Cu")
		(net 104)
	)
	(segment
		(start 78.16 79.86)
		(end 78.7 80.4)
		(width 0.125)
		(layer "In5.Cu")
		(net 104)
	)
	(segment
		(start 75.86 79.86)
		(end 78.16 79.86)
		(width 0.125)
		(layer "In5.Cu")
		(net 104)
	)
	(segment
		(start 69.1 69.6)
		(end 69.1 71.1)
		(width 0.125)
		(layer "In5.Cu")
		(net 104)
	)
	(segment
		(start 79.6 83.5)
		(end 91.5 83.5)
		(width 0.125)
		(layer "In5.Cu")
		(net 104)
	)
	(segment
		(start 135.000167 95.899833)
		(end 132.85 98.05)
		(width 0.15)
		(layer "B.Cu")
		(net 104)
	)
	(segment
		(start 132.85 101.64)
		(end 135.56 104.35)
		(width 0.15)
		(layer "B.Cu")
		(net 104)
	)
	(segment
		(start 136.3 104.35)
		(end 136.75 103.9)
		(width 0.15)
		(layer "B.Cu")
		(net 104)
	)
	(segment
		(start 136.75 103.9)
		(end 136.77 103.9)
		(width 0.15)
		(layer "B.Cu")
		(net 104)
	)
	(segment
		(start 135.56 104.35)
		(end 136.3 104.35)
		(width 0.15)
		(layer "B.Cu")
		(net 104)
	)
	(segment
		(start 135.000167 95.249833)
		(end 135.000167 95.899833)
		(width 0.15)
		(layer "B.Cu")
		(net 104)
	)
	(segment
		(start 132.85 98.05)
		(end 132.85 101.64)
		(width 0.15)
		(layer "B.Cu")
		(net 104)
	)
	(segment
		(start 37.715 104.7)
		(end 36.9 104.7)
		(width 0.15)
		(layer "F.Cu")
		(net 105)
	)
	(segment
		(start 37.715 103.7)
		(end 36.9 103.7)
		(width 0.15)
		(layer "F.Cu")
		(net 105)
	)
	(via
		(at 36.4 104.2)
		(size 0.45)
		(drill 0.1)
		(layers "F.Cu" "B.Cu")
		(free yes)
		(net 105)
	)
	(via
		(at 35.2 101.8)
		(size 0.45)
		(drill 0.1)
		(layers "F.Cu" "B.Cu")
		(free yes)
		(net 105)
	)
	(via
		(at 34 104.2)
		(size 0.45)
		(drill 0.1)
		(layers "F.Cu" "B.Cu")
		(free yes)
		(net 105)
	)
	(via
		(at 53.05 90.25)
		(size 0.45)
		(drill 0.1)
		(layers "F.Cu" "B.Cu")
		(free yes)
		(net 105)
	)
	(via
		(at 35.2 103)
		(size 0.45)
		(drill 0.1)
		(layers "F.Cu" "B.Cu")
		(free yes)
		(net 105)
	)
	(via
		(at 36.4 103)
		(size 0.45)
		(drill 0.1)
		(layers "F.Cu" "B.Cu")
		(free yes)
		(net 105)
	)
	(via
		(at 34 103)
		(size 0.45)
		(drill 0.1)
		(layers "F.Cu" "B.Cu")
		(free yes)
		(net 105)
	)
	(via
		(at 36.4 101.8)
		(size 0.45)
		(drill 0.1)
		(layers "F.Cu" "B.Cu")
		(free yes)
		(net 105)
	)
	(via
		(at 53.51 89.35)
		(size 0.45)
		(drill 0.1)
		(layers "F.Cu" "B.Cu")
		(free yes)
		(net 105)
	)
	(via
		(at 35.2 104.2)
		(size 0.45)
		(drill 0.1)
		(layers "F.Cu" "B.Cu")
		(free yes)
		(net 105)
	)
	(via
		(at 53.51 89.95)
		(size 0.45)
		(drill 0.1)
		(layers "F.Cu" "B.Cu")
		(free yes)
		(net 105)
	)
	(via
		(at 53.05 89.65)
		(size 0.45)
		(drill 0.1)
		(layers "F.Cu" "B.Cu")
		(free yes)
		(net 105)
	)
	(via
		(at 53.5 90.55)
		(size 0.45)
		(drill 0.1)
		(layers "F.Cu" "B.Cu")
		(free yes)
		(net 105)
	)
	(via
		(at 34 101.8)
		(size 0.45)
		(drill 0.1)
		(layers "F.Cu" "B.Cu")
		(free yes)
		(net 105)
	)
	(segment
		(start 42.759 103.7)
		(end 42.6 103.541)
		(width 0.15)
		(layer "F.Cu")
		(net 106)
	)
	(segment
		(start 33.55 95.225)
		(end 30.775 98)
		(width 0.15)
		(layer "F.Cu")
		(net 106)
	)
	(segment
		(start 34.775 95.225)
		(end 33.55 95.225)
		(width 0.15)
		(layer "F.Cu")
		(net 106)
	)
	(segment
		(start 30.775 98)
		(end 30.775 104.325)
		(width 0.15)
		(layer "F.Cu")
		(net 106)
	)
	(segment
		(start 44.861 103.909)
		(end 49.32 99.45)
		(width 0.2)
		(layer "F.Cu")
		(net 106)
	)
	(segment
		(start 42.595 103.541)
		(end 43.768 103.541)
		(width 0.15)
		(layer "F.Cu")
		(net 106)
	)
	(segment
		(start 42.759 104.685)
		(end 42.759 103.7)
		(width 0.15)
		(layer "F.Cu")
		(net 106)
	)
	(segment
		(start 43.768 103.541)
		(end 44.141 103.914)
		(width 0.15)
		(layer "F.Cu")
		(net 106)
	)
	(segment
		(start 44.861 103.909)
		(end 44.141 103.909)
		(width 0.2)
		(layer "F.Cu")
		(net 106)
	)
	(via
		(at 34.775 95.225)
		(size 0.45)
		(drill 0.1)
		(layers "F.Cu" "B.Cu")
		(net 106)
	)
	(via
		(at 56.4 100.15)
		(size 0.45)
		(drill 0.1)
		(layers "F.Cu" "B.Cu")
		(net 106)
	)
	(segment
		(start 56.4 100.15)
		(end 55.741145 99.491145)
		(width 0.15)
		(layer "In5.Cu")
		(net 106)
	)
	(segment
		(start 55.741145 99.491145)
		(end 49.287 99.491145)
		(width 0.15)
		(layer "In5.Cu")
		(net 106)
	)
	(segment
		(start 56.4 100.15)
		(end 56.33 100.22)
		(width 0.15)
		(layer "B.Cu")
		(net 106)
	)
	(segment
		(start 56.33 100.22)
		(end 54.4 100.22)
		(width 0.15)
		(layer "B.Cu")
		(net 106)
	)
	(segment
		(start 144.4755 93.0775)
		(end 144.328 93.225)
		(width 0.155)
		(layer "F.Cu")
		(net 107)
	)
	(segment
		(start 145.038074 92.2005)
		(end 144.4755 92.763074)
		(width 0.155)
		(layer "F.Cu")
		(net 107)
	)
	(segment
		(start 116.597323 70.477)
		(end 116.644323 70.43)
		(width 0.155)
		(layer "F.Cu")
		(net 107)
	)
	(segment
		(start 116.597323 72.005136)
		(end 116.597323 70.477)
		(width 0.155)
		(layer "F.Cu")
		(net 107)
	)
	(segment
		(start 144.4755 92.763074)
		(end 144.4755 93.0775)
		(width 0.155)
		(layer "F.Cu")
		(net 107)
	)
	(segment
		(start 145.4495 92.2005)
		(end 145.038074 92.2005)
		(width 0.155)
		(layer "F.Cu")
		(net 107)
	)
	(segment
		(start 145.7 91.95)
		(end 145.4495 92.2005)
		(width 0.155)
		(layer "F.Cu")
		(net 107)
	)
	(via
		(at 144.328 93.225)
		(size 0.45)
		(drill 0.1)
		(layers "F.Cu" "B.Cu")
		(net 107)
	)
	(via
		(at 116.644323 70.43)
		(size 0.45)
		(drill 0.1)
		(layers "F.Cu" "B.Cu")
		(net 107)
	)
	(segment
		(start 133.238282 75.699)
		(end 136.563282 75.699)
		(width 0.16)
		(layer "In5.Cu")
		(net 107)
	)
	(segment
		(start 141.682825 80.818543)
		(end 144.101 83.236718)
		(width 0.16)
		(layer "In5.Cu")
		(net 107)
	)
	(segment
		(start 141.387452 80.831074)
		(end 141.399982 80.818543)
		(width 0.16)
		(layer "In5.Cu")
		(net 107)
	)
	(segment
		(start 141.11714 80.535702)
		(end 141.117141 80.535701)
		(width 0.16)
		(layer "In5.Cu")
		(net 107)
	)
	(segment
		(start 116.496323 70.282)
		(end 116.496323 70.174395)
		(width 0.16)
		(layer "In5.Cu")
		(net 107)
	)
	(segment
		(start 116.796718 69.874)
		(end 123.096718 69.874)
		(width 0.16)
		(layer "In5.Cu")
		(net 107)
	)
	(segment
		(start 123.301718 69.669)
		(end 124.478282 69.669)
		(width 0.16)
		(layer "In5.Cu")
		(net 107)
	)
	(segment
		(start 141.387453 80.831073)
		(end 141.387452 80.831074)
		(width 0.16)
		(layer "In5.Cu")
		(net 107)
	)
	(segment
		(start 124.783282 69.974)
		(end 127.513282 69.974)
		(width 0.16)
		(layer "In5.Cu")
		(net 107)
	)
	(segment
		(start 144.476 92.911718)
		(end 144.476 93.077)
		(width 0.16)
		(layer "In5.Cu")
		(net 107)
	)
	(segment
		(start 116.644323 70.43)
		(end 116.496323 70.282)
		(width 0.16)
		(layer "In5.Cu")
		(net 107)
	)
	(segment
		(start 127.513282 69.974)
		(end 133.238282 75.699)
		(width 0.16)
		(layer "In5.Cu")
		(net 107)
	)
	(segment
		(start 136.563282 75.699)
		(end 141.117141 80.252859)
		(width 0.16)
		(layer "In5.Cu")
		(net 107)
	)
	(segment
		(start 144.101 83.236718)
		(end 144.101 92.536718)
		(width 0.16)
		(layer "In5.Cu")
		(net 107)
	)
	(segment
		(start 141.682824 80.818543)
		(end 141.682825 80.818543)
		(width 0.16)
		(layer "In5.Cu")
		(net 107)
	)
	(segment
		(start 141.10461 80.831073)
		(end 141.10461 80.831074)
		(width 0.16)
		(layer "In5.Cu")
		(net 107)
	)
	(segment
		(start 144.101 92.536718)
		(end 144.476 92.911718)
		(width 0.16)
		(layer "In5.Cu")
		(net 107)
	)
	(segment
		(start 124.478282 69.669)
		(end 124.783282 69.974)
		(width 0.16)
		(layer "In5.Cu")
		(net 107)
	)
	(segment
		(start 116.496323 70.174395)
		(end 116.796718 69.874)
		(width 0.16)
		(layer "In5.Cu")
		(net 107)
	)
	(segment
		(start 144.476 93.077)
		(end 144.328 93.225)
		(width 0.16)
		(layer "In5.Cu")
		(net 107)
	)
	(segment
		(start 123.096718 69.874)
		(end 123.301718 69.669)
		(width 0.16)
		(layer "In5.Cu")
		(net 107)
	)
	(segment
		(start 141.117141 80.535701)
		(end 141.10461 80.548231)
		(width 0.16)
		(layer "In5.Cu")
		(net 107)
	)
	(arc
		(start 141.10461 80.831074)
		(mid 141.246032 80.889652)
		(end 141.387453 80.831073)
		(width 0.16)
		(layer "In5.Cu")
		(net 107)
	)
	(arc
		(start 141.117141 80.252859)
		(mid 141.175719 80.394281)
		(end 141.11714 80.535702)
		(width 0.16)
		(layer "In5.Cu")
		(net 107)
	)
	(arc
		(start 141.399982 80.818543)
		(mid 141.541403 80.759965)
		(end 141.682824 80.818543)
		(width 0.16)
		(layer "In5.Cu")
		(net 107)
	)
	(arc
		(start 141.10461 80.548231)
		(mid 141.046032 80.689652)
		(end 141.10461 80.831073)
		(width 0.16)
		(layer "In5.Cu")
		(net 107)
	)
	(segment
		(start 116.65 70.435677)
		(end 116.644323 70.43)
		(width 0.155)
		(layer "B.Cu")
		(net 107)
	)
	(segment
		(start 116.65 71.1)
		(end 116.65 70.675677)
		(width 0.155)
		(layer "B.Cu")
		(net 107)
	)
	(segment
		(start 116.65 70.675677)
		(end 116.65 70.435677)
		(width 0.155)
		(layer "B.Cu")
		(net 107)
	)
	(segment
		(start 116.65 70.675677)
		(end 116.644323 70.67)
		(width 0.155)
		(layer "B.Cu")
		(net 107)
	)
	(segment
		(start 131.1 118.6)
		(end 131.1 114.65)
		(width 0.15)
		(layer "B.Cu")
		(net 108)
	)
	(segment
		(start 131.5 114.25)
		(end 132.4 114.25)
		(width 0.15)
		(layer "B.Cu")
		(net 108)
	)
	(segment
		(start 132.3 119.8)
		(end 131.1 118.6)
		(width 0.15)
		(layer "B.Cu")
		(net 108)
	)
	(segment
		(start 138.7 119.8)
		(end 132.3 119.8)
		(width 0.15)
		(layer "B.Cu")
		(net 108)
	)
	(segment
		(start 141.515 114)
		(end 141.515 116.985)
		(width 0.15)
		(layer "B.Cu")
		(net 108)
	)
	(segment
		(start 132.4 114.25)
		(end 132.952 113.698)
		(width 0.15)
		(layer "B.Cu")
		(net 108)
	)
	(segment
		(start 131.1 114.65)
		(end 131.5 114.25)
		(width 0.15)
		(layer "B.Cu")
		(net 108)
	)
	(segment
		(start 132.952 112.7)
		(end 132.95 112.7)
		(width 0.15)
		(layer "B.Cu")
		(net 108)
	)
	(segment
		(start 132.952 113.698)
		(end 132.952 112.7)
		(width 0.15)
		(layer "B.Cu")
		(net 108)
	)
	(segment
		(start 141.515 116.985)
		(end 138.7 119.8)
		(width 0.15)
		(layer "B.Cu")
		(net 108)
	)
	(segment
		(start 140.35 111.2)
		(end 136.55 111.2)
		(width 0.15)
		(layer "B.Cu")
		(net 109)
	)
	(segment
		(start 141.515 112.4)
		(end 141.515 112.365)
		(width 0.15)
		(layer "B.Cu")
		(net 109)
	)
	(segment
		(start 141.515 112.365)
		(end 140.35 111.2)
		(width 0.15)
		(layer "B.Cu")
		(net 109)
	)
	(segment
		(start 92.85 78.4)
		(end 94.95 76.3)
		(width 0.5)
		(layer "B.Cu")
		(net 110)
	)
	(segment
		(start 92.85 80.4)
		(end 92.85 78.4)
		(width 0.5)
		(layer "B.Cu")
		(net 110)
	)
	(segment
		(start 99.085 75.875)
		(end 99.085 75.25)
		(width 0.5)
		(layer "B.Cu")
		(net 110)
	)
	(segment
		(start 101.2 72.6)
		(end 100.2 72.6)
		(width 0.15)
		(layer "B.Cu")
		(net 110)
	)
	(segment
		(start 94.95 76.3)
		(end 97 76.3)
		(width 0.5)
		(layer "B.Cu")
		(net 110)
	)
	(segment
		(start 100.2 72.6)
		(end 100.005 72.795)
		(width 0.15)
		(layer "B.Cu")
		(net 110)
	)
	(segment
		(start 101.35 74.235)
		(end 101.35 72.75)
		(width 0.15)
		(layer "B.Cu")
		(net 110)
	)
	(segment
		(start 97.25 76.55)
		(end 98.41 76.55)
		(width 0.5)
		(layer "B.Cu")
		(net 110)
	)
	(segment
		(start 102.215 75.1)
		(end 101.35 74.235)
		(width 0.15)
		(layer "B.Cu")
		(net 110)
	)
	(segment
		(start 101.35 72.75)
		(end 101.2 72.6)
		(width 0.15)
		(layer "B.Cu")
		(net 110)
	)
	(segment
		(start 100.005 72.795)
		(end 100.005 73.55)
		(width 0.15)
		(layer "B.Cu")
		(net 110)
	)
	(segment
		(start 98.41 76.55)
		(end 99.085 75.875)
		(width 0.5)
		(layer "B.Cu")
		(net 110)
	)
	(segment
		(start 102.215 75.7)
		(end 102.215 75.1)
		(width 0.15)
		(layer "B.Cu")
		(net 110)
	)
	(segment
		(start 97 76.3)
		(end 97.25 76.55)
		(width 0.5)
		(layer "B.Cu")
		(net 110)
	)
	(segment
		(start 100.97 76.78)
		(end 100.97 75.25)
		(width 0.5)
		(layer "B.Cu")
		(net 111)
	)
	(segment
		(start 96.55 80.4)
		(end 96.55 78.15)
		(width 0.5)
		(layer "B.Cu")
		(net 111)
	)
	(segment
		(start 96.55 78.15)
		(end 96.9 77.8)
		(width 0.5)
		(layer "B.Cu")
		(net 111)
	)
	(segment
		(start 99.95 77.8)
		(end 100.97 76.78)
		(width 0.5)
		(layer "B.Cu")
		(net 111)
	)
	(segment
		(start 102.215 76.7)
		(end 101 76.7)
		(width 0.15)
		(layer "B.Cu")
		(net 111)
	)
	(segment
		(start 96.9 77.8)
		(end 99.95 77.8)
		(width 0.5)
		(layer "B.Cu")
		(net 111)
	)
	(segment
		(start 56.605 104.85)
		(end 58.035 104.85)
		(width 0.155)
		(layer "F.Cu")
		(net 112)
	)
	(segment
		(start 136.5 111.8)
		(end 135.85 111.8)
		(width 0.15)
		(layer "F.Cu")
		(net 112)
	)
	(segment
		(start 58.15 104.1245)
		(end 58.16 104.1345)
		(width 0.155)
		(layer "F.Cu")
		(net 112)
	)
	(segment
		(start 58.16 104.1345)
		(end 58.16 104.725)
		(width 0.155)
		(layer "F.Cu")
		(net 112)
	)
	(segment
		(start 135.55 112.1)
		(end 135.55 112.5)
		(width 0.15)
		(layer "F.Cu")
		(net 112)
	)
	(segment
		(start 104.85 90.95)
		(end 104.85 91.8)
		(width 0.15)
		(layer "F.Cu")
		(net 112)
	)
	(segment
		(start 135.85 111.8)
		(end 135.55 112.1)
		(width 0.15)
		(layer "F.Cu")
		(net 112)
	)
	(segment
		(start 96.531153 98.999485)
		(end 96.531153 98.653847)
		(width 0.3)
		(layer "F.Cu")
		(net 112)
	)
	(segment
		(start 99.75 116)
		(end 100.05 115.7)
		(width 0.125)
		(layer "F.Cu")
		(net 112)
	)
	(segment
		(start 102.95 90.285)
		(end 101.985 90.285)
		(width 0.15)
		(layer "F.Cu")
		(net 112)
	)
	(segment
		(start 96.531153 98.653847)
		(end 97.135 98.05)
		(width 0.3)
		(layer "F.Cu")
		(net 112)
	)
	(segment
		(start 100.05 115.135)
		(end 99.05 115.135)
		(width 0.125)
		(layer "F.Cu")
		(net 112)
	)
	(segment
		(start 100.05 115.7)
		(end 100.05 115.135)
		(width 0.125)
		(layer "F.Cu")
		(net 112)
	)
	(segment
		(start 135.55 112.5)
		(end 135.85 112.8)
		(width 0.15)
		(layer "F.Cu")
		(net 112)
	)
	(segment
		(start 58.035 104.85)
		(end 58.16 104.725)
		(width 0.155)
		(layer "F.Cu")
		(net 112)
	)
	(segment
		(start 104.85 91.8)
		(end 105.5 92.45)
		(width 0.15)
		(layer "F.Cu")
		(net 112)
	)
	(segment
		(start 105.5 100.05)
		(end 106.585 101.135)
		(width 0.15)
		(layer "F.Cu")
		(net 112)
	)
	(segment
		(start 104.185 90.285)
		(end 102.95 90.285)
		(width 0.15)
		(layer "F.Cu")
		(net 112)
	)
	(segment
		(start 105.5 92.45)
		(end 105.5 100.05)
		(width 0.15)
		(layer "F.Cu")
		(net 112)
	)
	(segment
		(start 101.985 90.285)
		(end 101.95 90.25)
		(width 0.15)
		(layer "F.Cu")
		(net 112)
	)
	(segment
		(start 104.85 90.95)
		(end 104.185 90.285)
		(width 0.15)
		(layer "F.Cu")
		(net 112)
	)
	(via
		(at 138.725 100.94)
		(size 0.45)
		(drill 0.1)
		(layers "F.Cu" "B.Cu")
		(net 112)
	)
	(via
		(at 88.5 115.25)
		(size 0.45)
		(drill 0.1)
		(layers "F.Cu" "B.Cu")
		(net 112)
	)
	(via
		(at 135.85 112.8)
		(size 0.45)
		(drill 0.1)
		(layers "F.Cu" "B.Cu")
		(net 112)
	)
	(via
		(at 64.874499 81.856212)
		(size 0.45)
		(drill 0.1)
		(layers "F.Cu" "B.Cu")
		(net 112)
	)
	(via
		(at 106.585 101.135)
		(size 0.45)
		(drill 0.1)
		(layers "F.Cu" "B.Cu")
		(net 112)
	)
	(via
		(at 99.75 116)
		(size 0.45)
		(drill 0.1)
		(layers "F.Cu" "B.Cu")
		(net 112)
	)
	(via
		(at 58.15 104.1245)
		(size 0.45)
		(drill 0.1)
		(layers "F.Cu" "B.Cu")
		(net 112)
	)
	(via
		(at 65.61 85.68)
		(size 0.45)
		(drill 0.1)
		(layers "F.Cu" "B.Cu")
		(net 112)
	)
	(via
		(at 80.065 117.91)
		(size 0.45)
		(drill 0.1)
		(layers "F.Cu" "B.Cu")
		(net 112)
	)
	(via
		(at 96.531153 98.999485)
		(size 0.45)
		(drill 0.1)
		(layers "F.Cu" "B.Cu")
		(net 112)
	)
	(via
		(at 104.1 103.6)
		(size 0.45)
		(drill 0.1)
		(layers "F.Cu" "B.Cu")
		(net 112)
	)
	(segment
		(start 65.56 85.63)
		(end 65.61 85.68)
		(width 0.15)
		(layer "In2.Cu")
		(net 112)
	)
	(segment
		(start 67.9 109.7)
		(end 68.4 110.2)
		(width 0.3)
		(layer "In2.Cu")
		(net 112)
	)
	(segment
		(start 62.94 88.05)
		(end 62.94 90.875)
		(width 0.3)
		(layer "In2.Cu")
		(net 112)
	)
	(segment
		(start 64.874499 81.856212)
		(end 64.886212 81.856212)
		(width 0.15)
		(layer "In2.Cu")
		(net 112)
	)
	(segment
		(start 88.3 116)
		(end 88.5 115.8)
		(width 0.3)
		(layer "In2.Cu")
		(net 112)
	)
	(segment
		(start 104.19 103.69)
		(end 104.1 103.6)
		(width 0.3)
		(layer "In2.Cu")
		(net 112)
	)
	(segment
		(start 88.1 116)
		(end 88.3 116)
		(width 0.3)
		(layer "In2.Cu")
		(net 112)
	)
	(segment
		(start 88.1 116)
		(end 88.5 116)
		(width 0.3)
		(layer "In2.Cu")
		(net 112)
	)
	(segment
		(start 68.4 110.2)
		(end 68.4 114.1)
		(width 0.3)
		(layer "In2.Cu")
		(net 112)
	)
	(segment
		(start 65.56 82.53)
		(end 65.56 85.63)
		(width 0.15)
		(layer "In2.Cu")
		(net 112)
	)
	(segment
		(start 88.1 116)
		(end 80.065 116)
		(width 0.3)
		(layer "In2.Cu")
		(net 112)
	)
	(segment
		(start 88.5 116)
		(end 88.5 115.8)
		(width 0.3)
		(layer "In2.Cu")
		(net 112)
	)
	(segment
		(start 138.725 109.925)
		(end 138.725 100.94)
		(width 0.3)
		(layer "In2.Cu")
		(net 112)
	)
	(segment
		(start 70.65 115.85)
		(end 75.25 115.85)
		(width 0.3)
		(layer "In2.Cu")
		(net 112)
	)
	(segment
		(start 98.35 99.1)
		(end 102.85 103.6)
		(width 0.3)
		(layer "In2.Cu")
		(net 112)
	)
	(segment
		(start 69.3 114.5)
		(end 70.65 115.85)
		(width 0.3)
		(layer "In2.Cu")
		(net 112)
	)
	(segment
		(start 62.94 90.875)
		(end 61.767893 90.875)
		(width 0.3)
		(layer "In2.Cu")
		(net 112)
	)
	(segment
		(start 96.531153 98.999485)
		(end 96.631668 99.1)
		(width 0.3)
		(layer "In2.Cu")
		(net 112)
	)
	(segment
		(start 68.8 114.5)
		(end 69.3 114.5)
		(width 0.3)
		(layer "In2.Cu")
		(net 112)
	)
	(segment
		(start 99.75 116)
		(end 114.207107 116)
		(width 0.3)
		(layer "In2.Cu")
		(net 112)
	)
	(segment
		(start 75.25 115.85)
		(end 75.4 116)
		(width 0.3)
		(layer "In2.Cu")
		(net 112)
	)
	(segment
		(start 56.25 92.05)
		(end 57.03 92.83)
		(width 0.3)
		(layer "In2.Cu")
		(net 112)
	)
	(segment
		(start 135.85 112.8)
		(end 138.725 109.925)
		(width 0.3)
		(layer "In2.Cu")
		(net 112)
	)
	(segment
		(start 62.94 90.875)
		(end 62.94 107.94)
		(width 0.3)
		(layer "In2.Cu")
		(net 112)
	)
	(segment
		(start 57.03 92.83)
		(end 57.03 98.016397)
		(width 0.3)
		(layer "In2.Cu")
		(net 112)
	)
	(segment
		(start 88.85 116)
		(end 88.7 116)
		(width 0.3)
		(layer "In2.Cu")
		(net 112)
	)
	(segment
		(start 88.5 116)
		(end 88.85 116)
		(width 0.3)
		(layer "In2.Cu")
		(net 112)
	)
	(segment
		(start 57.03 98.016397)
		(end 58.15 99.136397)
		(width 0.3)
		(layer "In2.Cu")
		(net 112)
	)
	(segment
		(start 75.4 116)
		(end 80.065 116)
		(width 0.3)
		(layer "In2.Cu")
		(net 112)
	)
	(segment
		(start 80.065 117.91)
		(end 80.065 116)
		(width 0.15)
		(layer "In2.Cu")
		(net 112)
	)
	(segment
		(start 64.886212 81.856212)
		(end 65.56 82.53)
		(width 0.15)
		(layer "In2.Cu")
		(net 112)
	)
	(segment
		(start 114.207107 116)
		(end 117.407107 112.8)
		(width 0.3)
		(layer "In2.Cu")
		(net 112)
	)
	(segment
		(start 64.7 109.7)
		(end 67.9 109.7)
		(width 0.3)
		(layer "In2.Cu")
		(net 112)
	)
	(segment
		(start 117.407107 112.8)
		(end 135.85 112.8)
		(width 0.3)
		(layer "In2.Cu")
		(net 112)
	)
	(segment
		(start 61.767893 90.875)
		(end 59.342893 88.45)
		(width 0.3)
		(layer "In2.Cu")
		(net 112)
	)
	(segment
		(start 102.85 103.6)
		(end 104.1 103.6)
		(width 0.3)
		(layer "In2.Cu")
		(net 112)
	)
	(segment
		(start 65.31 85.68)
		(end 62.94 88.05)
		(width 0.3)
		(layer "In2.Cu")
		(net 112)
	)
	(segment
		(start 88.85 116)
		(end 99.75 116)
		(width 0.3)
		(layer "In2.Cu")
		(net 112)
	)
	(segment
		(start 68.4 114.1)
		(end 68.8 114.5)
		(width 0.3)
		(layer "In2.Cu")
		(net 112)
	)
	(segment
		(start 58.15 99.136397)
		(end 58.15 104.1245)
		(width 0.3)
		(layer "In2.Cu")
		(net 112)
	)
	(segment
		(start 88.7 116)
		(end 88.5 115.8)
		(width 0.3)
		(layer "In2.Cu")
		(net 112)
	)
	(segment
		(start 65.61 85.68)
		(end 65.31 85.68)
		(width 0.3)
		(layer "In2.Cu")
		(net 112)
	)
	(segment
		(start 99.75 113.75)
		(end 104.19 109.31)
		(width 0.3)
		(layer "In2.Cu")
		(net 112)
	)
	(segment
		(start 88.5 115.8)
		(end 88.5 115.25)
		(width 0.3)
		(layer "In2.Cu")
		(net 112)
	)
	(segment
		(start 56.25 89.82)
		(end 56.25 92.05)
		(width 0.3)
		(layer "In2.Cu")
		(net 112)
	)
	(segment
		(start 99.75 116)
		(end 99.75 113.75)
		(width 0.3)
		(layer "In2.Cu")
		(net 112)
	)
	(segment
		(start 62.94 107.94)
		(end 64.7 109.7)
		(width 0.3)
		(layer "In2.Cu")
		(net 112)
	)
	(segment
		(start 104.19 109.31)
		(end 104.19 103.69)
		(width 0.3)
		(layer "In2.Cu")
		(net 112)
	)
	(segment
		(start 57.62 88.45)
		(end 56.25 89.82)
		(width 0.3)
		(layer "In2.Cu")
		(net 112)
	)
	(segment
		(start 96.631668 99.1)
		(end 98.35 99.1)
		(width 0.3)
		(layer "In2.Cu")
		(net 112)
	)
	(segment
		(start 59.342893 88.45)
		(end 57.62 88.45)
		(width 0.3)
		(layer "In2.Cu")
		(net 112)
	)
	(segment
		(start 80.695 121.395)
		(end 80.695 118.54)
		(width 0.15)
		(layer "B.Cu")
		(net 112)
	)
	(segment
		(start 138.43 100.645)
		(end 138.43 100.075)
		(width 0.3)
		(layer "B.Cu")
		(net 112)
	)
	(segment
		(start 103.095 104.625)
		(end 108.15 99.57)
		(width 0.3)
		(layer "B.Cu")
		(net 112)
	)
	(segment
		(start 138.725 100.94)
		(end 138.43 100.645)
		(width 0.3)
		(layer "B.Cu")
		(net 112)
	)
	(segment
		(start 65.61 85.68)
		(end 65.45 85.52)
		(width 0.15)
		(layer "B.Cu")
		(net 112)
	)
	(segment
		(start 68.69 126.07)
		(end 70.19 127.57)
		(width 0.15)
		(layer "B.Cu")
		(net 112)
	)
	(segment
		(start 138.43 99.87)
		(end 138.43 100.075)
		(width 0.3)
		(layer "B.Cu")
		(net 112)
	)
	(segment
		(start 138.75 99.55)
		(end 138.43 99.87)
		(width 0.3)
		(layer "B.Cu")
		(net 112)
	)
	(segment
		(start 96.531153 98.999485)
		(end 96.048406 99.482232)
		(width 0.3)
		(layer "B.Cu")
		(net 112)
	)
	(segment
		(start 65.45 85.52)
		(end 65.45 84.8)
		(width 0.15)
		(layer "B.Cu")
		(net 112)
	)
	(segment
		(start 96.048406 99.575)
		(end 96.973396 100.49999)
		(width 0.3)
		(layer "B.Cu")
		(net 112)
	)
	(segment
		(start 66.95 83.3)
		(end 67.615 83.3)
		(width 0.15)
		(layer "B.Cu")
		(net 112)
	)
	(segment
		(start 65.7 86.64)
		(end 66.28 86.64)
		(width 0.15)
		(layer "B.Cu")
		(net 112)
	)
	(segment
		(start 65.3 86.24)
		(end 65.7 86.64)
		(width 0.15)
		(layer "B.Cu")
		(net 112)
	)
	(segment
		(start 89 113.085)
		(end 88.5 113.585)
		(width 0.125)
		(layer "B.Cu")
		(net 112)
	)
	(segment
		(start 66.855 86.115)
		(end 66.785 86.115)
		(width 0.155)
		(layer "B.Cu")
		(net 112)
	)
	(segment
		(start 138.75 99.0975)
		(end 138.75 99.55)
		(width 0.3)
		(layer "B.Cu")
		(net 112)
	)
	(segment
		(start 65.61 85.68)
		(end 65.3 85.99)
		(width 0.15)
		(layer "B.Cu")
		(net 112)
	)
	(segment
		(start 109.91 95.73)
		(end 109.22 95.04)
		(width 0.3)
		(layer "B.Cu")
		(net 112)
	)
	(segment
		(start 63.5 83.152893)
		(end 63.5 82.7)
		(width 0.3)
		(layer "B.Cu")
		(net 112)
	)
	(segment
		(start 96.048406 99.482232)
		(end 96.048406 99.575)
		(width 0.3)
		(layer "B.Cu")
		(net 112)
	)
	(segment
		(start 96.973396 100.49999)
		(end 98 100.49999)
		(width 0.3)
		(layer "B.Cu")
		(net 112)
	)
	(segment
		(start 70.19 127.57)
		(end 74.52 127.57)
		(width 0.15)
		(layer "B.Cu")
		(net 112)
	)
	(segment
		(start 64.018 84.53)
		(end 64.018 83.670893)
		(width 0.3)
		(layer "B.Cu")
		(net 112)
	)
	(segment
		(start 74.52 127.57)
		(end 80.695 121.395)
		(width 0.15)
		(layer "B.Cu")
		(net 112)
	)
	(segment
		(start 66.55 80.735)
		(end 66.55 79.695)
		(width 0.15)
		(layer "B.Cu")
		(net 112)
	)
	(segment
		(start 64.018 83.670893)
		(end 63.5 83.152893)
		(width 0.3)
		(layer "B.Cu")
		(net 112)
	)
	(segment
		(start 68.395 85.55)
		(end 67.42 85.55)
		(width 0.155)
		(layer "B.Cu")
		(net 112)
	)
	(segment
		(start 66.705 86.215)
		(end 66.8 86.215)
		(width 0.15)
		(layer "B.Cu")
		(net 112)
	)
	(segment
		(start 65.61 85.68)
		(end 65.168 85.68)
		(width 0.3)
		(layer "B.Cu")
		(net 112)
	)
	(segment
		(start 68.165 126.07)
		(end 68.69 126.07)
		(width 0.15)
		(layer "B.Cu")
		(net 112)
	)
	(segment
		(start 65.3 85.99)
		(end 65.3 86.24)
		(width 0.15)
		(layer "B.Cu")
		(net 112)
	)
	(segment
		(start 88.5 113.585)
		(end 88.5 115.25)
		(width 0.125)
		(layer "B.Cu")
		(net 112)
	)
	(segment
		(start 100.66 104.625)
		(end 103.095 104.625)
		(width 0.3)
		(layer "B.Cu")
		(net 112)
	)
	(segment
		(start 109.22 95.04)
		(end 108.15175 95.04)
		(width 0.3)
		(layer "B.Cu")
		(net 112)
	)
	(segment
		(start 64.874499 81.856212)
		(end 65.428788 81.856212)
		(width 0.15)
		(layer "B.Cu")
		(net 112)
	)
	(segment
		(start 109.91 99.19)
		(end 109.91 95.73)
		(width 0.3)
		(layer "B.Cu")
		(net 112)
	)
	(segment
		(start 109.53 99.57)
		(end 109.91 99.19)
		(width 0.3)
		(layer "B.Cu")
		(net 112)
	)
	(segment
		(start 138.75 98.5075)
		(end 138.75 99.0975)
		(width 0.3)
		(layer "B.Cu")
		(net 112)
	)
	(segment
		(start 67.42 85.55)
		(end 66.855 86.115)
		(width 0.155)
		(layer "B.Cu")
		(net 112)
	)
	(segment
		(start 80.695 118.54)
		(end 80.065 117.91)
		(width 0.15)
		(layer "B.Cu")
		(net 112)
	)
	(segment
		(start 65.45 84.8)
		(end 66.95 83.3)
		(width 0.15)
		(layer "B.Cu")
		(net 112)
	)
	(segment
		(start 108.15 99.57)
		(end 109.53 99.57)
		(width 0.3)
		(layer "B.Cu")
		(net 112)
	)
	(segment
		(start 65.428788 81.856212)
		(end 66.55 80.735)
		(width 0.15)
		(layer "B.Cu")
		(net 112)
	)
	(segment
		(start 66.28 86.64)
		(end 66.705 86.215)
		(width 0.15)
		(layer "B.Cu")
		(net 112)
	)
	(segment
		(start 65.168 85.68)
		(end 64.018 84.53)
		(width 0.3)
		(layer "B.Cu")
		(net 112)
	)
	(segment
		(start 146.612632 87.4005)
		(end 146.862367 87.4005)
		(width 0.155)
		(layer "F.Cu")
		(net 113)
	)
	(segment
		(start 147.137131 87.25)
		(end 147.45 87.25)
		(width 0.155)
		(layer "F.Cu")
		(net 113)
	)
	(segment
		(start 116.246823 82.647496)
		(end 116.246823 80.305636)
		(width 0.155)
		(layer "F.Cu")
		(net 113)
	)
	(segment
		(start 110.230011 83.950011)
		(end 110.230011 83.803546)
		(width 0.155)
		(layer "F.Cu")
		(net 113)
	)
	(segment
		(start 148.037633 87.4005)
		(end 148.090368 87.4005)
		(width 0.155)
		(layer "F.Cu")
		(net 113)
	)
	(segment
		(start 110.484057 83.5495)
		(end 110.885942 83.5495)
		(width 0.155)
		(layer "F.Cu")
		(net 113)
	)
	(segment
		(start 116.246823 80.305636)
		(end 116.347323 80.205136)
		(width 0.155)
		(layer "F.Cu")
		(net 113)
	)
	(segment
		(start 110.992008 83.593434)
		(end 111.070206 83.671632)
		(width 0.155)
		(layer "F.Cu")
		(net 113)
	)
	(segment
		(start 111.282338 83.7595)
		(end 115.134819 83.7595)
		(width 0.155)
		(layer "F.Cu")
		(net 113)
	)
	(segment
		(start 110.273945 83.69748)
		(end 110.377991 83.593434)
		(width 0.155)
		(layer "F.Cu")
		(net 113)
	)
	(segment
		(start 146.3 87.15)
		(end 146.506566 87.356566)
		(width 0.155)
		(layer "F.Cu")
		(net 113)
	)
	(segment
		(start 115.488373 83.613053)
		(end 116.100377 83.001049)
		(width 0.155)
		(layer "F.Cu")
		(net 113)
	)
	(segment
		(start 148.196434 87.356566)
		(end 148.3 87.253)
		(width 0.155)
		(layer "F.Cu")
		(net 113)
	)
	(segment
		(start 146.968433 87.356566)
		(end 147.031065 87.293934)
		(width 0.155)
		(layer "F.Cu")
		(net 113)
	)
	(segment
		(start 147.45 87.25)
		(end 147.762869 87.25)
		(width 0.155)
		(layer "F.Cu")
		(net 113)
	)
	(segment
		(start 147.868935 87.293934)
		(end 147.931567 87.356566)
		(width 0.155)
		(layer "F.Cu")
		(net 113)
	)
	(via
		(at 110.230011 83.950011)
		(size 0.45)
		(drill 0.1)
		(layers "F.Cu" "B.Cu")
		(net 113)
	)
	(via
		(at 148.3 87.253)
		(size 0.45)
		(drill 0.1)
		(layers "F.Cu" "B.Cu")
		(net 113)
	)
	(arc
		(start 110.885942 83.5495)
		(mid 110.943345 83.560918)
		(end 110.992008 83.593434)
		(width 0.155)
		(layer "F.Cu")
		(net 113)
	)
	(arc
		(start 146.862367 87.4005)
		(mid 146.91977 87.389082)
		(end 146.968433 87.356566)
		(width 0.155)
		(layer "F.Cu")
		(net 113)
	)
	(arc
		(start 147.762869 87.25)
		(mid 147.820272 87.261418)
		(end 147.868935 87.293934)
		(width 0.155)
		(layer "F.Cu")
		(net 113)
	)
	(arc
		(start 110.230011 83.803546)
		(mid 110.241429 83.746143)
		(end 110.273945 83.69748)
		(width 0.155)
		(layer "F.Cu")
		(net 113)
	)
	(arc
		(start 110.484057 83.5495)
		(mid 110.426654 83.560918)
		(end 110.377991 83.593434)
		(width 0.155)
		(layer "F.Cu")
		(net 113)
	)
	(arc
		(start 148.037633 87.4005)
		(mid 147.98023 87.389082)
		(end 147.931567 87.356566)
		(width 0.155)
		(layer "F.Cu")
		(net 113)
	)
	(arc
		(start 116.246823 82.647496)
		(mid 116.208763 82.838837)
		(end 116.100377 83.001049)
		(width 0.155)
		(layer "F.Cu")
		(net 113)
	)
	(arc
		(start 147.137131 87.25)
		(mid 147.079728 87.261418)
		(end 147.031065 87.293934)
		(width 0.155)
		(layer "F.Cu")
		(net 113)
	)
	(arc
		(start 111.070206 83.671632)
		(mid 111.167533 83.736664)
		(end 111.282338 83.7595)
		(width 0.155)
		(layer "F.Cu")
		(net 113)
	)
	(arc
		(start 146.612632 87.4005)
		(mid 146.555229 87.389082)
		(end 146.506566 87.356566)
		(width 0.155)
		(layer "F.Cu")
		(net 113)
	)
	(arc
		(start 148.090368 87.4005)
		(mid 148.147771 87.389082)
		(end 148.196434 87.356566)
		(width 0.155)
		(layer "F.Cu")
		(net 113)
	)
	(arc
		(start 115.134819 83.7595)
		(mid 115.326161 83.72144)
		(end 115.488373 83.613053)
		(width 0.155)
		(layer "F.Cu")
		(net 113)
	)
	(segment
		(start 112.811718 94.751)
		(end 110.999 92.938282)
		(width 0.16)
		(layer "In5.Cu")
		(net 113)
	)
	(segment
		(start 110.999 92.938282)
		(end 110.999 88.488282)
		(width 0.16)
		(layer "In5.Cu")
		(net 113)
	)
	(segment
		(start 132.501 99.038282)
		(end 132.501 99.938282)
		(width 0.16)
		(layer "In5.Cu")
		(net 113)
	)
	(segment
		(start 109.849 84.121718)
		(end 110.020707 83.950011)
		(width 0.16)
		(layer "In5.Cu")
		(net 113)
	)
	(segment
		(start 148.3 87.253)
		(end 148.152 87.401)
		(width 0.16)
		(layer "In5.Cu")
		(net 113)
	)
	(segment
		(start 110.378201 87.584641)
		(end 110.378202 87.58464)
		(width 0.16)
		(layer "In5.Cu")
		(net 113)
	)
	(segment
		(start 110.673868 87.854659)
		(end 110.673867 87.85466)
		(width 0.16)
		(layer "In5.Cu")
		(net 113)
	)
	(segment
		(start 115.099 98.488282)
		(end 115.099 95.488282)
		(width 0.16)
		(layer "In5.Cu")
		(net 113)
	)
	(segment
		(start 133.288282 98.251)
		(end 132.501 99.038282)
		(width 0.16)
		(layer "In5.Cu")
		(net 113)
	)
	(segment
		(start 141.538282 97.561)
		(end 139.498282 99.601)
		(width 0.16)
		(layer "In5.Cu")
		(net 113)
	)
	(segment
		(start 110.095359 87.584641)
		(end 109.999 87.488282)
		(width 0.16)
		(layer "In5.Cu")
		(net 113)
	)
	(segment
		(start 132.501 99.938282)
		(end 131.348282 101.091)
		(width 0.16)
		(layer "In5.Cu")
		(net 113)
	)
	(segment
		(start 110.999 88.488282)
		(end 110.661043 88.150325)
		(width 0.16)
		(layer "In5.Cu")
		(net 113)
	)
	(segment
		(start 139.498282 99.601)
		(end 136.161718 99.601)
		(width 0.16)
		(layer "In5.Cu")
		(net 113)
	)
	(segment
		(start 147.918282 87.401)
		(end 147.401 87.918282)
		(width 0.16)
		(layer "In5.Cu")
		(net 113)
	)
	(segment
		(start 114.361718 94.751)
		(end 112.811718 94.751)
		(width 0.16)
		(layer "In5.Cu")
		(net 113)
	)
	(segment
		(start 110.391026 87.571817)
		(end 110.378201 87.584641)
		(width 0.16)
		(layer "In5.Cu")
		(net 113)
	)
	(segment
		(start 144.078282 97.561)
		(end 141.538282 97.561)
		(width 0.16)
		(layer "In5.Cu")
		(net 113)
	)
	(segment
		(start 147.401 87.918282)
		(end 147.401 94.238282)
		(width 0.16)
		(layer "In5.Cu")
		(net 113)
	)
	(segment
		(start 136.161718 99.601)
		(end 134.811718 98.251)
		(width 0.16)
		(layer "In5.Cu")
		(net 113)
	)
	(segment
		(start 110.673868 87.571817)
		(end 110.673869 87.571818)
		(width 0.16)
		(layer "In5.Cu")
		(net 113)
	)
	(segment
		(start 109.849 85.268282)
		(end 109.849 84.121718)
		(width 0.16)
		(layer "In5.Cu")
		(net 113)
	)
	(segment
		(start 131.348282 101.091)
		(end 125.268282 101.091)
		(width 0.16)
		(layer "In5.Cu")
		(net 113)
	)
	(segment
		(start 148.152 87.401)
		(end 147.918282 87.401)
		(width 0.16)
		(layer "In5.Cu")
		(net 113)
	)
	(segment
		(start 125.268282 101.091)
		(end 123.658282 102.701)
		(width 0.16)
		(layer "In5.Cu")
		(net 113)
	)
	(segment
		(start 147.401 94.238282)
		(end 144.078282 97.561)
		(width 0.16)
		(layer "In5.Cu")
		(net 113)
	)
	(segment
		(start 115.099 95.488282)
		(end 114.361718 94.751)
		(width 0.16)
		(layer "In5.Cu")
		(net 113)
	)
	(segment
		(start 110.020707 83.950011)
		(end 110.230011 83.950011)
		(width 0.16)
		(layer "In5.Cu")
		(net 113)
	)
	(segment
		(start 123.658282 102.701)
		(end 119.311718 102.701)
		(width 0.16)
		(layer "In5.Cu")
		(net 113)
	)
	(segment
		(start 119.311718 102.701)
		(end 115.099 98.488282)
		(width 0.16)
		(layer "In5.Cu")
		(net 113)
	)
	(segment
		(start 109.999 85.418282)
		(end 109.849 85.268282)
		(width 0.16)
		(layer "In5.Cu")
		(net 113)
	)
	(segment
		(start 110.661042 87.867482)
		(end 110.673868 87.854659)
		(width 0.16)
		(layer "In5.Cu")
		(net 113)
	)
	(segment
		(start 134.811718 98.251)
		(end 133.288282 98.251)
		(width 0.16)
		(layer "In5.Cu")
		(net 113)
	)
	(segment
		(start 109.999 87.488282)
		(end 109.999 85.418282)
		(width 0.16)
		(layer "In5.Cu")
		(net 113)
	)
	(arc
		(start 110.661043 88.150325)
		(mid 110.602464 88.008904)
		(end 110.661042 87.867482)
		(width 0.16)
		(layer "In5.Cu")
		(net 113)
	)
	(arc
		(start 110.673867 87.85466)
		(mid 110.732446 87.713239)
		(end 110.673868 87.571817)
		(width 0.16)
		(layer "In5.Cu")
		(net 113)
	)
	(arc
		(start 110.673869 87.571818)
		(mid 110.532448 87.513239)
		(end 110.391026 87.571817)
		(width 0.16)
		(layer "In5.Cu")
		(net 113)
	)
	(arc
		(start 110.378202 87.58464)
		(mid 110.236781 87.643219)
		(end 110.095359 87.584641)
		(width 0.16)
		(layer "In5.Cu")
		(net 113)
	)
	(segment
		(start 116.097323 72.005136)
		(end 116.097323 70.477)
		(width 0.155)
		(layer "F.Cu")
		(net 114)
	)
	(segment
		(start 116.097323 70.477)
		(end 116.050323 70.43)
		(width 0.155)
		(layer "F.Cu")
		(net 114)
	)
	(segment
		(start 144.7745 93.0775)
		(end 144.922 93.225)
		(width 0.155)
		(layer "F.Cu")
		(net 114)
	)
	(segment
		(start 145.7 92.75)
		(end 145.4495 92.4995)
		(width 0.155)
		(layer "F.Cu")
		(net 114)
	)
	(segment
		(start 145.4495 92.4995)
		(end 145.161926 92.4995)
		(width 0.155)
		(layer "F.Cu")
		(net 114)
	)
	(segment
		(start 145.161926 92.4995)
		(end 144.7745 92.886926)
		(width 0.155)
		(layer "F.Cu")
		(net 114)
	)
	(segment
		(start 144.7745 92.886926)
		(end 144.7745 93.0775)
		(width 0.155)
		(layer "F.Cu")
		(net 114)
	)
	(via
		(at 144.922 93.225)
		(size 0.45)
		(drill 0.1)
		(layers "F.Cu" "B.Cu")
		(net 114)
	)
	(via
		(at 116.050323 70.43)
		(size 0.45)
		(drill 0.1)
		(layers "F.Cu" "B.Cu")
		(net 114)
	)
	(segment
		(start 144.399 83.113282)
		(end 144.399 92.413282)
		(width 0.16)
		(layer "In5.Cu")
		(net 114)
	)
	(segment
		(start 144.399 92.413282)
		(end 144.774 92.788282)
		(width 0.16)
		(layer "In5.Cu")
		(net 114)
	)
	(segment
		(start 133.361718 75.401)
		(end 136.686718 75.401)
		(width 0.16)
		(layer "In5.Cu")
		(net 114)
	)
	(segment
		(start 116.198323 70.050959)
		(end 116.673282 69.576)
		(width 0.16)
		(layer "In5.Cu")
		(net 114)
	)
	(segment
		(start 116.050323 70.43)
		(end 116.198323 70.282)
		(width 0.16)
		(layer "In5.Cu")
		(net 114)
	)
	(segment
		(start 122.973282 69.576)
		(end 123.178282 69.371)
		(width 0.16)
		(layer "In5.Cu")
		(net 114)
	)
	(segment
		(start 124.601718 69.371)
		(end 124.906718 69.676)
		(width 0.16)
		(layer "In5.Cu")
		(net 114)
	)
	(segment
		(start 116.198323 70.282)
		(end 116.198323 70.050959)
		(width 0.16)
		(layer "In5.Cu")
		(net 114)
	)
	(segment
		(start 136.686718 75.401)
		(end 144.399 83.113282)
		(width 0.16)
		(layer "In5.Cu")
		(net 114)
	)
	(segment
		(start 123.178282 69.371)
		(end 124.601718 69.371)
		(width 0.16)
		(layer "In5.Cu")
		(net 114)
	)
	(segment
		(start 144.774 92.788282)
		(end 144.774 93.077)
		(width 0.16)
		(layer "In5.Cu")
		(net 114)
	)
	(segment
		(start 116.673282 69.576)
		(end 122.973282 69.576)
		(width 0.16)
		(layer "In5.Cu")
		(net 114)
	)
	(segment
		(start 124.906718 69.676)
		(end 127.636718 69.676)
		(width 0.16)
		(layer "In5.Cu")
		(net 114)
	)
	(segment
		(start 144.774 93.077)
		(end 144.922 93.225)
		(width 0.16)
		(layer "In5.Cu")
		(net 114)
	)
	(segment
		(start 127.636718 69.676)
		(end 133.361718 75.401)
		(width 0.16)
		(layer "In5.Cu")
		(net 114)
	)
	(segment
		(start 116.05 70.670323)
		(end 116.050323 70.67)
		(width 0.155)
		(layer "B.Cu")
		(net 114)
	)
	(segment
		(start 116.050323 70.67)
		(end 116.050323 70.43)
		(width 0.155)
		(layer "B.Cu")
		(net 114)
	)
	(segment
		(start 116.05 71.1)
		(end 116.05 70.670323)
		(width 0.155)
		(layer "B.Cu")
		(net 114)
	)
	(segment
		(start 68.67 97.02)
		(end 68.67 96.6)
		(width 0.15)
		(layer "F.Cu")
		(net 115)
	)
	(segment
		(start 67.04 92.7)
		(end 64.8 92.7)
		(width 0.15)
		(layer "F.Cu")
		(net 115)
	)
	(segment
		(start 64.8 92.7)
		(end 64.6 92.5)
		(width 0.15)
		(layer "F.Cu")
		(net 115)
	)
	(segment
		(start 68.19 93.85)
		(end 67.04 92.7)
		(width 0.15)
		(layer "F.Cu")
		(net 115)
	)
	(segment
		(start 68.67 96.6)
		(end 68.19 96.12)
		(width 0.15)
		(layer "F.Cu")
		(net 115)
	)
	(segment
		(start 66.9 121.878173)
		(end 65.718173 123.06)
		(width 0.15)
		(layer "F.Cu")
		(net 115)
	)
	(segment
		(start 66.9 120.65)
		(end 66.9 121.878173)
		(width 0.15)
		(layer "F.Cu")
		(net 115)
	)
	(segment
		(start 65.718173 123.06)
		(end 62.445 123.06)
		(width 0.15)
		(layer "F.Cu")
		(net 115)
	)
	(segment
		(start 62.445 123.06)
		(end 61.285 121.9)
		(width 0.15)
		(layer "F.Cu")
		(net 115)
	)
	(segment
		(start 68.19 96.12)
		(end 68.19 93.85)
		(width 0.15)
		(layer "F.Cu")
		(net 115)
	)
	(via
		(at 51.85 77.2975)
		(size 0.45)
		(drill 0.1)
		(layers "F.Cu" "B.Cu")
		(free yes)
		(net 115)
	)
	(via
		(at 50.95 78.45)
		(size 0.45)
		(drill 0.1)
		(layers "F.Cu" "B.Cu")
		(free yes)
		(net 115)
	)
	(via
		(at 73.95 86.45)
		(size 0.45)
		(drill 0.1)
		(layers "F.Cu" "B.Cu")
		(free yes)
		(net 115)
	)
	(via
		(at 72.95 85.95)
		(size 0.45)
		(drill 0.1)
		(layers "F.Cu" "B.Cu")
		(free yes)
		(net 115)
	)
	(via
		(at 64.275 93.925)
		(size 0.45)
		(drill 0.1)
		(layers "F.Cu" "B.Cu")
		(free yes)
		(net 115)
	)
	(via
		(at 51.5 78.45)
		(size 0.45)
		(drill 0.1)
		(layers "F.Cu" "B.Cu")
		(free yes)
		(net 115)
	)
	(via
		(at 51.85 77.8975)
		(size 0.45)
		(drill 0.1)
		(layers "F.Cu" "B.Cu")
		(free yes)
		(net 115)
	)
	(via
		(at 141.01 118.9)
		(size 0.45)
		(drill 0.1)
		(layers "F.Cu" "B.Cu")
		(free yes)
		(net 115)
	)
	(via
		(at 64.1 91.5)
		(size 0.45)
		(drill 0.1)
		(layers "F.Cu" "B.Cu")
		(free yes)
		(net 115)
	)
	(via
		(at 66.9 120.65)
		(size 0.45)
		(drill 0.1)
		(layers "F.Cu" "B.Cu")
		(net 115)
	)
	(via
		(at 64.6 91.5)
		(size 0.45)
		(drill 0.1)
		(layers "F.Cu" "B.Cu")
		(free yes)
		(net 115)
	)
	(via
		(at 73.45 86.45)
		(size 0.45)
		(drill 0.1)
		(layers "F.Cu" "B.Cu")
		(free yes)
		(net 115)
	)
	(via
		(at 73.45 86.95)
		(size 0.45)
		(drill 0.1)
		(layers "F.Cu" "B.Cu")
		(free yes)
		(net 115)
	)
	(via
		(at 73.45 85.95)
		(size 0.45)
		(drill 0.1)
		(layers "F.Cu" "B.Cu")
		(free yes)
		(net 115)
	)
	(via
		(at 51.38 80.74)
		(size 0.45)
		(drill 0.1)
		(layers "F.Cu" "B.Cu")
		(free yes)
		(net 115)
	)
	(via
		(at 51.25 77.2975)
		(size 0.45)
		(drill 0.1)
		(layers "F.Cu" "B.Cu")
		(free yes)
		(net 115)
	)
	(via
		(at 54.48 81.3125)
		(size 0.45)
		(drill 0.1)
		(layers "F.Cu" "B.Cu")
		(free yes)
		(net 115)
	)
	(via
		(at 50.83 80.74)
		(size 0.45)
		(drill 0.1)
		(layers "F.Cu" "B.Cu")
		(free yes)
		(net 115)
	)
	(via
		(at 141.01 119.4)
		(size 0.45)
		(drill 0.1)
		(layers "F.Cu" "B.Cu")
		(free yes)
		(net 115)
	)
	(via
		(at 64.1 92)
		(size 0.45)
		(drill 0.1)
		(layers "F.Cu" "B.Cu")
		(free yes)
		(net 115)
	)
	(via
		(at 51.25 77.8975)
		(size 0.45)
		(drill 0.1)
		(layers "F.Cu" "B.Cu")
		(free yes)
		(net 115)
	)
	(via
		(at 64.6 93.5)
		(size 0.45)
		(drill 0.1)
		(layers "F.Cu" "B.Cu")
		(free yes)
		(net 115)
	)
	(via
		(at 72.95 85.45)
		(size 0.45)
		(drill 0.1)
		(layers "F.Cu" "B.Cu")
		(free yes)
		(net 115)
	)
	(via
		(at 64.6 92.5)
		(size 0.45)
		(drill 0.1)
		(layers "F.Cu" "B.Cu")
		(free yes)
		(net 115)
	)
	(via
		(at 73.45 85.45)
		(size 0.45)
		(drill 0.1)
		(layers "F.Cu" "B.Cu")
		(free yes)
		(net 115)
	)
	(via
		(at 64.6 93)
		(size 0.45)
		(drill 0.1)
		(layers "F.Cu" "B.Cu")
		(free yes)
		(net 115)
	)
	(via
		(at 140.51 118.9)
		(size 0.45)
		(drill 0.1)
		(layers "F.Cu" "B.Cu")
		(free yes)
		(net 115)
	)
	(via
		(at 64.6 92)
		(size 0.45)
		(drill 0.1)
		(layers "F.Cu" "B.Cu")
		(free yes)
		(net 115)
	)
	(via
		(at 73.95 86.95)
		(size 0.45)
		(drill 0.1)
		(layers "F.Cu" "B.Cu")
		(free yes)
		(net 115)
	)
	(via
		(at 140.51 119.4)
		(size 0.45)
		(drill 0.1)
		(layers "F.Cu" "B.Cu")
		(free yes)
		(net 115)
	)
	(segment
		(start 49.44 82.12)
		(end 49.44 81.05)
		(width 0.125)
		(layer "B.Cu")
		(net 115)
	)
	(segment
		(start 75.55 80.25)
		(end 75.05 80.75)
		(width 0.3)
		(layer "B.Cu")
		(net 115)
	)
	(segment
		(start 67.48 120.07)
		(end 68.165 120.07)
		(width 0.15)
		(layer "B.Cu")
		(net 115)
	)
	(segment
		(start 76.26 80.89)
		(end 75.52 81.63)
		(width 0.3)
		(layer "B.Cu")
		(net 115)
	)
	(segment
		(start 66.9 120.65)
		(end 67.48 120.07)
		(width 0.15)
		(layer "B.Cu")
		(net 115)
	)
	(segment
		(start 75.52 83.38)
		(end 73.45 85.45)
		(width 0.3)
		(layer "B.Cu")
		(net 115)
	)
	(segment
		(start 49.44 81.05)
		(end 49.79 80.7)
		(width 0.125)
		(layer "B.Cu")
		(net 115)
	)
	(segment
		(start 75.52 81.63)
		(end 75.52 83.38)
		(width 0.3)
		(layer "B.Cu")
		(net 115)
	)
	(segment
		(start 76.26 80.25)
		(end 75.55 80.25)
		(width 0.3)
		(layer "B.Cu")
		(net 115)
	)
	(segment
		(start 50.45 80.7)
		(end 50.725 80.425)
		(width 0.125)
		(layer "B.Cu")
		(net 115)
	)
	(segment
		(start 50.725 80.425)
		(end 50.725 80.1005)
		(width 0.125)
		(layer "B.Cu")
		(net 115)
	)
	(segment
		(start 76.26 80.25)
		(end 76.26 80.89)
		(width 0.3)
		(layer "B.Cu")
		(net 115)
	)
	(segment
		(start 75.05 80.75)
		(end 74.775 80.75)
		(width 0.3)
		(layer "B.Cu")
		(net 115)
	)
	(segment
		(start 49.51 82.19)
		(end 49.44 82.12)
		(width 0.125)
		(layer "B.Cu")
		(net 115)
	)
	(segment
		(start 49.79 80.7)
		(end 50.45 80.7)
		(width 0.125)
		(layer "B.Cu")
		(net 115)
	)
	(segment
		(start 74.775 79.45)
		(end 75.575 80.25)
		(width 0.13)
		(layer "B.Cu")
		(net 115)
	)
	(segment
		(start 103.15 78.55)
		(end 103.15 75.2)
		(width 0.15)
		(layer "F.Cu")
		(net 116)
	)
	(segment
		(start 105.2 89.2)
		(end 103.7 87.7)
		(width 0.15)
		(layer "F.Cu")
		(net 116)
	)
	(segment
		(start 103.7 86.15)
		(end 103.4 85.85)
		(width 0.15)
		(layer "F.Cu")
		(net 116)
	)
	(segment
		(start 103.15 75.2)
		(end 104.597323 73.752677)
		(width 0.15)
		(layer "F.Cu")
		(net 116)
	)
	(segment
		(start 103.7 87.7)
		(end 103.7 86.15)
		(width 0.15)
		(layer "F.Cu")
		(net 116)
	)
	(segment
		(start 105.85 99.45)
		(end 105.85 92.3)
		(width 0.15)
		(layer "F.Cu")
		(net 116)
	)
	(segment
		(start 108.3 103.2)
		(end 108.3 101.9)
		(width 0.15)
		(layer "F.Cu")
		(net 116)
	)
	(segment
		(start 103.35 78.75)
		(end 103.15 78.55)
		(width 0.15)
		(layer "F.Cu")
		(net 116)
	)
	(segment
		(start 105.85 92.3)
		(end 105.2 91.65)
		(width 0.15)
		(layer "F.Cu")
		(net 116)
	)
	(segment
		(start 105.2 91.65)
		(end 105.2 89.2)
		(width 0.15)
		(layer "F.Cu")
		(net 116)
	)
	(segment
		(start 104.597323 73.752677)
		(end 104.597323 72.005136)
		(width 0.15)
		(layer "F.Cu")
		(net 116)
	)
	(segment
		(start 108.3 101.9)
		(end 105.85 99.45)
		(width 0.15)
		(layer "F.Cu")
		(net 116)
	)
	(via
		(at 108.3 103.2)
		(size 0.45)
		(drill 0.1)
		(layers "F.Cu" "B.Cu")
		(net 116)
	)
	(via
		(at 103.4 85.85)
		(size 0.45)
		(drill 0.1)
		(layers "F.Cu" "B.Cu")
		(net 116)
	)
	(via
		(at 103.35 78.75)
		(size 0.45)
		(drill 0.1)
		(layers "F.Cu" "B.Cu")
		(net 116)
	)
	(segment
		(start 103.35 85.8)
		(end 103.4 85.85)
		(width 0.15)
		(layer "In5.Cu")
		(net 116)
	)
	(segment
		(start 103.35 78.75)
		(end 103.35 85.8)
		(width 0.15)
		(layer "In5.Cu")
		(net 116)
	)
	(segment
		(start 108.7 106.5)
		(end 108.7 107.95)
		(width 0.15)
		(layer "B.Cu")
		(net 116)
	)
	(segment
		(start 107.8 105.6)
		(end 108.7 106.5)
		(width 0.15)
		(layer "B.Cu")
		(net 116)
	)
	(segment
		(start 108.3 103.2)
		(end 107 103.2)
		(width 0.15)
		(layer "B.Cu")
		(net 116)
	)
	(segment
		(start 106 104.2)
		(end 106 105.4)
		(width 0.15)
		(layer "B.Cu")
		(net 116)
	)
	(segment
		(start 106.2 105.6)
		(end 107.8 105.6)
		(width 0.15)
		(layer "B.Cu")
		(net 116)
	)
	(segment
		(start 107 103.2)
		(end 106 104.2)
		(width 0.15)
		(layer "B.Cu")
		(net 116)
	)
	(segment
		(start 106 105.4)
		(end 106.2 105.6)
		(width 0.15)
		(layer "B.Cu")
		(net 116)
	)
	(segment
		(start 137.4 116.8)
		(end 136.5 115.9)
		(width 0.3)
		(layer "F.Cu")
		(net 117)
	)
	(segment
		(start 81.875 125.1)
		(end 81.875 125.15)
		(width 0.155)
		(layer "F.Cu")
		(net 117)
	)
	(segment
		(start 84.55 125.6)
		(end 84.55 126.6)
		(width 0.155)
		(layer "F.Cu")
		(net 117)
	)
	(segment
		(start 139.15 116.8)
		(end 137.4 116.8)
		(width 0.3)
		(layer "F.Cu")
		(net 117)
	)
	(segment
		(start 82.325 125.6)
		(end 85.475 125.6)
		(width 0.155)
		(layer "F.Cu")
		(net 117)
	)
	(segment
		(start 81.875 125.15)
		(end 82.325 125.6)
		(width 0.155)
		(layer "F.Cu")
		(net 117)
	)
	(segment
		(start 85.475 125.6)
		(end 85.975 125.1)
		(width 0.155)
		(layer "F.Cu")
		(net 117)
	)
	(via
		(at 55.28 78.77)
		(size 0.45)
		(drill 0.1)
		(layers "F.Cu" "B.Cu")
		(net 117)
	)
	(via
		(at 63.535 127.1)
		(size 0.45)
		(drill 0.1)
		(layers "F.Cu" "B.Cu")
		(net 117)
	)
	(via
		(at 139.15 116.8)
		(size 0.45)
		(drill 0.1)
		(layers "F.Cu" "B.Cu")
		(net 117)
	)
	(via
		(at 84.55 126.6)
		(size 0.45)
		(drill 0.1)
		(layers "F.Cu" "B.Cu")
		(net 117)
	)
	(segment
		(start 100.1 126.2)
		(end 82.92 126.2)
		(width 0.3)
		(layer "In2.Cu")
		(net 117)
	)
	(segment
		(start 54.9 127.6)
		(end 63.535 127.6)
		(width 0.3)
		(layer "In2.Cu")
		(net 117)
	)
	(segment
		(start 54.55 78.04)
		(end 54.55 77.142893)
		(width 0.3)
		(layer "In2.Cu")
		(net 117)
	)
	(segment
		(start 55.28 78.77)
		(end 54.55 78.04)
		(width 0.3)
		(layer "In2.Cu")
		(net 117)
	)
	(segment
		(start 130.107107 126.6)
		(end 130.007107 126.5)
		(width 0.3)
		(layer "In2.Cu")
		(net 117)
	)
	(segment
		(start 48.5 77.475)
		(end 48.5 81.84)
		(width 0.3)
		(layer "In2.Cu")
		(net 117)
	)
	(segment
		(start 140.9 116.8)
		(end 141.6 117.5)
		(width 0.3)
		(layer "In2.Cu")
		(net 117)
	)
	(segment
		(start 129.592893 126.5)
		(end 129.492893 126.6)
		(width 0.3)
		(layer "In2.Cu")
		(net 117)
	)
	(segment
		(start 49.266053 76.708947)
		(end 48.5 77.475)
		(width 0.3)
		(layer "In2.Cu")
		(net 117)
	)
	(segment
		(start 141.6 117.5)
		(end 141.6 122.4)
		(width 0.3)
		(layer "In2.Cu")
		(net 117)
	)
	(segment
		(start 100.5 126.6)
		(end 100.1 126.2)
		(width 0.3)
		(layer "In2.Cu")
		(net 117)
	)
	(segment
		(start 54.116053 76.708947)
		(end 49.266053 76.708947)
		(width 0.3)
		(layer "In2.Cu")
		(net 117)
	)
	(segment
		(start 63.535 127.1)
		(end 63.535 127.6)
		(width 0.15)
		(layer "In2.Cu")
		(net 117)
	)
	(segment
		(start 82.92 126.2)
		(end 81.52 127.6)
		(width 0.3)
		(layer "In2.Cu")
		(net 117)
	)
	(segment
		(start 84.55 126.6)
		(end 84.55 126.15)
		(width 0.155)
		(layer "In2.Cu")
		(net 117)
	)
	(segment
		(start 49.0925 95.2175)
		(end 52.25 98.375)
		(width 0.3)
		(layer "In2.Cu")
		(net 117)
	)
	(segment
		(start 54.55 77.142893)
		(end 54.116053 76.708947)
		(width 0.3)
		(layer "In2.Cu")
		(net 117)
	)
	(segment
		(start 139.15 116.8)
		(end 140.9 116.8)
		(width 0.3)
		(layer "In2.Cu")
		(net 117)
	)
	(segment
		(start 49.0925 82.4325)
		(end 49.0925 95.2175)
		(width 0.3)
		(layer "In2.Cu")
		(net 117)
	)
	(segment
		(start 52.25 98.375)
		(end 52.25 124.95)
		(width 0.3)
		(layer "In2.Cu")
		(net 117)
	)
	(segment
		(start 48.5 81.84)
		(end 49.0925 82.4325)
		(width 0.3)
		(layer "In2.Cu")
		(net 117)
	)
	(segment
		(start 81.52 127.6)
		(end 63.535 127.6)
		(width 0.3)
		(layer "In2.Cu")
		(net 117)
	)
	(segment
		(start 129.492893 126.6)
		(end 100.5 126.6)
		(width 0.3)
		(layer "In2.Cu")
		(net 117)
	)
	(segment
		(start 137.4 126.6)
		(end 130.107107 126.6)
		(width 0.3)
		(layer "In2.Cu")
		(net 117)
	)
	(segment
		(start 130.007107 126.5)
		(end 129.592893 126.5)
		(width 0.3)
		(layer "In2.Cu")
		(net 117)
	)
	(segment
		(start 52.25 124.95)
		(end 54.9 127.6)
		(width 0.3)
		(layer "In2.Cu")
		(net 117)
	)
	(segment
		(start 141.6 122.4)
		(end 137.4 126.6)
		(width 0.3)
		(layer "In2.Cu")
		(net 117)
	)
	(segment
		(start 69.69 77.77)
		(end 70.91 77.77)
		(width 0.15)
		(layer "B.Cu")
		(net 117)
	)
	(segment
		(start 62.4 79.8)
		(end 64.075 78.125)
		(width 0.3)
		(layer "B.Cu")
		(net 117)
	)
	(segment
		(start 63.3 76.5)
		(end 64.075 76.5)
		(width 0.3)
		(layer "B.Cu")
		(net 117)
	)
	(segment
		(start 68 75.05)
		(end 67.8 75.25)
		(width 0.3)
		(layer "B.Cu")
		(net 117)
	)
	(segment
		(start 55.25 78.8)
		(end 55.25 80.051)
		(width 0.3)
		(layer "B.Cu")
		(net 117)
	)
	(segment
		(start 63.535 126.145)
		(end 63.535 127.1)
		(width 0.15)
		(layer "B.Cu")
		(net 117)
	)
	(segment
		(start 64.075 76.5)
		(end 64.815 76.5)
		(width 0.3)
		(layer "B.Cu")
		(net 117)
	)
	(segment
		(start 68.01 74.8)
		(end 68.185 74.625)
		(width 0.3)
		(layer "B.Cu")
		(net 117)
	)
	(segment
		(start 58.093406 80.545)
		(end 58.79 80.545)
		(width 0.3)
		(layer "B.Cu")
		(net 117)
	)
	(segment
		(start 68 75.45)
		(end 67.8 75.25)
		(width 0.3)
		(layer "B.Cu")
		(net 117)
	)
	(segment
		(start 70.2 79.4)
		(end 70.2 79.57)
		(width 0.5)
		(layer "B.Cu")
		(net 117)
	)
	(segment
		(start 71.29 78.15)
		(end 73.86 78.15)
		(width 0.15)
		(layer "B.Cu")
		(net 117)
	)
	(segment
		(start 64.815 76.47)
		(end 65.785 75.5)
		(width 0.3)
		(layer "B.Cu")
		(net 117)
	)
	(segment
		(start 58.79 80.545)
		(end 59.535 79.8)
		(width 0.3)
		(layer "B.Cu")
		(net 117)
	)
	(segment
		(start 73.86 78.15)
		(end 74.12 77.89)
		(width 0.15)
		(layer "B.Cu")
		(net 117)
	)
	(segment
		(start 56.45 79.38)
		(end 57.175 80.105)
		(width 0.3)
		(layer "B.Cu")
		(net 117)
	)
	(segment
		(start 74.12 77.89)
		(end 74.12 77.51)
		(width 0.15)
		(layer "B.Cu")
		(net 117)
	)
	(segment
		(start 68 75.25)
		(end 68 75.65)
		(width 0.3)
		(layer "B.Cu")
		(net 117)
	)
	(segment
		(start 56.45 78.45)
		(end 56.45 79.38)
		(width 0.3)
		(layer "B.Cu")
		(net 117)
	)
	(segment
		(start 68 74.8)
		(end 68 75.05)
		(width 0.3)
		(layer "B.Cu")
		(net 117)
	)
	(segment
		(start 70.2 79.57)
		(end 69.8 79.97)
		(width 0.5)
		(layer "B.Cu")
		(net 117)
	)
	(segment
		(start 70.2 78.76)
		(end 70.2 79.4)
		(width 0.3)
		(layer "B.Cu")
		(net 117)
	)
	(segment
		(start 69.69 77.77)
		(end 69.69 76.287)
		(width 0.3)
		(layer "B.Cu")
		(net 117)
	)
	(segment
		(start 69.69 76.287)
		(end 69.6 76.197)
		(width 0.3)
		(layer "B.Cu")
		(net 117)
	)
	(segment
		(start 55.28 78.77)
		(end 55.28 78.12)
		(width 0.3)
		(layer "B.Cu")
		(net 117)
	)
	(segment
		(start 67.15 75.25)
		(end 66.035 75.25)
		(width 0.3)
		(layer "B.Cu")
		(net 117)
	)
	(segment
		(start 69.69 78.25)
		(end 70.2 78.76)
		(width 0.3)
		(layer "B.Cu")
		(net 117)
	)
	(segment
		(start 68 74.8)
		(end 68.01 74.8)
		(width 0.3)
		(layer "B.Cu")
		(net 117)
	)
	(segment
		(start 64.075 78.125)
		(end 64.075 76.5)
		(width 0.3)
		(layer "B.Cu")
		(net 117)
	)
	(segment
		(start 70.91 77.77)
		(end 71.29 78.15)
		(width 0.15)
		(layer "B.Cu")
		(net 117)
	)
	(segment
		(start 65.11 124.57)
		(end 63.535 126.145)
		(width 0.15)
		(layer "B.Cu")
		(net 117)
	)
	(segment
		(start 68.185 74.625)
		(end 68.185 72.9)
		(width 0.3)
		(layer "B.Cu")
		(net 117)
	)
	(segment
		(start 57.653406 80.105)
		(end 58.093406 80.545)
		(width 0.3)
		(layer "B.Cu")
		(net 117)
	)
	(segment
		(start 69.69 77.77)
		(end 69.69 78.25)
		(width 0.3)
		(layer "B.Cu")
		(net 117)
	)
	(segment
		(start 55.28 78.12)
		(end 55.3 78.1)
		(width 0.3)
		(layer "B.Cu")
		(net 117)
	)
	(segment
		(start 67.15 75.25)
		(end 67.8 75.25)
		(width 0.3)
		(layer "B.Cu")
		(net 117)
	)
	(segment
		(start 68.547 76.197)
		(end 68 75.65)
		(width 0.3)
		(layer "B.Cu")
		(net 117)
	)
	(segment
		(start 68.165 124.57)
		(end 65.11 124.57)
		(width 0.15)
		(layer "B.Cu")
		(net 117)
	)
	(segment
		(start 55.28 78.77)
		(end 55.25 78.8)
		(width 0.3)
		(layer "B.Cu")
		(net 117)
	)
	(segment
		(start 56.1 78.1)
		(end 56.45 78.45)
		(width 0.3)
		(layer "B.Cu")
		(net 117)
	)
	(segment
		(start 66.035 75.25)
		(end 65.785 75.5)
		(width 0.3)
		(layer "B.Cu")
		(net 117)
	)
	(segment
		(start 68 75.65)
		(end 68 75.45)
		(width 0.3)
		(layer "B.Cu")
		(net 117)
	)
	(segment
		(start 68 75.25)
		(end 68 74.8)
		(width 0.3)
		(layer "B.Cu")
		(net 117)
	)
	(segment
		(start 57.175 80.105)
		(end 57.653406 80.105)
		(width 0.3)
		(layer "B.Cu")
		(net 117)
	)
	(segment
		(start 63.2 76.6)
		(end 63.3 76.5)
		(width 0.3)
		(layer "B.Cu")
		(net 117)
	)
	(segment
		(start 67.8 75.25)
		(end 68 75.25)
		(width 0.3)
		(layer "B.Cu")
		(net 117)
	)
	(segment
		(start 69.6 76.197)
		(end 68.547 76.197)
		(width 0.3)
		(layer "B.Cu")
		(net 117)
	)
	(segment
		(start 55.3 78.1)
		(end 56.1 78.1)
		(width 0.3)
		(layer "B.Cu")
		(net 117)
	)
	(segment
		(start 69.8 79.97)
		(end 69.8 80.49)
		(width 0.5)
		(layer "B.Cu")
		(net 117)
	)
	(segment
		(start 59.535 79.8)
		(end 62.4 79.8)
		(width 0.3)
		(layer "B.Cu")
		(net 117)
	)
	(segment
		(start 114.25 94.45)
		(end 113.961091 94.45)
		(width 0.15)
		(layer "F.Cu")
		(net 118)
	)
	(segment
		(start 120.85 87.1)
		(end 121.2 87.1)
		(width 0.15)
		(layer "F.Cu")
		(net 118)
	)
	(segment
		(start 114.011092 92.6)
		(end 118.55 92.6)
		(width 0.15)
		(layer "F.Cu")
		(net 118)
	)
	(segment
		(start 120.2 90.95)
		(end 120.2 89.35)
		(width 0.15)
		(layer "F.Cu")
		(net 118)
	)
	(segment
		(start 113.525 93.086092)
		(end 114.011092 92.6)
		(width 0.15)
		(layer "F.Cu")
		(net 118)
	)
	(segment
		(start 113.961091 94.45)
		(end 113.525 94.013909)
		(width 0.15)
		(layer "F.Cu")
		(net 118)
	)
	(segment
		(start 101.6 78.36)
		(end 101.6 75.575)
		(width 0.15)
		(layer "F.Cu")
		(net 118)
	)
	(segment
		(start 120.2 89.35)
		(end 120.1 89.25)
		(width 0.15)
		(layer "F.Cu")
		(net 118)
	)
	(segment
		(start 113.525 94.013909)
		(end 113.525 93.086092)
		(width 0.15)
		(layer "F.Cu")
		(net 118)
	)
	(segment
		(start 100.597323 74.572323)
		(end 100.597323 72.005136)
		(width 0.15)
		(layer "F.Cu")
		(net 118)
	)
	(segment
		(start 120.1 89.25)
		(end 120.1 87.85)
		(width 0.15)
		(layer "F.Cu")
		(net 118)
	)
	(segment
		(start 101.6 75.575)
		(end 100.597323 74.572323)
		(width 0.15)
		(layer "F.Cu")
		(net 118)
	)
	(segment
		(start 120.1 87.85)
		(end 120.85 87.1)
		(width 0.15)
		(layer "F.Cu")
		(net 118)
	)
	(segment
		(start 118.55 92.6)
		(end 120.2 90.95)
		(width 0.15)
		(layer "F.Cu")
		(net 118)
	)
	(via
		(at 121.2 87.1)
		(size 0.45)
		(drill 0.1)
		(layers "F.Cu" "B.Cu")
		(net 118)
	)
	(via
		(at 101.6 78.36)
		(size 0.45)
		(drill 0.1)
		(layers "F.Cu" "B.Cu")
		(net 118)
	)
	(segment
		(start 109.5 75.1)
		(end 110.7 76.3)
		(width 0.15)
		(layer "In5.Cu")
		(net 118)
	)
	(segment
		(start 113.65 77.4)
		(end 115.5 77.4)
		(width 0.15)
		(layer "In5.Cu")
		(net 118)
	)
	(segment
		(start 118.2 81.05)
		(end 118.64 81.05)
		(width 0.15)
		(layer "In5.Cu")
		(net 118)
	)
	(segment
		(start 120.85 86.75)
		(end 121.2 87.1)
		(width 0.15)
		(layer "In5.Cu")
		(net 118)
	)
	(segment
		(start 101.6 77.875)
		(end 101.725 77.75)
		(width 0.15)
		(layer "In5.Cu")
		(net 118)
	)
	(segment
		(start 101.95 77.75)
		(end 103.95 75.75)
		(width 0.15)
		(layer "In5.Cu")
		(net 118)
	)
	(segment
		(start 112.55 76.3)
		(end 113.65 77.4)
		(width 0.15)
		(layer "In5.Cu")
		(net 118)
	)
	(segment
		(start 101.725 77.75)
		(end 101.95 77.75)
		(width 0.15)
		(layer "In5.Cu")
		(net 118)
	)
	(segment
		(start 110.7 76.3)
		(end 112.55 76.3)
		(width 0.15)
		(layer "In5.Cu")
		(net 118)
	)
	(segment
		(start 116.6 79.45)
		(end 118.2 81.05)
		(width 0.15)
		(layer "In5.Cu")
		(net 118)
	)
	(segment
		(start 118.64 81.05)
		(end 118.95 81.36)
		(width 0.15)
		(layer "In5.Cu")
		(net 118)
	)
	(segment
		(start 118.95 83.59)
		(end 119.86 84.5)
		(width 0.15)
		(layer "In5.Cu")
		(net 118)
	)
	(segment
		(start 107.15 75.75)
		(end 107.8 75.1)
		(width 0.15)
		(layer "In5.Cu")
		(net 118)
	)
	(segment
		(start 101.6 78.36)
		(end 101.6 77.875)
		(width 0.15)
		(layer "In5.Cu")
		(net 118)
	)
	(segment
		(start 115.5 77.4)
		(end 116.6 78.5)
		(width 0.15)
		(layer "In5.Cu")
		(net 118)
	)
	(segment
		(start 118.95 81.36)
		(end 118.95 83.59)
		(width 0.15)
		(layer "In5.Cu")
		(net 118)
	)
	(segment
		(start 103.95 75.75)
		(end 107.15 75.75)
		(width 0.15)
		(layer "In5.Cu")
		(net 118)
	)
	(segment
		(start 120.85 84.875)
		(end 120.85 86.75)
		(width 0.15)
		(layer "In5.Cu")
		(net 118)
	)
	(segment
		(start 107.8 75.1)
		(end 109.5 75.1)
		(width 0.15)
		(layer "In5.Cu")
		(net 118)
	)
	(segment
		(start 120.475 84.5)
		(end 120.85 84.875)
		(width 0.15)
		(layer "In5.Cu")
		(net 118)
	)
	(segment
		(start 119.86 84.5)
		(end 120.475 84.5)
		(width 0.15)
		(layer "In5.Cu")
		(net 118)
	)
	(segment
		(start 116.6 78.5)
		(end 116.6 79.45)
		(width 0.15)
		(layer "In5.Cu")
		(net 118)
	)
	(segment
		(start 113.95 94.05)
		(end 113.8 93.9)
		(width 0.15)
		(layer "F.Cu")
		(net 119)
	)
	(segment
		(start 114.05 92.95)
		(end 118.65 92.95)
		(width 0.15)
		(layer "F.Cu")
		(net 119)
	)
	(segment
		(start 120.375 89.075)
		(end 120.375 88.275)
		(width 0.15)
		(layer "F.Cu")
		(net 119)
	)
	(segment
		(start 120.375 88.275)
		(end 121.05 87.6)
		(width 0.15)
		(layer "F.Cu")
		(net 119)
	)
	(segment
		(start 120.5 89.2)
		(end 120.375 89.075)
		(width 0.15)
		(layer "F.Cu")
		(net 119)
	)
	(segment
		(start 121.55 87.6)
		(end 121.85 87.3)
		(width 0.15)
		(layer "F.Cu")
		(net 119)
	)
	(segment
		(start 100.4 78.35)
		(end 100.425 78.325)
		(width 0.15)
		(layer "F.Cu")
		(net 119)
	)
	(segment
		(start 121.05 87.6)
		(end 121.55 87.6)
		(width 0.15)
		(layer "F.Cu")
		(net 119)
	)
	(segment
		(start 100.425 75.175)
		(end 100.097323 74.847323)
		(width 0.15)
		(layer "F.Cu")
		(net 119)
	)
	(segment
		(start 113.8 93.2)
		(end 114.05 92.95)
		(width 0.15)
		(layer "F.Cu")
		(net 119)
	)
	(segment
		(start 121.85 87.3)
		(end 121.85 86.975)
		(width 0.15)
		(layer "F.Cu")
		(net 119)
	)
	(segment
		(start 113.8 93.9)
		(end 113.8 93.2)
		(width 0.15)
		(layer "F.Cu")
		(net 119)
	)
	(segment
		(start 114.25 94.05)
		(end 113.95 94.05)
		(width 0.15)
		(layer "F.Cu")
		(net 119)
	)
	(segment
		(start 100.097323 74.847323)
		(end 100.097323 72.005136)
		(width 0.15)
		(layer "F.Cu")
		(net 119)
	)
	(segment
		(start 118.65 92.95)
		(end 120.5 91.1)
		(width 0.15)
		(layer "F.Cu")
		(net 119)
	)
	(segment
		(start 100.425 78.325)
		(end 100.425 75.175)
		(width 0.15)
		(layer "F.Cu")
		(net 119)
	)
	(segment
		(start 120.5 91.1)
		(end 120.5 89.2)
		(width 0.15)
		(layer "F.Cu")
		(net 119)
	)
	(via
		(at 100.4 78.35)
		(size 0.45)
		(drill 0.1)
		(layers "F.Cu" "B.Cu")
		(net 119)
	)
	(via
		(at 121.85 86.975)
		(size 0.45)
		(drill 0.1)
		(layers "F.Cu" "B.Cu")
		(net 119)
	)
	(segment
		(start 109.65 74.8)
		(end 110.85 76)
		(width 0.15)
		(layer "In5.Cu")
		(net 119)
	)
	(segment
		(start 100.4 78.35)
		(end 100.5 78.35)
		(width 0.15)
		(layer "In5.Cu")
		(net 119)
	)
	(segment
		(start 121.3 84.85)
		(end 121.3 86.425)
		(width 0.15)
		(layer "In5.Cu")
		(net 119)
	)
	(segment
		(start 107.65 74.8)
		(end 109.65 74.8)
		(width 0.15)
		(layer "In5.Cu")
		(net 119)
	)
	(segment
		(start 107 75.45)
		(end 107.65 74.8)
		(width 0.15)
		(layer "In5.Cu")
		(net 119)
	)
	(segment
		(start 101.425 77.425)
		(end 101.825 77.425)
		(width 0.15)
		(layer "In5.Cu")
		(net 119)
	)
	(segment
		(start 110.85 76)
		(end 112.7 76)
		(width 0.15)
		(layer "In5.Cu")
		(net 119)
	)
	(segment
		(start 120.045 84.225)
		(end 120.675 84.225)
		(width 0.15)
		(layer "In5.Cu")
		(net 119)
	)
	(segment
		(start 112.7 76)
		(end 113.8 77.1)
		(width 0.15)
		(layer "In5.Cu")
		(net 119)
	)
	(segment
		(start 119.35 83.53)
		(end 120.045 84.225)
		(width 0.15)
		(layer "In5.Cu")
		(net 119)
	)
	(segment
		(start 121.3 86.425)
		(end 121.85 86.975)
		(width 0.15)
		(layer "In5.Cu")
		(net 119)
	)
	(segment
		(start 115.65 77.1)
		(end 119.35 80.8)
		(width 0.15)
		(layer "In5.Cu")
		(net 119)
	)
	(segment
		(start 113.8 77.1)
		(end 115.65 77.1)
		(width 0.15)
		(layer "In5.Cu")
		(net 119)
	)
	(segment
		(start 101.825 77.425)
		(end 103.8 75.45)
		(width 0.15)
		(layer "In5.Cu")
		(net 119)
	)
	(segment
		(start 100.5 78.35)
		(end 101.425 77.425)
		(width 0.15)
		(layer "In5.Cu")
		(net 119)
	)
	(segment
		(start 120.675 84.225)
		(end 121.3 84.85)
		(width 0.15)
		(layer "In5.Cu")
		(net 119)
	)
	(segment
		(start 119.35 80.8)
		(end 119.35 83.53)
		(width 0.15)
		(layer "In5.Cu")
		(net 119)
	)
	(segment
		(start 103.8 75.45)
		(end 107 75.45)
		(width 0.15)
		(layer "In5.Cu")
		(net 119)
	)
	(segment
		(start 149.275 96.95)
		(end 149.275 95.005)
		(width 0.15)
		(layer "F.Cu")
		(net 120)
	)
	(segment
		(start 147.55 97.725)
		(end 147.55 97.55)
		(width 0.15)
		(layer "F.Cu")
		(net 120)
	)
	(segment
		(start 147.55 97.55)
		(end 147.95 97.15)
		(width 0.15)
		(layer "F.Cu")
		(net 120)
	)
	(segment
		(start 149.075 97.15)
		(end 149.275 96.95)
		(width 0.15)
		(layer "F.Cu")
		(net 120)
	)
	(segment
		(start 148.97 94.7)
		(end 148.25 94.7)
		(width 0.15)
		(layer "F.Cu")
		(net 120)
	)
	(segment
		(start 68.6 70.93)
		(end 68.597323 70.932677)
		(width 0.15)
		(layer "F.Cu")
		(net 120)
	)
	(segment
		(start 68.597323 70.932677)
		(end 68.597323 72.005136)
		(width 0.15)
		(layer "F.Cu")
		(net 120)
	)
	(segment
		(start 147.95 97.15)
		(end 149.075 97.15)
		(width 0.15)
		(layer "F.Cu")
		(net 120)
	)
	(segment
		(start 68.6 69.9755)
		(end 68.6 70.93)
		(width 0.15)
		(layer "F.Cu")
		(net 120)
	)
	(segment
		(start 149.275 95.005)
		(end 148.97 94.7)
		(width 0.15)
		(layer "F.Cu")
		(net 120)
	)
	(via
		(at 68.6 69.9755)
		(size 0.45)
		(drill 0.1)
		(layers "F.Cu" "B.Cu")
		(net 120)
	)
	(via
		(at 147.55 97.725)
		(size 0.45)
		(drill 0.1)
		(layers "F.Cu" "B.Cu")
		(net 120)
	)
	(segment
		(start 92.64 98.77)
		(end 92.64 103.96)
		(width 0.125)
		(layer "In5.Cu")
		(net 120)
	)
	(segment
		(start 123.75 110.4)
		(end 127.3 106.85)
		(width 0.125)
		(layer "In5.Cu")
		(net 120)
	)
	(segment
		(start 144.275 101.35)
		(end 147.55 98.075)
		(width 0.125)
		(layer "In5.Cu")
		(net 120)
	)
	(segment
		(start 135.91 104.69)
		(end 137.385 104.69)
		(width 0.125)
		(layer "In5.Cu")
		(net 120)
	)
	(segment
		(start 99.08 110.4)
		(end 123.75 110.4)
		(width 0.125)
		(layer "In5.Cu")
		(net 120)
	)
	(segment
		(start 78.05 80.15)
		(end 78.4 80.5)
		(width 0.125)
		(layer "In5.Cu")
		(net 120)
	)
	(segment
		(start 133.75 106.85)
		(end 135.91 104.69)
		(width 0.125)
		(layer "In5.Cu")
		(net 120)
	)
	(segment
		(start 127.3 106.85)
		(end 133.75 106.85)
		(width 0.125)
		(layer "In5.Cu")
		(net 120)
	)
	(segment
		(start 68.6 69.9755)
		(end 68.6 71.325)
		(width 0.125)
		(layer "In5.Cu")
		(net 120)
	)
	(segment
		(start 78.4 82.8)
		(end 79.4 83.8)
		(width 0.125)
		(layer "In5.Cu")
		(net 120)
	)
	(segment
		(start 139.15 102.27)
		(end 140.07 101.35)
		(width 0.125)
		(layer "In5.Cu")
		(net 120)
	)
	(segment
		(start 91.85 97.98)
		(end 92.64 98.77)
		(width 0.125)
		(layer "In5.Cu")
		(net 120)
	)
	(segment
		(start 73.72 78.12)
		(end 75.75 80.15)
		(width 0.125)
		(layer "In5.Cu")
		(net 120)
	)
	(segment
		(start 91.85 84.35)
		(end 91.85 97.98)
		(width 0.125)
		(layer "In5.Cu")
		(net 120)
	)
	(segment
		(start 73.72 73.47)
		(end 73.72 78.12)
		(width 0.125)
		(layer "In5.Cu")
		(net 120)
	)
	(segment
		(start 147.55 98.075)
		(end 147.55 97.725)
		(width 0.125)
		(layer "In5.Cu")
		(net 120)
	)
	(segment
		(start 137.385 104.69)
		(end 139.15 102.925)
		(width 0.125)
		(layer "In5.Cu")
		(net 120)
	)
	(segment
		(start 92.64 103.96)
		(end 99.08 110.4)
		(width 0.125)
		(layer "In5.Cu")
		(net 120)
	)
	(segment
		(start 68.6 71.325)
		(end 68.825 71.55)
		(width 0.125)
		(layer "In5.Cu")
		(net 120)
	)
	(segment
		(start 75.75 80.15)
		(end 78.05 80.15)
		(width 0.125)
		(layer "In5.Cu")
		(net 120)
	)
	(segment
		(start 79.4 83.8)
		(end 91.3 83.8)
		(width 0.125)
		(layer "In5.Cu")
		(net 120)
	)
	(segment
		(start 68.825 71.55)
		(end 71.8 71.55)
		(width 0.125)
		(layer "In5.Cu")
		(net 120)
	)
	(segment
		(start 71.8 71.55)
		(end 73.72 73.47)
		(width 0.125)
		(layer "In5.Cu")
		(net 120)
	)
	(segment
		(start 140.07 101.35)
		(end 144.275 101.35)
		(width 0.125)
		(layer "In5.Cu")
		(net 120)
	)
	(segment
		(start 78.4 80.5)
		(end 78.4 82.8)
		(width 0.125)
		(layer "In5.Cu")
		(net 120)
	)
	(segment
		(start 139.15 102.925)
		(end 139.15 102.27)
		(width 0.125)
		(layer "In5.Cu")
		(net 120)
	)
	(segment
		(start 91.3 83.8)
		(end 91.85 84.35)
		(width 0.125)
		(layer "In5.Cu")
		(net 120)
	)
	(segment
		(start 47.93 106.17)
		(end 49.31 107.55)
		(width 0.5)
		(layer "B.Cu")
		(net 121)
	)
	(segment
		(start 46.57 106.17)
		(end 47.93 106.17)
		(width 0.5)
		(layer "B.Cu")
		(net 121)
	)
	(segment
		(start 33.435 112.035)
		(end 31.9 110.5)
		(width 0.5)
		(layer "B.Cu")
		(net 121)
	)
	(segment
		(start 31.9 107.7)
		(end 33 106.6)
		(width 0.5)
		(layer "B.Cu")
		(net 121)
	)
	(segment
		(start 33 106.6)
		(end 46.14 106.6)
		(width 0.5)
		(layer "B.Cu")
		(net 121)
	)
	(segment
		(start 31.9 110.5)
		(end 31.9 107.7)
		(width 0.5)
		(layer "B.Cu")
		(net 121)
	)
	(segment
		(start 46.14 106.6)
		(end 46.57 106.17)
		(width 0.5)
		(layer "B.Cu")
		(net 121)
	)
	(segment
		(start 33.435 113.696397)
		(end 33.435 112.035)
		(width 0.5)
		(layer "B.Cu")
		(net 121)
	)
	(segment
		(start 37.71 107.39)
		(end 37.3 107.8)
		(width 0.5)
		(layer "B.Cu")
		(net 122)
	)
	(segment
		(start 46.77 107.55)
		(end 46.61 107.39)
		(width 0.5)
		(layer "B.Cu")
		(net 122)
	)
	(segment
		(start 37.3 107.8)
		(end 37.3 109.2)
		(width 0.5)
		(layer "B.Cu")
		(net 122)
	)
	(segment
		(start 46.61 107.39)
		(end 37.71 107.39)
		(width 0.5)
		(layer "B.Cu")
		(net 122)
	)
	(segment
		(start 37.3 109.2)
		(end 35.975 110.525)
		(width 0.5)
		(layer "B.Cu")
		(net 122)
	)
	(segment
		(start 35.975 110.525)
		(end 35.975 114.956397)
		(width 0.5)
		(layer "B.Cu")
		(net 122)
	)
	(segment
		(start 43.6 110.5)
		(end 43.6 112.3)
		(width 0.5)
		(layer "B.Cu")
		(net 123)
	)
	(segment
		(start 42.325 113.575)
		(end 42.325 114.956397)
		(width 0.5)
		(layer "B.Cu")
		(net 123)
	)
	(segment
		(start 43.6 112.3)
		(end 42.325 113.575)
		(width 0.5)
		(layer "B.Cu")
		(net 123)
	)
	(segment
		(start 51.03 107.795)
		(end 50.135 108.69)
		(width 0.5)
		(layer "B.Cu")
		(net 123)
	)
	(segment
		(start 45.6 109.6)
		(end 44.5 109.6)
		(width 0.5)
		(layer "B.Cu")
		(net 123)
	)
	(segment
		(start 44.5 109.6)
		(end 43.6 110.5)
		(width 0.5)
		(layer "B.Cu")
		(net 123)
	)
	(segment
		(start 50.135 108.69)
		(end 46.51 108.69)
		(width 0.5)
		(layer "B.Cu")
		(net 123)
	)
	(segment
		(start 51.03 107.55)
		(end 51.03 107.795)
		(width 0.5)
		(layer "B.Cu")
		(net 123)
	)
	(segment
		(start 46.51 108.69)
		(end 45.6 109.6)
		(width 0.5)
		(layer "B.Cu")
		(net 123)
	)
	(segment
		(start 50.586656 109.35)
		(end 51.076656 108.86)
		(width 0.5)
		(layer "B.Cu")
		(net 124)
	)
	(segment
		(start 46.019565 110.457091)
		(end 47.126656 109.35)
		(width 0.5)
		(layer "B.Cu")
		(net 124)
	)
	(segment
		(start 47.126656 109.35)
		(end 50.586656 109.35)
		(width 0.5)
		(layer "B.Cu")
		(net 124)
	)
	(segment
		(start 51.076656 108.86)
		(end 52.26 108.86)
		(width 0.5)
		(layer "B.Cu")
		(net 124)
	)
	(segment
		(start 52.26 108.86)
		(end 53.57 107.55)
		(width 0.5)
		(layer "B.Cu")
		(net 124)
	)
	(segment
		(start 46.019565 112.580435)
		(end 46.019565 110.457091)
		(width 0.5)
		(layer "B.Cu")
		(net 124)
	)
	(segment
		(start 44.913603 113.686397)
		(end 46.019565 112.580435)
		(width 0.5)
		(layer "B.Cu")
		(net 124)
	)
	(segment
		(start 77 115.115)
		(end 77 115.885)
		(width 0.165)
		(layer "F.Cu")
		(net 125)
	)
	(segment
		(start 76.93 109.441425)
		(end 76.6005 109.111925)
		(width 0.155)
		(layer "F.Cu")
		(net 125)
	)
	(segment
		(start 76.6005 108.817969)
		(end 76.55 108.767469)
		(width 0.155)
		(layer "F.Cu")
		(net 125)
	)
	(segment
		(start 77.1005 113.3505)
		(end 77.1005 114.601999)
		(width 0.155)
		(layer "F.Cu")
		(net 125)
	)
	(segment
		(start 76.95 113.2)
		(end 77.1005 113.3505)
		(width 0.155)
		(layer "F.Cu")
		(net 125)
	)
	(segment
		(start 76.93 109.66)
		(end 76.93 109.441425)
		(width 0.155)
		(layer "F.Cu")
		(net 125)
	)
	(segment
		(start 77 116.01)
		(end 77.1005 116.1105)
		(width 0.155)
		(layer "F.Cu")
		(net 125)
	)
	(segment
		(start 76.600425 117.058149)
		(end 76.600425 117.564505)
		(width 0.155)
		(layer "F.Cu")
		(net 125)
	)
	(segment
		(start 77.1005 116.1105)
		(end 77.1005 116.558074)
		(width 0.155)
		(layer "F.Cu")
		(net 125)
	)
	(segment
		(start 76.600425 117.564505)
		(end 76.49993 117.665)
		(width 0.155)
		(layer "F.Cu")
		(net 125)
	)
	(segment
		(start 77 114.702499)
		(end 77 115.115)
		(width 0.155)
		(layer "F.Cu")
		(net 125)
	)
	(segment
		(start 76.6005 109.111925)
		(end 76.6005 108.817969)
		(width 0.155)
		(layer "F.Cu")
		(net 125)
	)
	(segment
		(start 77.1005 116.558074)
		(end 76.600425 117.058149)
		(width 0.155)
		(layer "F.Cu")
		(net 125)
	)
	(segment
		(start 77.1005 114.601999)
		(end 77 114.702499)
		(width 0.155)
		(layer "F.Cu")
		(net 125)
	)
	(via
		(at 76.95 113.2)
		(size 0.45)
		(drill 0.1)
		(layers "F.Cu" "B.Cu")
		(net 125)
	)
	(via
		(at 76.93 109.66)
		(size 0.45)
		(drill 0.1)
		(layers "F.Cu" "B.Cu")
		(net 125)
	)
	(segment
		(start 77.076 113.074)
		(end 76.95 113.2)
		(width 0.16)
		(layer "In3.Cu")
		(net 125)
	)
	(segment
		(start 76.95 109.66)
		(end 77.27 109.98)
		(width 0.16)
		(layer "In3.Cu")
		(net 125)
	)
	(segment
		(start 77.27 110.844282)
		(end 77.076 111.038282)
		(width 0.16)
		(layer "In3.Cu")
		(net 125)
	)
	(segment
		(start 77.27 109.98)
		(end 77.27 110.844282)
		(width 0.16)
		(layer "In3.Cu")
		(net 125)
	)
	(segment
		(start 76.93 109.66)
		(end 76.95 109.66)
		(width 0.16)
		(layer "In3.Cu")
		(net 125)
	)
	(segment
		(start 77.076 111.038282)
		(end 77.076 113.074)
		(width 0.16)
		(layer "In3.Cu")
		(net 125)
	)
	(segment
		(start 51.35 115)
		(end 50.285 115)
		(width 0.15)
		(layer "B.Cu")
		(net 126)
	)
	(segment
		(start 50.285 115)
		(end 50.235 115.05)
		(width 0.15)
		(layer "B.Cu")
		(net 126)
	)
	(segment
		(start 50.23 115.12)
		(end 50.23 115)
		(width 0.15)
		(layer "B.Cu")
		(net 126)
	)
	(segment
		(start 51.6 114.225)
		(end 51.6 114.75)
		(width 0.15)
		(layer "B.Cu")
		(net 126)
	)
	(segment
		(start 49.495 116)
		(end 49.495 115.855)
		(width 0.15)
		(layer "B.Cu")
		(net 126)
	)
	(segment
		(start 51.6 114.75)
		(end 51.35 115)
		(width 0.15)
		(layer "B.Cu")
		(net 126)
	)
	(segment
		(start 49.495 115.855)
		(end 50.23 115.12)
		(width 0.15)
		(layer "B.Cu")
		(net 126)
	)
	(segment
		(start 49.265 116)
		(end 49.265 115.97)
		(width 0.15)
		(layer "B.Cu")
		(net 126)
	)
	(segment
		(start 40.73 105.791)
		(end 40.415 105.476)
		(width 0.15)
		(layer "F.Cu")
		(net 127)
	)
	(segment
		(start 39.871 105.471)
		(end 40.415 105.471)
		(width 0.15)
		(layer "F.Cu")
		(net 127)
	)
	(segment
		(start 42.653 105.791)
		(end 40.73 105.791)
		(width 0.15)
		(layer "F.Cu")
		(net 127)
	)
	(segment
		(start 38.68 104.7)
		(end 39.1 104.7)
		(width 0.15)
		(layer "F.Cu")
		(net 127)
	)
	(segment
		(start 42.759 105.685)
		(end 43.33 105.685)
		(width 0.15)
		(layer "F.Cu")
		(net 127)
	)
	(segment
		(start 44.141 104.874)
		(end 44.701 104.874)
		(width 0.15)
		(layer "F.Cu")
		(net 127)
	)
	(segment
		(start 50.39 102.415)
		(end 50.39 102.75)
		(width 0.15)
		(layer "F.Cu")
		(net 127)
	)
	(segment
		(start 49.975 102)
		(end 50.39 102.415)
		(width 0.15)
		(layer "F.Cu")
		(net 127)
	)
	(segment
		(start 44.701 104.874)
		(end 47.575 102)
		(width 0.15)
		(layer "F.Cu")
		(net 127)
	)
	(segment
		(start 47.575 102)
		(end 49.975 102)
		(width 0.15)
		(layer "F.Cu")
		(net 127)
	)
	(segment
		(start 42.653 105.791)
		(end 42.759 105.685)
		(width 0.15)
		(layer "F.Cu")
		(net 127)
	)
	(segment
		(start 39.1 104.7)
		(end 39.871 105.471)
		(width 0.15)
		(layer "F.Cu")
		(net 127)
	)
	(segment
		(start 43.33 105.685)
		(end 44.141 104.874)
		(width 0.15)
		(layer "F.Cu")
		(net 127)
	)
	(via
		(at 56.66428 100.75)
		(size 0.45)
		(drill 0.1)
		(layers "F.Cu" "B.Cu")
		(net 127)
	)
	(via
		(at 50.39 102.75)
		(size 0.45)
		(drill 0.1)
		(layers "F.Cu" "B.Cu")
		(net 127)
	)
	(segment
		(start 52.4 100.74)
		(end 50.39 102.75)
		(width 0.15)
		(layer "In5.Cu")
		(net 127)
	)
	(segment
		(start 56.66428 100.75)
		(end 56.65428 100.74)
		(width 0.15)
		(layer "In5.Cu")
		(net 127)
	)
	(segment
		(start 56.65428 100.74)
		(end 52.4 100.74)
		(width 0.15)
		(layer "In5.Cu")
		(net 127)
	)
	(segment
		(start 52.95 84.38)
		(end 51.96 84.38)
		(width 0.13)
		(layer "B.Cu")
		(net 127)
	)
	(segment
		(start 57.26 97.78)
		(end 57.01 97.53)
		(width 0.13)
		(layer "B.Cu")
		(net 127)
	)
	(segment
		(start 56.172771 89.427229)
		(end 56.172771 86.197771)
		(width 0.13)
		(layer "B.Cu")
		(net 127)
	)
	(segment
		(start 56.66428 100.75)
		(end 57.26 100.15428)
		(width 0.15)
		(layer "B.Cu")
		(net 127)
	)
	(segment
		(start 57.01 97.53)
		(end 55.915 97.53)
		(width 0.13)
		(layer "B.Cu")
		(net 127)
	)
	(segment
		(start 55.725 95.305)
		(end 55.725 89.875)
		(width 0.13)
		(layer "B.Cu")
		(net 127)
	)
	(segment
		(start 55.7625 85.7875)
		(end 54.3575 85.7875)
		(width 0.13)
		(layer "B.Cu")
		(net 127)
	)
	(segment
		(start 55.23 95.8)
		(end 55.725 95.305)
		(width 0.13)
		(layer "B.Cu")
		(net 127)
	)
	(segment
		(start 57.26 100.15428)
		(end 57.26 98.801)
		(width 0.15)
		(layer "B.Cu")
		(net 127)
	)
	(segment
		(start 55.23 96.845)
		(end 55.23 95.8)
		(width 0.13)
		(layer "B.Cu")
		(net 127)
	)
	(segment
		(start 54.3575 85.7875)
		(end 52.95 84.38)
		(width 0.13)
		(layer "B.Cu")
		(net 127)
	)
	(segment
		(start 57.26 98.801)
		(end 57.26 97.78)
		(width 0.13)
		(layer "B.Cu")
		(net 127)
	)
	(segment
		(start 51.96 84.38)
		(end 51.5 83.92)
		(width 0.13)
		(layer "B.Cu")
		(net 127)
	)
	(segment
		(start 56.172771 86.197771)
		(end 55.7625 85.7875)
		(width 0.13)
		(layer "B.Cu")
		(net 127)
	)
	(segment
		(start 55.915 97.53)
		(end 55.23 96.845)
		(width 0.13)
		(layer "B.Cu")
		(net 127)
	)
	(segment
		(start 55.725 89.875)
		(end 56.172771 89.427229)
		(width 0.13)
		(layer "B.Cu")
		(net 127)
	)
	(segment
		(start 148.755 95.25)
		(end 148.83 95.175)
		(width 0.15)
		(layer "F.Cu")
		(net 128)
	)
	(segment
		(start 68.1 69.6)
		(end 68.097323 69.602677)
		(width 0.15)
		(layer "F.Cu")
		(net 128)
	)
	(segment
		(start 68.097323 71.097323)
		(end 68.1 71.1)
		(width 0.15)
		(layer "F.Cu")
		(net 128)
	)
	(segment
		(start 68.1 71.1)
		(end 68.1 71.18)
		(width 0.15)
		(layer "F.Cu")
		(net 128)
	)
	(segment
		(start 68.097323 69.602677)
		(end 68.097323 71.097323)
		(width 0.15)
		(layer "F.Cu")
		(net 128)
	)
	(segment
		(start 148.25 95.25)
		(end 148.755 95.25)
		(width 0.15)
		(layer "F.Cu")
		(net 128)
	)
	(via
		(at 68.1 69.6)
		(size 0.45)
		(drill 0.1)
		(layers "F.Cu" "B.Cu")
		(net 128)
	)
	(via
		(at 148.83 95.175)
		(size 0.45)
		(drill 0.1)
		(layers "F.Cu" "B.Cu")
		(net 128)
	)
	(via
		(at 139.34 103.93)
		(size 0.45)
		(drill 0.1)
		(layers "F.Cu" "B.Cu")
		(net 128)
	)
	(via
		(at 140.34 100.55)
		(size 0.45)
		(drill 0.1)
		(layers "F.Cu" "B.Cu")
		(net 128)
	)
	(segment
		(start 78.1 82.9)
		(end 78.1 80.6)
		(width 0.125)
		(layer "In5.Cu")
		(net 128)
	)
	(segment
		(start 77.93 80.43)
		(end 75.63 80.43)
		(width 0.125)
		(layer "In5.Cu")
		(net 128)
	)
	(segment
		(start 91.1 84.05)
		(end 79.25 84.05)
		(width 0.125)
		(layer "In5.Cu")
		(net 128)
	)
	(segment
		(start 148.83 95.175)
		(end 148.305 95.175)
		(width 0.15)
		(layer "In5.Cu")
		(net 128)
	)
	(segment
		(start 78.1 80.6)
		(end 77.93 80.43)
		(width 0.125)
		(layer "In5.Cu")
		(net 128)
	)
	(segment
		(start 142.93 100.55)
		(end 140.34 100.55)
		(width 0.15)
		(layer "In5.Cu")
		(net 128)
	)
	(segment
		(start 73.43 78.23)
		(end 73.43 73.59)
		(width 0.125)
		(layer "In5.Cu")
		(net 128)
	)
	(segment
		(start 75.63 80.43)
		(end 73.43 78.23)
		(width 0.125)
		(layer "In5.Cu")
		(net 128)
	)
	(segment
		(start 99.58 111.3)
		(end 92.39 104.11)
		(width 0.125)
		(layer "In5.Cu")
		(net 128)
	)
	(segment
		(start 68.4 71.85)
		(end 68.1 71.55)
		(width 0.125)
		(layer "In5.Cu")
		(net 128)
	)
	(segment
		(start 127.42 107.18)
		(end 123.3 111.3)
		(width 0.125)
		(layer "In5.Cu")
		(net 128)
	)
	(segment
		(start 138.29 104.98)
		(end 136.05 104.98)
		(width 0.125)
		(layer "In5.Cu")
		(net 128)
	)
	(segment
		(start 91.593119 98.083119)
		(end 91.593119 84.543119)
		(width 0.125)
		(layer "In5.Cu")
		(net 128)
	)
	(segment
		(start 79.25 84.05)
		(end 78.1 82.9)
		(width 0.125)
		(layer "In5.Cu")
		(net 128)
	)
	(segment
		(start 91.593119 84.543119)
		(end 91.1 84.05)
		(width 0.125)
		(layer "In5.Cu")
		(net 128)
	)
	(segment
		(start 139.34 103.93)
		(end 138.29 104.98)
		(width 0.125)
		(layer "In5.Cu")
		(net 128)
	)
	(segment
		(start 68.1 71.55)
		(end 68.1 69.6)
		(width 0.125)
		(layer "In5.Cu")
		(net 128)
	)
	(segment
		(start 136.05 104.98)
		(end 133.85 107.18)
		(width 0.125)
		(layer "In5.Cu")
		(net 128)
	)
	(segment
		(start 92.39 98.88)
		(end 91.593119 98.083119)
		(width 0.125)
		(layer "In5.Cu")
		(net 128)
	)
	(segment
		(start 73.43 73.59)
		(end 71.69 71.85)
		(width 0.125)
		(layer "In5.Cu")
		(net 128)
	)
	(segment
		(start 148.305 95.175)
		(end 142.93 100.55)
		(width 0.15)
		(layer "In5.Cu")
		(net 128)
	)
	(segment
		(start 133.85 107.18)
		(end 127.42 107.18)
		(width 0.125)
		(layer "In5.Cu")
		(net 128)
	)
	(segment
		(start 123.3 111.3)
		(end 99.58 111.3)
		(width 0.125)
		(layer "In5.Cu")
		(net 128)
	)
	(segment
		(start 71.69 71.85)
		(end 68.4 71.85)
		(width 0.125)
		(layer "In5.Cu")
		(net 128)
	)
	(segment
		(start 92.39 104.11)
		(end 92.39 98.88)
		(width 0.125)
		(layer "In5.Cu")
		(net 128)
	)
	(segment
		(start 139.34 101.55)
		(end 140.34 100.55)
		(width 0.15)
		(layer "B.Cu")
		(net 128)
	)
	(segment
		(start 139.34 103.93)
		(end 139.34 101.55)
		(width 0.15)
		(layer "B.Cu")
		(net 128)
	)
	(segment
		(start 65.3 83.159789)
		(end 65.047289 83.4125)
		(width 0.125)
		(layer "F.Cu")
		(net 129)
	)
	(segment
		(start 66.347323 81.373337)
		(end 65.3 82.42066)
		(width 0.125)
		(layer "F.Cu")
		(net 129)
	)
	(segment
		(start 65.3 82.42066)
		(end 65.3 83.159789)
		(width 0.125)
		(layer "F.Cu")
		(net 129)
	)
	(segment
		(start 131.315 109.65)
		(end 132.85 109.65)
		(width 0.15)
		(layer "F.Cu")
		(net 129)
	)
	(segment
		(start 64.61 83.4125)
		(end 64.31 83.1125)
		(width 0.125)
		(layer "F.Cu")
		(net 129)
	)
	(segment
		(start 65.047289 83.4125)
		(end 64.61 83.4125)
		(width 0.125)
		(layer "F.Cu")
		(net 129)
	)
	(segment
		(start 132.85 109.65)
		(end 132.95 109.75)
		(width 0.15)
		(layer "F.Cu")
		(net 129)
	)
	(segment
		(start 66.347323 80.205136)
		(end 66.347323 81.373337)
		(width 0.125)
		(layer "F.Cu")
		(net 129)
	)
	(segment
		(start 148.485 109.5)
		(end 149.1 109.5)
		(width 0.15)
		(layer "F.Cu")
		(net 129)
	)
	(via
		(at 64.31 83.1125)
		(size 0.45)
		(drill 0.1)
		(layers "F.Cu" "B.Cu")
		(net 129)
	)
	(via
		(at 132.95 109.75)
		(size 0.45)
		(drill 0.1)
		(layers "F.Cu" "B.Cu")
		(net 129)
	)
	(via
		(at 149.1 109.5)
		(size 0.45)
		(drill 0.1)
		(layers "F.Cu" "B.Cu")
		(net 129)
	)
	(segment
		(start 124.783304 121.697645)
		(end 125.147903 121.659324)
		(width 0.125)
		(layer "In3.Cu")
		(net 129)
	)
	(segment
		(start 127.537397 120.107568)
		(end 127.720701 119.790077)
		(width 0.125)
		(layer "In3.Cu")
		(net 129)
	)
	(segment
		(start 67.1 122.4)
		(end 81.9 122.4)
		(width 0.125)
		(layer "In3.Cu")
		(net 129)
	)
	(segment
		(start 133.125 109.575)
		(end 132.95 109.75)
		(width 0.15)
		(layer "In3.Cu")
		(net 129)
	)
	(segment
		(start 148.85 109.25)
		(end 135.45 109.25)
		(width 0.15)
		(layer "In3.Cu")
		(net 129)
	)
	(segment
		(start 64.31 83.1125)
		(end 64.3 83.1225)
		(width 0.15)
		(layer "In3.Cu")
		(net 129)
	)
	(segment
		(start 128.1 112.1)
		(end 130.6 109.6)
		(width 0.125)
		(layer "In3.Cu")
		(net 129)
	)
	(segment
		(start 124.6 121.7)
		(end 124.783304 121.697645)
		(width 0.125)
		(layer "In3.Cu")
		(net 129)
	)
	(segment
		(start 123.1 121.7)
		(end 124.6 121.7)
		(width 0.125)
		(layer "In3.Cu")
		(net 129)
	)
	(segment
		(start 132.8 109.6)
		(end 132.95 109.75)
		(width 0.125)
		(layer "In3.Cu")
		(net 129)
	)
	(segment
		(start 135.45 109.25)
		(end 134.9 108.7)
		(width 0.15)
		(layer "In3.Cu")
		(net 129)
	)
	(segment
		(start 128.1 118.2)
		(end 128.1 112.1)
		(width 0.125)
		(layer "In3.Cu")
		(net 129)
	)
	(segment
		(start 133.375 109.326041)
		(end 133.126041 109.575)
		(width 0.15)
		(layer "In3.Cu")
		(net 129)
	)
	(segment
		(start 64.3 86.4)
		(end 63 87.7)
		(width 0.15)
		(layer "In3.Cu")
		(net 129)
	)
	(segment
		(start 134.9 108.7)
		(end 134 108.7)
		(width 0.15)
		(layer "In3.Cu")
		(net 129)
	)
	(segment
		(start 127.321911 120.40416)
		(end 127.537397 120.107568)
		(width 0.125)
		(layer "In3.Cu")
		(net 129)
	)
	(segment
		(start 133.375 109.325)
		(end 133.375 109.326041)
		(width 0.15)
		(layer "In3.Cu")
		(net 129)
	)
	(segment
		(start 64.3 83.1225)
		(end 64.3 86.4)
		(width 0.15)
		(layer "In3.Cu")
		(net 129)
	)
	(segment
		(start 64 111.5)
		(end 66.05 113.55)
		(width 0.125)
		(layer "In3.Cu")
		(net 129)
	)
	(segment
		(start 62.4 97.72)
		(end 62.4 109.9)
		(width 0.15)
		(layer "In3.Cu")
		(net 129)
	)
	(segment
		(start 108.3 122.9)
		(end 121.9 122.9)
		(width 0.125)
		(layer "In3.Cu")
		(net 129)
	)
	(segment
		(start 126.507568 121.137397)
		(end 126.80416 120.921911)
		(width 0.125)
		(layer "In3.Cu")
		(net 129)
	)
	(segment
		(start 128.097645 118.383304)
		(end 128.1 118.2)
		(width 0.125)
		(layer "In3.Cu")
		(net 129)
	)
	(segment
		(start 128.059324 118.747903)
		(end 128.097645 118.383304)
		(width 0.125)
		(layer "In3.Cu")
		(net 129)
	)
	(segment
		(start 121.9 122.9)
		(end 123.1 121.7)
		(width 0.125)
		(layer "In3.Cu")
		(net 129)
	)
	(segment
		(start 126.80416 120.921911)
		(end 127.076602 120.676602)
		(width 0.125)
		(layer "In3.Cu")
		(net 129)
	)
	(segment
		(start 83.9 120.4)
		(end 105.8 120.4)
		(width 0.125)
		(layer "In3.Cu")
		(net 129)
	)
	(segment
		(start 125.855164 121.469814)
		(end 126.190077 121.320701)
		(width 0.125)
		(layer "In3.Cu")
		(net 129)
	)
	(segment
		(start 125.147903 121.659324)
		(end 125.506499 121.583102)
		(width 0.125)
		(layer "In3.Cu")
		(net 129)
	)
	(segment
		(start 133.126041 109.575)
		(end 133.125 109.575)
		(width 0.15)
		(layer "In3.Cu")
		(net 129)
	)
	(segment
		(start 66.05 121.35)
		(end 67.1 122.4)
		(width 0.125)
		(layer "In3.Cu")
		(net 129)
	)
	(segment
		(start 130.6 109.6)
		(end 132.8 109.6)
		(width 0.125)
		(layer "In3.Cu")
		(net 129)
	)
	(segment
		(start 127.076602 120.676602)
		(end 127.321911 120.40416)
		(width 0.125)
		(layer "In3.Cu")
		(net 129)
	)
	(segment
		(start 125.506499 121.583102)
		(end 125.855164 121.469814)
		(width 0.125)
		(layer "In3.Cu")
		(net 129)
	)
	(segment
		(start 63 97.12)
		(end 62.4 97.72)
		(width 0.15)
		(layer "In3.Cu")
		(net 129)
	)
	(segment
		(start 105.8 120.4)
		(end 108.3 122.9)
		(width 0.125)
		(layer "In3.Cu")
		(net 129)
	)
	(segment
		(start 126.190077 121.320701)
		(end 126.507568 121.137397)
		(width 0.125)
		(layer "In3.Cu")
		(net 129)
	)
	(segment
		(start 66.05 113.55)
		(end 66.05 121.35)
		(width 0.125)
		(layer "In3.Cu")
		(net 129)
	)
	(segment
		(start 127.869814 119.455164)
		(end 127.983102 119.106499)
		(width 0.125)
		(layer "In3.Cu")
		(net 129)
	)
	(segment
		(start 127.720701 119.790077)
		(end 127.869814 119.455164)
		(width 0.125)
		(layer "In3.Cu")
		(net 129)
	)
	(segment
		(start 63 87.7)
		(end 63 97.12)
		(width 0.15)
		(layer "In3.Cu")
		(net 129)
	)
	(segment
		(start 134 108.7)
		(end 133.375 109.325)
		(width 0.15)
		(layer "In3.Cu")
		(net 129)
	)
	(segment
		(start 81.9 122.4)
		(end 83.9 120.4)
		(width 0.125)
		(layer "In3.Cu")
		(net 129)
	)
	(segment
		(start 127.983102 119.106499)
		(end 128.059324 118.747903)
		(width 0.125)
		(layer "In3.Cu")
		(net 129)
	)
	(segment
		(start 62.4 109.9)
		(end 64 111.5)
		(width 0.15)
		(layer "In3.Cu")
		(net 129)
	)
	(segment
		(start 149.1 109.5)
		(end 148.85 109.25)
		(width 0.15)
		(layer "In3.Cu")
		(net 129)
	)
	(segment
		(start 148.485 108.5)
		(end 149.1 108.5)
		(width 0.15)
		(layer "F.Cu")
		(net 130)
	)
	(segment
		(start 132.95 109.15)
		(end 131.315 109.15)
		(width 0.15)
		(layer "F.Cu")
		(net 130)
	)
	(segment
		(start 65.847323 81.484429)
		(end 65.847323 80.205136)
		(width 0.125)
		(layer "F.Cu")
		(net 130)
	)
	(segment
		(start 64.87 82.986252)
		(end 64.87 82.461752)
		(width 0.125)
		(layer "F.Cu")
		(net 130)
	)
	(segment
		(start 64.87 82.461752)
		(end 65.847323 81.484429)
		(width 0.125)
		(layer "F.Cu")
		(net 130)
	)
	(segment
		(start 64.871248 82.9875)
		(end 64.87 82.986252)
		(width 0.125)
		(layer "F.Cu")
		(net 130)
	)
	(via
		(at 149.1 108.5)
		(size 0.45)
		(drill 0.1)
		(layers "F.Cu" "B.Cu")
		(net 130)
	)
	(via
		(at 64.871248 82.9875)
		(size 0.45)
		(drill 0.1)
		(layers "F.Cu" "B.Cu")
		(net 130)
	)
	(via
		(at 132.95 109.15)
		(size 0.45)
		(drill 0.1)
		(layers "F.Cu" "B.Cu")
		(net 130)
	)
	(segment
		(start 67.2 122.1)
		(end 81.8 122.1)
		(width 0.125)
		(layer "In3.Cu")
		(net 130)
	)
	(segment
		(start 127.8 118.1)
		(end 127.8 112)
		(width 0.125)
		(layer "In3.Cu")
		(net 130)
	)
	(segment
		(start 81.8 122.1)
		(end 83.8 120.1)
		(width 0.125)
		(layer "In3.Cu")
		(net 130)
	)
	(segment
		(start 127.8 112)
		(end 130.5 109.3)
		(width 0.125)
		(layer "In3.Cu")
		(net 130)
	)
	(segment
		(start 122.9 121.4)
		(end 124.5 121.4)
		(width 0.125)
		(layer "In3.Cu")
		(net 130)
	)
	(segment
		(start 130.5 109.3)
		(end 132.8 109.3)
		(width 0.125)
		(layer "In3.Cu")
		(net 130)
	)
	(segment
		(start 66.35 113.45)
		(end 66.35 121.25)
		(width 0.125)
		(layer "In3.Cu")
		(net 130)
	)
	(segment
		(start 63.3 97.32)
		(end 62.7 97.92)
		(width 0.15)
		(layer "In3.Cu")
		(net 130)
	)
	(segment
		(start 62.7 97.92)
		(end 62.7 109.8)
		(width 0.15)
		(layer "In3.Cu")
		(net 130)
	)
	(segment
		(start 105.8875 120.1)
		(end 108.3875 122.6)
		(width 0.125)
		(layer "In3.Cu")
		(net 130)
	)
	(segment
		(start 83.8 120.1)
		(end 105.8875 120.1)
		(width 0.125)
		(layer "In3.Cu")
		(net 130)
	)
	(segment
		(start 64.871248 83.228752)
		(end 64.6 83.5)
		(width 0.15)
		(layer "In3.Cu")
		(net 130)
	)
	(segment
		(start 135.4 108.8)
		(end 134.95 108.35)
		(width 0.15)
		(layer "In3.Cu")
		(net 130)
	)
	(segment
		(start 148.8 108.8)
		(end 135.4 108.8)
		(width 0.15)
		(layer "In3.Cu")
		(net 130)
	)
	(segment
		(start 64.6 83.5)
		(end 64.6 86.5)
		(width 0.15)
		(layer "In3.Cu")
		(net 130)
	)
	(segment
		(start 64.871248 82.9875)
		(end 64.871248 83.228752)
		(width 0.15)
		(layer "In3.Cu")
		(net 130)
	)
	(segment
		(start 63.3 87.8)
		(end 63.3 97.32)
		(width 0.15)
		(layer "In3.Cu")
		(net 130)
	)
	(segment
		(start 149.1 108.5)
		(end 148.8 108.8)
		(width 0.15)
		(layer "In3.Cu")
		(net 130)
	)
	(segment
		(start 108.3875 122.6)
		(end 121.7 122.6)
		(width 0.125)
		(layer "In3.Cu")
		(net 130)
	)
	(segment
		(start 62.7 109.8)
		(end 64.3 111.4)
		(width 0.15)
		(layer "In3.Cu")
		(net 130)
	)
	(segment
		(start 66.35 121.25)
		(end 67.2 122.1)
		(width 0.125)
		(layer "In3.Cu")
		(net 130)
	)
	(segment
		(start 133.75 108.35)
		(end 132.95 109.15)
		(width 0.15)
		(layer "In3.Cu")
		(net 130)
	)
	(segment
		(start 121.7 122.6)
		(end 122.9 121.4)
		(width 0.125)
		(layer "In3.Cu")
		(net 130)
	)
	(segment
		(start 64.3 111.4)
		(end 66.35 113.45)
		(width 0.125)
		(layer "In3.Cu")
		(net 130)
	)
	(segment
		(start 64.6 86.5)
		(end 63.3 87.8)
		(width 0.15)
		(layer "In3.Cu")
		(net 130)
	)
	(segment
		(start 132.8 109.3)
		(end 132.95 109.15)
		(width 0.125)
		(layer "In3.Cu")
		(net 130)
	)
	(segment
		(start 134.95 108.35)
		(end 133.75 108.35)
		(width 0.15)
		(layer "In3.Cu")
		(net 130)
	)
	(arc
		(start 124.5 121.4)
		(mid 126.833452 120.433452)
		(end 127.8 118.1)
		(width 0.125)
		(layer "In3.Cu")
		(net 130)
	)
	(segment
		(start 147.137131 87.85)
		(end 147.45 87.85)
		(width 0.155)
		(layer "F.Cu")
		(net 131)
	)
	(segment
		(start 111.237992 83.416566)
		(end 111.159794 83.338368)
		(width 0.155)
		(layer "F.Cu")
		(net 131)
	)
	(segment
		(start 109.956454 83.529989)
		(end 109.809989 83.529989)
		(width 0.155)
		(layer "F.Cu")
		(net 131)
	)
	(segment
		(start 146.612632 87.6995)
		(end 146.862367 87.6995)
		(width 0.155)
		(layer "F.Cu")
		(net 131)
	)
	(segment
		(start 115.947823 82.585776)
		(end 115.947823 80.305636)
		(width 0.155)
		(layer "F.Cu")
		(net 131)
	)
	(segment
		(start 147.868935 87.806066)
		(end 147.931567 87.743434)
		(width 0.155)
		(layer "F.Cu")
		(net 131)
	)
	(segment
		(start 110.947662 83.2505)
		(end 110.422339 83.2505)
		(width 0.155)
		(layer "F.Cu")
		(net 131)
	)
	(segment
		(start 148.196434 87.743434)
		(end 148.3 87.847)
		(width 0.155)
		(layer "F.Cu")
		(net 131)
	)
	(segment
		(start 115.84531 82.833264)
		(end 115.320586 83.357988)
		(width 0.155)
		(layer "F.Cu")
		(net 131)
	)
	(segment
		(start 146.968433 87.743434)
		(end 147.031065 87.806066)
		(width 0.155)
		(layer "F.Cu")
		(net 131)
	)
	(segment
		(start 115.947823 80.305636)
		(end 115.847323 80.205136)
		(width 0.155)
		(layer "F.Cu")
		(net 131)
	)
	(segment
		(start 115.073099 83.4605)
		(end 111.344058 83.4605)
		(width 0.155)
		(layer "F.Cu")
		(net 131)
	)
	(segment
		(start 148.037633 87.6995)
		(end 148.090368 87.6995)
		(width 0.155)
		(layer "F.Cu")
		(net 131)
	)
	(segment
		(start 147.45 87.85)
		(end 147.762869 87.85)
		(width 0.155)
		(layer "F.Cu")
		(net 131)
	)
	(segment
		(start 110.210207 83.338368)
		(end 110.06252 83.486055)
		(width 0.155)
		(layer "F.Cu")
		(net 131)
	)
	(segment
		(start 146.3 87.95)
		(end 146.506566 87.743434)
		(width 0.155)
		(layer "F.Cu")
		(net 131)
	)
	(via
		(at 148.3 87.847)
		(size 0.45)
		(drill 0.1)
		(layers "F.Cu" "B.Cu")
		(net 131)
	)
	(via
		(at 109.809989 83.529989)
		(size 0.45)
		(drill 0.1)
		(layers "F.Cu" "B.Cu")
		(net 131)
	)
	(arc
		(start 115.947823 82.585776)
		(mid 115.921181 82.719716)
		(end 115.84531 82.833264)
		(width 0.155)
		(layer "F.Cu")
		(net 131)
	)
	(arc
		(start 147.931567 87.743434)
		(mid 147.98023 87.710918)
		(end 148.037633 87.6995)
		(width 0.155)
		(layer "F.Cu")
		(net 131)
	)
	(arc
		(start 146.862367 87.6995)
		(mid 146.91977 87.710918)
		(end 146.968433 87.743434)
		(width 0.155)
		(layer "F.Cu")
		(net 131)
	)
	(arc
		(start 147.868935 87.806066)
		(mid 147.820272 87.838582)
		(end 147.762869 87.85)
		(width 0.155)
		(layer "F.Cu")
		(net 131)
	)
	(arc
		(start 146.612632 87.6995)
		(mid 146.555229 87.710918)
		(end 146.506566 87.743434)
		(width 0.155)
		(layer "F.Cu")
		(net 131)
	)
	(arc
		(start 110.422339 83.2505)
		(mid 110.307534 83.273336)
		(end 110.210207 83.338368)
		(width 0.155)
		(layer "F.Cu")
		(net 131)
	)
	(arc
		(start 109.956454 83.529989)
		(mid 110.013857 83.518571)
		(end 110.06252 83.486055)
		(width 0.155)
		(layer "F.Cu")
		(net 131)
	)
	(arc
		(start 111.159794 83.338368)
		(mid 111.062467 83.273336)
		(end 110.947662 83.2505)
		(width 0.155)
		(layer "F.Cu")
		(net 131)
	)
	(arc
		(start 148.196434 87.743434)
		(mid 148.147771 87.710918)
		(end 148.090368 87.6995)
		(width 0.155)
		(layer "F.Cu")
		(net 131)
	)
	(arc
		(start 111.237992 83.416566)
		(mid 111.286655 83.449082)
		(end 111.344058 83.4605)
		(width 0.155)
		(layer "F.Cu")
		(net 131)
	)
	(arc
		(start 115.320586 83.357988)
		(mid 115.207038 83.433858)
		(end 115.073099 83.4605)
		(width 0.155)
		(layer "F.Cu")
		(net 131)
	)
	(arc
		(start 147.137131 87.85)
		(mid 147.079728 87.838582)
		(end 147.031065 87.806066)
		(width 0.155)
		(layer "F.Cu")
		(net 131)
	)
	(segment
		(start 144.201718 97.859)
		(end 141.661718 97.859)
		(width 0.16)
		(layer "In5.Cu")
		(net 131)
	)
	(segment
		(start 109.551 83.998282)
		(end 109.809989 83.739293)
		(width 0.16)
		(layer "In5.Cu")
		(net 131)
	)
	(segment
		(start 148.041718 87.699)
		(end 147.699 88.041718)
		(width 0.16)
		(layer "In5.Cu")
		(net 131)
	)
	(segment
		(start 110.701 88.611718)
		(end 109.701 87.611718)
		(width 0.16)
		(layer "In5.Cu")
		(net 131)
	)
	(segment
		(start 131.471718 101.389)
		(end 125.391718 101.389)
		(width 0.16)
		(layer "In5.Cu")
		(net 131)
	)
	(segment
		(start 123.781718 102.999)
		(end 119.188282 102.999)
		(width 0.16)
		(layer "In5.Cu")
		(net 131)
	)
	(segment
		(start 148.152 87.699)
		(end 148.041718 87.699)
		(width 0.16)
		(layer "In5.Cu")
		(net 131)
	)
	(segment
		(start 114.801 95.611718)
		(end 114.238282 95.049)
		(width 0.16)
		(layer "In5.Cu")
		(net 131)
	)
	(segment
		(start 136.038282 99.899)
		(end 134.688282 98.549)
		(width 0.16)
		(layer "In5.Cu")
		(net 131)
	)
	(segment
		(start 132.799 100.061718)
		(end 131.471718 101.389)
		(width 0.16)
		(layer "In5.Cu")
		(net 131)
	)
	(segment
		(start 141.661718 97.859)
		(end 139.621718 99.899)
		(width 0.16)
		(layer "In5.Cu")
		(net 131)
	)
	(segment
		(start 125.391718 101.389)
		(end 123.781718 102.999)
		(width 0.16)
		(layer "In5.Cu")
		(net 131)
	)
	(segment
		(start 133.411718 98.549)
		(end 132.799 99.161718)
		(width 0.16)
		(layer "In5.Cu")
		(net 131)
	)
	(segment
		(start 112.688282 95.049)
		(end 110.701 93.061718)
		(width 0.16)
		(layer "In5.Cu")
		(net 131)
	)
	(segment
		(start 147.699 88.041718)
		(end 147.699 94.361718)
		(width 0.16)
		(layer "In5.Cu")
		(net 131)
	)
	(segment
		(start 109.809989 83.739293)
		(end 109.809989 83.529989)
		(width 0.16)
		(layer "In5.Cu")
		(net 131)
	)
	(segment
		(start 110.701 93.061718)
		(end 110.701 88.611718)
		(width 0.16)
		(layer "In5.Cu")
		(net 131)
	)
	(segment
		(start 147.699 94.361718)
		(end 144.201718 97.859)
		(width 0.16)
		(layer "In5.Cu")
		(net 131)
	)
	(segment
		(start 109.701 85.541718)
		(end 109.551 85.391718)
		(width 0.16)
		(layer "In5.Cu")
		(net 131)
	)
	(segment
		(start 114.801 98.611718)
		(end 114.801 95.611718)
		(width 0.16)
		(layer "In5.Cu")
		(net 131)
	)
	(segment
		(start 134.688282 98.549)
		(end 133.411718 98.549)
		(width 0.16)
		(layer "In5.Cu")
		(net 131)
	)
	(segment
		(start 109.701 87.611718)
		(end 109.701 85.541718)
		(width 0.16)
		(layer "In5.Cu")
		(net 131)
	)
	(segment
		(start 109.551 85.391718)
		(end 109.551 83.998282)
		(width 0.16)
		(layer "In5.Cu")
		(net 131)
	)
	(segment
		(start 148.3 87.847)
		(end 148.152 87.699)
		(width 0.16)
		(layer "In5.Cu")
		(net 131)
	)
	(segment
		(start 114.238282 95.049)
		(end 112.688282 95.049)
		(width 0.16)
		(layer "In5.Cu")
		(net 131)
	)
	(segment
		(start 139.621718 99.899)
		(end 136.038282 99.899)
		(width 0.16)
		(layer "In5.Cu")
		(net 131)
	)
	(segment
		(start 119.188282 102.999)
		(end 114.801 98.611718)
		(width 0.16)
		(layer "In5.Cu")
		(net 131)
	)
	(segment
		(start 132.799 99.161718)
		(end 132.799 100.061718)
		(width 0.16)
		(layer "In5.Cu")
		(net 131)
	)
	(segment
		(start 114.996823 70.523177)
		(end 114.996823 71.179636)
		(width 0.155)
		(layer "F.Cu")
		(net 132)
	)
	(segment
		(start 115.12 70.4)
		(end 114.996823 70.523177)
		(width 0.155)
		(layer "F.Cu")
		(net 132)
	)
	(segment
		(start 132.378075 91.6305)
		(end 133.9055 91.6305)
		(width 0.155)
		(layer "F.Cu")
		(net 132)
	)
	(segment
		(start 133.9055 91.6305)
		(end 134.226 91.31)
		(width 0.155)
		(layer "F.Cu")
		(net 132)
	)
	(segment
		(start 132.168575 91.84)
		(end 132.378075 91.6305)
		(width 0.155)
		(layer "F.Cu")
		(net 132)
	)
	(segment
		(start 114.996823 71.179636)
		(end 115.097323 71.280136)
		(width 0.155)
		(layer "F.Cu")
		(net 132)
	)
	(segment
		(start 131.91 91.84)
		(end 132.168575 91.84)
		(width 0.155)
		(layer "F.Cu")
		(net 132)
	)
	(via
		(at 115.12 70.4)
		(size 0.45)
		(drill 0.1)
		(layers "F.Cu" "B.Cu")
		(net 132)
	)
	(via
		(at 131.91 91.84)
		(size 0.45)
		(drill 0.1)
		(layers "F.Cu" "B.Cu")
		(net 132)
	)
	(segment
		(start 126.651 70.341718)
		(end 126.198282 69.889)
		(width 0.16)
		(layer "In3.Cu")
		(net 132)
	)
	(segment
		(start 130.176 90.146718)
		(end 130.176 88.956)
		(width 0.16)
		(layer "In3.Cu")
		(net 132)
	)
	(segment
		(start 129.536927 88.516445)
		(end 129.567198 88.443356)
		(width 0.16)
		(layer "In3.Cu")
		(net 132)
	)
	(segment
		(start 130.176 83.911718)
		(end 129.376 83.111718)
		(width 0.16)
		(layer "In3.Cu")
		(net 132)
	)
	(segment
		(start 129.735774 88.356)
		(end 129.976 88.356)
		(width 0.16)
		(layer "In3.Cu")
		(net 132)
	)
	(segment
		(start 114.959 69.991718)
		(end 114.959 70.239)
		(width 0.16)
		(layer "In3.Cu")
		(net 132)
	)
	(segment
		(start 130.015553 88.354847)
		(end 130.088638 88.324575)
		(width 0.16)
		(layer "In3.Cu")
		(net 132)
	)
	(segment
		(start 132.028282 90.749)
		(end 130.778282 90.749)
		(width 0.16)
		(layer "In3.Cu")
		(net 132)
	)
	(segment
		(start 129.623134 88.387413)
		(end 129.696219 88.357132)
		(width 0.16)
		(layer "In3.Cu")
		(net 132)
	)
	(segment
		(start 130.174847 88.916447)
		(end 130.144575 88.843362)
		(width 0.16)
		(layer "In3.Cu")
		(net 132)
	)
	(segment
		(start 132.401 91.121718)
		(end 132.028282 90.749)
		(width 0.16)
		(layer "In3.Cu")
		(net 132)
	)
	(segment
		(start 116.678282 69.889)
		(end 116.418282 69.629)
		(width 0.16)
		(layer "In3.Cu")
		(net 132)
	)
	(segment
		(start 132.274282 91.84)
		(end 132.401 91.713282)
		(width 0.16)
		(layer "In3.Cu")
		(net 132)
	)
	(segment
		(start 129.976 88.356)
		(end 130.015553 88.354847)
		(width 0.16)
		(layer "In3.Cu")
		(net 132)
	)
	(segment
		(start 129.623148 88.724565)
		(end 129.56722 88.66863)
		(width 0.16)
		(layer "In3.Cu")
		(net 132)
	)
	(segment
		(start 129.696219 88.357132)
		(end 129.735774 88.356)
		(width 0.16)
		(layer "In3.Cu")
		(net 132)
	)
	(segment
		(start 130.144575 88.268638)
		(end 130.174847 88.195553)
		(width 0.16)
		(layer "In3.Cu")
		(net 132)
	)
	(segment
		(start 130.015553 88.757153)
		(end 129.976 88.756)
		(width 0.16)
		(layer "In3.Cu")
		(net 132)
	)
	(segment
		(start 129.567198 88.443356)
		(end 129.623134 88.387413)
		(width 0.16)
		(layer "In3.Cu")
		(net 132)
	)
	(segment
		(start 129.696224 88.754843)
		(end 129.623148 88.724565)
		(width 0.16)
		(layer "In3.Cu")
		(net 132)
	)
	(segment
		(start 129.536952 88.59555)
		(end 129.535774 88.556)
		(width 0.16)
		(layer "In3.Cu")
		(net 132)
	)
	(segment
		(start 130.088638 88.787425)
		(end 130.015553 88.757153)
		(width 0.16)
		(layer "In3.Cu")
		(net 132)
	)
	(segment
		(start 126.651 73.386718)
		(end 126.651 70.341718)
		(width 0.16)
		(layer "In3.Cu")
		(net 132)
	)
	(segment
		(start 129.735774 88.756)
		(end 129.696224 88.754843)
		(width 0.16)
		(layer "In3.Cu")
		(net 132)
	)
	(segment
		(start 116.418282 69.629)
		(end 115.321718 69.629)
		(width 0.16)
		(layer "In3.Cu")
		(net 132)
	)
	(segment
		(start 130.088638 88.324575)
		(end 130.144575 88.268638)
		(width 0.16)
		(layer "In3.Cu")
		(net 132)
	)
	(segment
		(start 131.91 91.84)
		(end 132.274282 91.84)
		(width 0.16)
		(layer "In3.Cu")
		(net 132)
	)
	(segment
		(start 129.976 88.756)
		(end 129.735774 88.756)
		(width 0.16)
		(layer "In3.Cu")
		(net 132)
	)
	(segment
		(start 129.56722 88.66863)
		(end 129.536952 88.59555)
		(width 0.16)
		(layer "In3.Cu")
		(net 132)
	)
	(segment
		(start 130.144575 88.843362)
		(end 130.088638 88.787425)
		(width 0.16)
		(layer "In3.Cu")
		(net 132)
	)
	(segment
		(start 130.176 88.956)
		(end 130.174847 88.916447)
		(width 0.16)
		(layer "In3.Cu")
		(net 132)
	)
	(segment
		(start 129.376 83.111718)
		(end 129.376 76.111718)
		(width 0.16)
		(layer "In3.Cu")
		(net 132)
	)
	(segment
		(start 115.321718 69.629)
		(end 114.959 69.991718)
		(width 0.16)
		(layer "In3.Cu")
		(net 132)
	)
	(segment
		(start 129.535774 88.556)
		(end 129.536927 88.516445)
		(width 0.16)
		(layer "In3.Cu")
		(net 132)
	)
	(segment
		(start 130.174847 88.195553)
		(end 130.176 88.156)
		(width 0.16)
		(layer "In3.Cu")
		(net 132)
	)
	(segment
		(start 132.401 91.713282)
		(end 132.401 91.121718)
		(width 0.16)
		(layer "In3.Cu")
		(net 132)
	)
	(segment
		(start 129.376 76.111718)
		(end 126.651 73.386718)
		(width 0.16)
		(layer "In3.Cu")
		(net 132)
	)
	(segment
		(start 130.778282 90.749)
		(end 130.176 90.146718)
		(width 0.16)
		(layer "In3.Cu")
		(net 132)
	)
	(segment
		(start 114.959 70.239)
		(end 115.12 70.4)
		(width 0.16)
		(layer "In3.Cu")
		(net 132)
	)
	(segment
		(start 130.176 88.156)
		(end 130.176 83.911718)
		(width 0.16)
		(layer "In3.Cu")
		(net 132)
	)
	(segment
		(start 126.198282 69.889)
		(end 116.678282 69.889)
		(width 0.16)
		(layer "In3.Cu")
		(net 132)
	)
	(segment
		(start 66.1 99.75)
		(end 66.1 98.81)
		(width 0.15)
		(layer "B.Cu")
		(net 133)
	)
	(segment
		(start 66.1 98.81)
		(end 66.075 98.785)
		(width 0.15)
		(layer "B.Cu")
		(net 133)
	)
	(via
		(at 65.7 107.15)
		(size 0.45)
		(drill 0.1)
		(layers "F.Cu" "B.Cu")
		(net 134)
	)
	(via
		(at 67.57 97.6)
		(size 0.45)
		(drill 0.1)
		(layers "F.Cu" "B.Cu")
		(net 134)
	)
	(segment
		(start 66.715 97.225)
		(end 65.39 98.55)
		(width 0.15)
		(layer "In3.Cu")
		(net 134)
	)
	(segment
		(start 63.6 98.55)
		(end 63.3 98.85)
		(width 0.15)
		(layer "In3.Cu")
		(net 134)
	)
	(segment
		(start 63.3 98.85)
		(end 63.3 106.75)
		(width 0.15)
		(layer "In3.Cu")
		(net 134)
	)
	(segment
		(start 67.195 97.225)
		(end 66.715 97.225)
		(width 0.15)
		(layer "In3.Cu")
		(net 134)
	)
	(segment
		(start 63.7 107.15)
		(end 65.7 107.15)
		(width 0.15)
		(layer "In3.Cu")
		(net 134)
	)
	(segment
		(start 67.57 97.6)
		(end 67.195 97.225)
		(width 0.15)
		(layer "In3.Cu")
		(net 134)
	)
	(segment
		(start 65.39 98.55)
		(end 63.6 98.55)
		(width 0.15)
		(layer "In3.Cu")
		(net 134)
	)
	(segment
		(start 63.3 106.75)
		(end 63.7 107.15)
		(width 0.15)
		(layer "In3.Cu")
		(net 134)
	)
	(segment
		(start 66.565 110.735)
		(end 66.315 110.735)
		(width 0.155)
		(layer "B.Cu")
		(net 134)
	)
	(segment
		(start 67.57 97.6)
		(end 68.041 97.6)
		(width 0.15)
		(layer "B.Cu")
		(net 134)
	)
	(segment
		(start 66.81 110.735)
		(end 66.565 110.735)
		(width 0.155)
		(layer "B.Cu")
		(net 134)
	)
	(segment
		(start 66.55 110.6)
		(end 66.55 110.72)
		(width 0.155)
		(layer "B.Cu")
		(net 134)
	)
	(segment
		(start 66.415 110.735)
		(end 66.55 110.6)
		(width 0.155)
		(layer "B.Cu")
		(net 134)
	)
	(segment
		(start 66.81 110.735)
		(end 66.685 110.735)
		(width 0.155)
		(layer "B.Cu")
		(net 134)
	)
	(segment
		(start 66.55 109.492444)
		(end 66.55 110.6)
		(width 0.155)
		(layer "B.Cu")
		(net 134)
	)
	(segment
		(start 66.1525 107.7025)
		(end 66.4 107.95)
		(width 0.155)
		(layer "B.Cu")
		(net 134)
	)
	(segment
		(start 65.7 107.5525)
		(end 65.55 107.7025)
		(width 0.125)
		(layer "B.Cu")
		(net 134)
	)
	(segment
		(start 65.7 107.15)
		(end 65.7 107.5525)
		(width 0.125)
		(layer "B.Cu")
		(net 134)
	)
	(segment
		(start 65.5625 107.7025)
		(end 66.1525 107.7025)
		(width 0.155)
		(layer "B.Cu")
		(net 134)
	)
	(segment
		(start 66.315 110.735)
		(end 66.415 110.735)
		(width 0.155)
		(layer "B.Cu")
		(net 134)
	)
	(segment
		(start 65.7 107.2)
		(end 65.7 106.45)
		(width 0.15)
		(layer "B.Cu")
		(net 134)
	)
	(segment
		(start 67.2 110.735)
		(end 66.76 110.735)
		(width 0.155)
		(layer "B.Cu")
		(net 134)
	)
	(segment
		(start 66.4 109.342444)
		(end 66.55 109.492444)
		(width 0.155)
		(layer "B.Cu")
		(net 134)
	)
	(segment
		(start 66.55 110.72)
		(end 66.565 110.735)
		(width 0.155)
		(layer "B.Cu")
		(net 134)
	)
	(segment
		(start 65.95 110.735)
		(end 65.925 110.76)
		(width 0.155)
		(layer "B.Cu")
		(net 134)
	)
	(segment
		(start 66.415 110.735)
		(end 65.95 110.735)
		(width 0.155)
		(layer "B.Cu")
		(net 134)
	)
	(segment
		(start 66.4 107.95)
		(end 66.4 109.342444)
		(width 0.155)
		(layer "B.Cu")
		(net 134)
	)
	(segment
		(start 66.685 110.735)
		(end 66.55 110.6)
		(width 0.155)
		(layer "B.Cu")
		(net 134)
	)
	(segment
		(start 68.041 97.6)
		(end 68.151 97.71)
		(width 0.15)
		(layer "B.Cu")
		(net 134)
	)
	(segment
		(start 47.341428 80.6)
		(end 46.3 80.6)
		(width 0.15)
		(layer "B.Cu")
		(net 135)
	)
	(segment
		(start 47.792428 81.051)
		(end 47.341428 80.6)
		(width 0.15)
		(layer "B.Cu")
		(net 135)
	)
	(segment
		(start 48.525 81.051)
		(end 47.792428 81.051)
		(width 0.15)
		(layer "B.Cu")
		(net 135)
	)
	(segment
		(start 46.3 80.6)
		(end 46.3 81.558572)
		(width 0.15)
		(layer "B.Cu")
		(net 135)
	)
	(segment
		(start 48.55 82.19)
		(end 48.525 82.165)
		(width 0.15)
		(layer "B.Cu")
		(net 135)
	)
	(segment
		(start 48.525 82.165)
		(end 48.525 81.051)
		(width 0.15)
		(layer "B.Cu")
		(net 135)
	)
	(segment
		(start 57.2 77.05)
		(end 57.2 75.5245)
		(width 0.125)
		(layer "F.Cu")
		(net 137)
	)
	(segment
		(start 65.75 125.6)
		(end 66.25 125.1)
		(width 0.155)
		(layer "F.Cu")
		(net 137)
	)
	(segment
		(start 62.15 125.1)
		(end 62.15 125.15)
		(width 0.155)
		(layer "F.Cu")
		(net 137)
	)
	(segment
		(start 67.7 125.6)
		(end 66.75 125.6)
		(width 0.15)
		(layer "F.Cu")
		(net 137)
	)
	(segment
		(start 58.45 78.3)
		(end 57.2 77.05)
		(width 0.125)
		(layer "F.Cu")
		(net 137)
	)
	(segment
		(start 66.75 125.6)
		(end 66.25 125.1)
		(width 0.15)
		(layer "F.Cu")
		(net 137)
	)
	(segment
		(start 62.6 125.6)
		(end 65.75 125.6)
		(width 0.155)
		(layer "F.Cu")
		(net 137)
	)
	(segment
		(start 62.15 125.15)
		(end 62.6 125.6)
		(width 0.155)
		(layer "F.Cu")
		(net 137)
	)
	(via
		(at 58.45 78.3)
		(size 0.45)
		(drill 0.1)
		(layers "F.Cu" "B.Cu")
		(net 137)
	)
	(via
		(at 65.15 125.6)
		(size 0.45)
		(drill 0.1)
		(layers "F.Cu" "B.Cu")
		(net 137)
	)
	(via
		(at 57.2 75.5245)
		(size 0.45)
		(drill 0.1)
		(layers "F.Cu" "B.Cu")
		(net 137)
	)
	(segment
		(start 52.25 113.3)
		(end 52.25 98.02)
		(width 0.125)
		(layer "In3.Cu")
		(net 137)
	)
	(segment
		(start 54.4 75.7)
		(end 54.5755 75.5245)
		(width 0.125)
		(layer "In3.Cu")
		(net 137)
	)
	(segment
		(start 52.25 98.02)
		(end 51.7 97.47)
		(width 0.125)
		(layer "In3.Cu")
		(net 137)
	)
	(segment
		(start 62.264675 114.325728)
		(end 61.898203 114.21456)
		(width 0.125)
		(layer "In3.Cu")
		(net 137)
	)
	(segment
		(start 63.84148 115.379315)
		(end 63.570685 115.10852)
		(width 0.125)
		(layer "In3.Cu")
		(net 137)
	)
	(segment
		(start 54.5755 75.5245)
		(end 57.2 75.5245)
		(width 0.125)
		(layer "In3.Cu")
		(net 137)
	)
	(segment
		(start 65.15 125.6)
		(end 64.85 125.3)
		(width 0.125)
		(layer "In3.Cu")
		(net 137)
	)
	(segment
		(start 64.624272 116.685325)
		(end 64.477718 116.331513)
		(width 0.125)
		(layer "In3.Cu")
		(net 137)
	)
	(segment
		(start 64.847689 117.808519)
		(end 64.810152 117.427401)
		(width 0.125)
		(layer "In3.Cu")
		(net 137)
	)
	(segment
		(start 51.7 82.55)
		(end 54.4 79.85)
		(width 0.125)
		(layer "In3.Cu")
		(net 137)
	)
	(segment
		(start 62.618487 114.472282)
		(end 62.264675 114.325728)
		(width 0.125)
		(layer "In3.Cu")
		(net 137)
	)
	(segment
		(start 63.274651 114.865571)
		(end 62.956229 114.652809)
		(width 0.125)
		(layer "In3.Cu")
		(net 137)
	)
	(segment
		(start 64.477718 116.331513)
		(end 64.297191 115.993771)
		(width 0.125)
		(layer "In3.Cu")
		(net 137)
	)
	(segment
		(start 54.4 79.85)
		(end 54.4 75.7)
		(width 0.125)
		(layer "In3.Cu")
		(net 137)
	)
	(segment
		(start 53.05 114.1)
		(end 52.25 113.3)
		(width 0.125)
		(layer "In3.Cu")
		(net 137)
	)
	(segment
		(start 51.7 97.47)
		(end 51.7 82.55)
		(width 0.125)
		(layer "In3.Cu")
		(net 137)
	)
	(segment
		(start 64.297191 115.993771)
		(end 64.084429 115.675349)
		(width 0.125)
		(layer "In3.Cu")
		(net 137)
	)
	(segment
		(start 64.85 118)
		(end 64.847689 117.808519)
		(width 0.125)
		(layer "In3.Cu")
		(net 137)
	)
	(segment
		(start 61.898203 114.21456)
		(end 61.522599 114.139848)
		(width 0.125)
		(layer "In3.Cu")
		(net 137)
	)
	(segment
		(start 62.956229 114.652809)
		(end 62.618487 114.472282)
		(width 0.125)
		(layer "In3.Cu")
		(net 137)
	)
	(segment
		(start 64.810152 117.427401)
		(end 64.73544 117.051797)
		(width 0.125)
		(layer "In3.Cu")
		(net 137)
	)
	(segment
		(start 60.95 114.1)
		(end 53.05 114.1)
		(width 0.125)
		(layer "In3.Cu")
		(net 137)
	)
	(segment
		(start 64.85 125.3)
		(end 64.85 118)
		(width 0.125)
		(layer "In3.Cu")
		(net 137)
	)
	(segment
		(start 64.73544 117.051797)
		(end 64.624272 116.685325)
		(width 0.125)
		(layer "In3.Cu")
		(net 137)
	)
	(segment
		(start 64.084429 115.675349)
		(end 63.84148 115.379315)
		(width 0.125)
		(layer "In3.Cu")
		(net 137)
	)
	(segment
		(start 61.141481 114.102311)
		(end 60.95 114.1)
		(width 0.125)
		(layer "In3.Cu")
		(net 137)
	)
	(segment
		(start 63.570685 115.10852)
		(end 63.274651 114.865571)
		(width 0.125)
		(layer "In3.Cu")
		(net 137)
	)
	(segment
		(start 61.522599 114.139848)
		(end 61.141481 114.102311)
		(width 0.125)
		(layer "In3.Cu")
		(net 137)
	)
	(segment
		(start 57.6375 74.496)
		(end 57.638 74.4965)
		(width 0.125)
		(layer "B.Cu")
		(net 137)
	)
	(segment
		(start 57.638 74.4965)
		(end 57.638 75.392)
		(width 0.125)
		(layer "B.Cu")
		(net 137)
	)
	(segment
		(start 57.638 75.392)
		(end 57.5055 75.5245)
		(width 0.125)
		(layer "B.Cu")
		(net 137)
	)
	(segment
		(start 57.5055 75.5245)
		(end 57.2 75.5245)
		(width 0.125)
		(layer "B.Cu")
		(net 137)
	)
	(segment
		(start 57.65 71.598959)
		(end 58.073959 71.175)
		(width 0.15)
		(layer "B.Cu")
		(net 137)
	)
	(segment
		(start 60.736 77.554)
		(end 60.385 77.905)
		(width 0.15)
		(layer "B.Cu")
		(net 137)
	)
	(segment
		(start 58.073959 71.175)
		(end 60.675 71.175)
		(width 0.15)
		(layer "B.Cu")
		(net 137)
	)
	(segment
		(start 59.649 77.391)
		(end 58.74 78.3)
		(width 0.125)
		(layer "B.Cu")
		(net 137)
	)
	(segment
		(start 57.6375 74.496)
		(end 57.65 74.4835)
		(width 0.15)
		(layer "B.Cu")
		(net 137)
	)
	(segment
		(start 60.385 78.95)
		(end 61.315 78.95)
		(width 0.15)
		(layer "B.Cu")
		(net 137)
	)
	(segment
		(start 58.74 78.3)
		(end 58.45 78.3)
		(width 0.125)
		(layer "B.Cu")
		(net 137)
	)
	(segment
		(start 60.04 77.35)
		(end 60.244 77.554)
		(width 0.15)
		(layer "B.Cu")
		(net 137)
	)
	(segment
		(start 60.385 77.905)
		(end 60.385 78.95)
		(width 0.15)
		(layer "B.Cu")
		(net 137)
	)
	(segment
		(start 57.65 74.4835)
		(end 57.65 71.598959)
		(width 0.15)
		(layer "B.Cu")
		(net 137)
	)
	(segment
		(start 60.675 71.175)
		(end 61.65 72.15)
		(width 0.15)
		(layer "B.Cu")
		(net 137)
	)
	(segment
		(start 61.65 72.15)
		(end 61.65 73.1)
		(width 0.15)
		(layer "B.Cu")
		(net 137)
	)
	(segment
		(start 60.95 77.554)
		(end 60.736 77.554)
		(width 0.15)
		(layer "B.Cu")
		(net 137)
	)
	(segment
		(start 59.649 77.35)
		(end 59.649 77.391)
		(width 0.125)
		(layer "B.Cu")
		(net 137)
	)
	(segment
		(start 59.649 77.35)
		(end 60.04 77.35)
		(width 0.15)
		(layer "B.Cu")
		(net 137)
	)
	(segment
		(start 60.244 77.554)
		(end 60.95 77.554)
		(width 0.15)
		(layer "B.Cu")
		(net 137)
	)
	(segment
		(start 71.65 79.45)
		(end 71.6 79.4)
		(width 0.5)
		(layer "B.Cu")
		(net 138)
	)
	(segment
		(start 70.715 80.285)
		(end 71.6 79.4)
		(width 0.5)
		(layer "B.Cu")
		(net 138)
	)
	(segment
		(start 72.52 80.75)
		(end 72.3 80.53)
		(width 0.3)
		(layer "B.Cu")
		(net 138)
	)
	(segment
		(start 72.3 80.53)
		(end 72.3 80.04)
		(width 0.3)
		(layer "B.Cu")
		(net 138)
	)
	(segment
		(start 72.3 80.04)
		(end 71.66 79.4)
		(width 0.3)
		(layer "B.Cu")
		(net 138)
	)
	(segment
		(start 70.715 80.6)
		(end 70.715 80.285)
		(width 0.5)
		(layer "B.Cu")
		(net 138)
	)
	(segment
		(start 72.825 80.75)
		(end 72.52 80.75)
		(width 0.3)
		(layer "B.Cu")
		(net 138)
	)
	(segment
		(start 71.66 79.4)
		(end 71.6 79.4)
		(width 0.3)
		(layer "B.Cu")
		(net 138)
	)
	(segment
		(start 62.025 82.625)
		(end 60.675 82.625)
		(width 0.5)
		(layer "B.Cu")
		(net 139)
	)
	(segment
		(start 62.03 83.88)
		(end 62.03 83.46)
		(width 0.5)
		(layer "B.Cu")
		(net 139)
	)
	(segment
		(start 62.03 83.46)
		(end 62.1 83.39)
		(width 0.5)
		(layer "B.Cu")
		(net 139)
	)
	(segment
		(start 62.1 83.39)
		(end 62.1 82.7)
		(width 0.5)
		(layer "B.Cu")
		(net 139)
	)
	(segment
		(start 62.1 82.7)
		(end 62.025 82.625)
		(width 0.5)
		(layer "B.Cu")
		(net 139)
	)
	(segment
		(start 60.675 82.625)
		(end 60.55 82.5)
		(width 0.5)
		(layer "B.Cu")
		(net 139)
	)
	(segment
		(start 131.3 102.256448)
		(end 131.556448 102)
		(width 0.15)
		(layer "F.Cu")
		(net 140)
	)
	(segment
		(start 131.556448 102)
		(end 131.85 102)
		(width 0.15)
		(layer "F.Cu")
		(net 140)
	)
	(segment
		(start 131.65 103.575)
		(end 131.3 103.225)
		(width 0.15)
		(layer "F.Cu")
		(net 140)
	)
	(segment
		(start 131.3 103.225)
		(end 131.3 102.256448)
		(width 0.15)
		(layer "F.Cu")
		(net 140)
	)
	(segment
		(start 131.65 103.7)
		(end 131.65 103.575)
		(width 0.15)
		(layer "F.Cu")
		(net 140)
	)
	(segment
		(start 131.85 102)
		(end 132 101.85)
		(width 0.15)
		(layer "F.Cu")
		(net 140)
	)
	(segment
		(start 132 101.85)
		(end 132 101.25)
		(width 0.15)
		(layer "F.Cu")
		(net 140)
	)
	(via
		(at 131.65 103.7)
		(size 0.45)
		(drill 0.1)
		(layers "F.Cu" "B.Cu")
		(net 140)
	)
	(segment
		(start 112.85 94.1)
		(end 113.2 93.75)
		(width 0.15)
		(layer "B.Cu")
		(net 140)
	)
	(segment
		(start 117.7 105.75)
		(end 117.7 100.6)
		(width 0.15)
		(layer "B.Cu")
		(net 140)
	)
	(segment
		(start 113.4875 100.0875)
		(end 112.85 99.45)
		(width 0.15)
		(layer "B.Cu")
		(net 140)
	)
	(segment
		(start 131.65 103.7)
		(end 131.5 103.55)
		(width 0.15)
		(layer "B.Cu")
		(net 140)
	)
	(segment
		(start 117.1875 100.0875)
		(end 113.4875 100.0875)
		(width 0.15)
		(layer "B.Cu")
		(net 140)
	)
	(segment
		(start 131.5 103.55)
		(end 129.15 103.55)
		(width 0.15)
		(layer "B.Cu")
		(net 140)
	)
	(segment
		(start 117.7 100.6)
		(end 117.1875 100.0875)
		(width 0.15)
		(layer "B.Cu")
		(net 140)
	)
	(segment
		(start 126.2 106.5)
		(end 118.45 106.5)
		(width 0.15)
		(layer "B.Cu")
		(net 140)
	)
	(segment
		(start 113.2 93.75)
		(end 116.725 93.75)
		(width 0.15)
		(layer "B.Cu")
		(net 140)
	)
	(segment
		(start 118.45 106.5)
		(end 117.7 105.75)
		(width 0.15)
		(layer "B.Cu")
		(net 140)
	)
	(segment
		(start 112.85 99.45)
		(end 112.85 94.1)
		(width 0.15)
		(layer "B.Cu")
		(net 140)
	)
	(segment
		(start 129.15 103.55)
		(end 126.2 106.5)
		(width 0.15)
		(layer "B.Cu")
		(net 140)
	)
	(segment
		(start 132.6 106.4)
		(end 133.15 105.85)
		(width 0.15)
		(layer "F.Cu")
		(net 141)
	)
	(segment
		(start 132.8 102.65)
		(end 132 102.65)
		(width 0.15)
		(layer "F.Cu")
		(net 141)
	)
	(segment
		(start 129.9 107.415)
		(end 129.9 106.815)
		(width 0.15)
		(layer "F.Cu")
		(net 141)
	)
	(segment
		(start 133.15 103)
		(end 132.8 102.65)
		(width 0.15)
		(layer "F.Cu")
		(net 141)
	)
	(segment
		(start 133.15 105.85)
		(end 133.15 103)
		(width 0.15)
		(layer "F.Cu")
		(net 141)
	)
	(segment
		(start 130.315 106.4)
		(end 132.6 106.4)
		(width 0.15)
		(layer "F.Cu")
		(net 141)
	)
	(segment
		(start 129.9 106.815)
		(end 130.315 106.4)
		(width 0.15)
		(layer "F.Cu")
		(net 141)
	)
	(segment
		(start 44.6725 125.5725)
		(end 44.38 125.28)
		(width 0.155)
		(layer "B.Cu")
		(net 142)
	)
	(segment
		(start 47.8 126.95)
		(end 47.8 126.14)
		(width 0.155)
		(layer "B.Cu")
		(net 142)
	)
	(segment
		(start 46.177077 125.5725)
		(end 44.6725 125.5725)
		(width 0.155)
		(layer "B.Cu")
		(net 142)
	)
	(segment
		(start 44.38 124.56)
		(end 43.77 123.95)
		(width 0.155)
		(layer "B.Cu")
		(net 142)
	)
	(segment
		(start 44.38 125.28)
		(end 44.38 124.56)
		(width 0.155)
		(layer "B.Cu")
		(net 142)
	)
	(segment
		(start 47.8 126.14)
		(end 47.49 125.83)
		(width 0.155)
		(layer "B.Cu")
		(net 142)
	)
	(segment
		(start 46.434577 125.83)
		(end 46.177077 125.5725)
		(width 0.155)
		(layer "B.Cu")
		(net 142)
	)
	(segment
		(start 47.49 125.83)
		(end 46.434577 125.83)
		(width 0.155)
		(layer "B.Cu")
		(net 142)
	)
	(segment
		(start 43.77 126.68)
		(end 43.5 126.95)
		(width 0.15)
		(layer "B.Cu")
		(net 143)
	)
	(segment
		(start 43.77 125.83)
		(end 43.77 126.68)
		(width 0.15)
		(layer "B.Cu")
		(net 143)
	)
	(segment
		(start 74.385 101)
		(end 75.06 101.675)
		(width 0.15)
		(layer "B.Cu")
		(net 144)
	)
	(segment
		(start 77.625 103.125)
		(end 77.625 104.025)
		(width 0.15)
		(layer "B.Cu")
		(net 144)
	)
	(segment
		(start 77.625 104.025)
		(end 78.35 104.75)
		(width 0.15)
		(layer "B.Cu")
		(net 144)
	)
	(segment
		(start 78.35 104.75)
		(end 79.1 104.75)
		(width 0.15)
		(layer "B.Cu")
		(net 144)
	)
	(segment
		(start 75.06 101.675)
		(end 76.175 101.675)
		(width 0.15)
		(layer "B.Cu")
		(net 144)
	)
	(segment
		(start 76.175 101.675)
		(end 77.625 103.125)
		(width 0.15)
		(layer "B.Cu")
		(net 144)
	)
	(segment
		(start 74.385 101.95)
		(end 76.05 101.95)
		(width 0.15)
		(layer "B.Cu")
		(net 145)
	)
	(segment
		(start 76.05 101.95)
		(end 77.25 103.15)
		(width 0.15)
		(layer "B.Cu")
		(net 145)
	)
	(segment
		(start 77.25 103.15)
		(end 77.25 104.75)
		(width 0.15)
		(layer "B.Cu")
		(net 145)
	)
	(segment
		(start 60.55 125.385)
		(end 60.55 126.6)
		(width 0.2)
		(layer "B.Cu")
		(net 146)
	)
	(segment
		(start 68.85 125.285)
		(end 68.85 126.4)
		(width 0.15)
		(layer "F.Cu")
		(net 147)
	)
	(segment
		(start 68.85 126.4)
		(end 68.8 126.45)
		(width 0.15)
		(layer "F.Cu")
		(net 147)
	)
	(segment
		(start 47.9 96.4)
		(end 47.9 94.6875)
		(width 0.5)
		(layer "B.Cu")
		(net 148)
	)
	(segment
		(start 49.31 103.85)
		(end 49.31 102.59)
		(width 0.5)
		(layer "B.Cu")
		(net 148)
	)
	(segment
		(start 49.31 102.59)
		(end 50.1 101.8)
		(width 0.5)
		(layer "B.Cu")
		(net 148)
	)
	(segment
		(start 50.5 96.9)
		(end 48.4 96.9)
		(width 0.5)
		(layer "B.Cu")
		(net 148)
	)
	(segment
		(start 51.8 98.2)
		(end 50.5 96.9)
		(width 0.5)
		(layer "B.Cu")
		(net 148)
	)
	(segment
		(start 50.1 101.8)
		(end 51.8 101.8)
		(width 0.5)
		(layer "B.Cu")
		(net 148)
	)
	(segment
		(start 53.57 103.85)
		(end 53.57 102.27)
		(width 0.5)
		(layer "B.Cu")
		(net 148)
	)
	(segment
		(start 51.8 101.8)
		(end 51.8 98.2)
		(width 0.5)
		(layer "B.Cu")
		(net 148)
	)
	(segment
		(start 53.1 101.8)
		(end 51.8 101.8)
		(width 0.5)
		(layer "B.Cu")
		(net 148)
	)
	(segment
		(start 48.4 96.9)
		(end 47.9 96.4)
		(width 0.5)
		(layer "B.Cu")
		(net 148)
	)
	(segment
		(start 53.57 102.27)
		(end 53.1 101.8)
		(width 0.5)
		(layer "B.Cu")
		(net 148)
	)
	(segment
		(start 47.475 103.85)
		(end 46.77 103.85)
		(width 0.5)
		(layer "B.Cu")
		(net 149)
	)
	(segment
		(start 53.3 96.7)
		(end 53.69375 96.30625)
		(width 0.5)
		(layer "B.Cu")
		(net 149)
	)
	(segment
		(start 53.69375 96.30625)
		(end 53.69375 95.54375)
		(width 0.5)
		(layer "B.Cu")
		(net 149)
	)
	(segment
		(start 50.4 105.2)
		(end 54.2 105.2)
		(width 0.5)
		(layer "B.Cu")
		(net 149)
	)
	(segment
		(start 53.69375 95.54375)
		(end 54.5 94.7375)
		(width 0.5)
		(layer "B.Cu")
		(net 149)
	)
	(segment
		(start 54.2 105.2)
		(end 54.55 104.85)
		(width 0.5)
		(layer "B.Cu")
		(net 149)
	)
	(segment
		(start 50.4 105.2)
		(end 48.825 105.2)
		(width 0.5)
		(layer "B.Cu")
		(net 149)
	)
	(segment
		(start 51.03 105.17)
		(end 51 105.2)
		(width 0.5)
		(layer "B.Cu")
		(net 149)
	)
	(segment
		(start 54.55 104.85)
		(end 54.55 101.95)
		(width 0.5)
		(layer "B.Cu")
		(net 149)
	)
	(segment
		(start 48.825 105.2)
		(end 47.475 103.85)
		(width 0.5)
		(layer "B.Cu")
		(net 149)
	)
	(segment
		(start 51.03 103.85)
		(end 51.03 105.17)
		(width 0.5)
		(layer "B.Cu")
		(net 149)
	)
	(segment
		(start 53.3 100.7)
		(end 53.3 96.7)
		(width 0.5)
		(layer "B.Cu")
		(net 149)
	)
	(segment
		(start 54.55 101.95)
		(end 53.3 100.7)
		(width 0.5)
		(layer "B.Cu")
		(net 149)
	)
	(segment
		(start 51 105.2)
		(end 50.4 105.2)
		(width 0.5)
		(layer "B.Cu")
		(net 149)
	)
	(segment
		(start 107.45 126.45)
		(end 107.65 126.25)
		(width 0.15)
		(layer "F.Cu")
		(net 150)
	)
	(segment
		(start 107.6 125.325)
		(end 107.64 125.285)
		(width 0.15)
		(layer "F.Cu")
		(net 150)
	)
	(segment
		(start 107.6 126.5)
		(end 107.6 125.325)
		(width 0.15)
		(layer "F.Cu")
		(net 150)
	)
	(segment
		(start 77.3995 116.681926)
		(end 76.899425 117.182001)
		(width 0.155)
		(layer "F.Cu")
		(net 151)
	)
	(segment
		(start 77.3995 113.3255)
		(end 77.3995 114.601999)
		(width 0.155)
		(layer "F.Cu")
		(net 151)
	)
	(segment
		(start 77.5 115.115)
		(end 77.5 115.885)
		(width 0.165)
		(layer "F.Cu")
		(net 151)
	)
	(segment
		(start 76.899425 117.182001)
		(end 76.899425 117.564505)
		(width 0.155)
		(layer "F.Cu")
		(net 151)
	)
	(segment
		(start 77.525 113.2)
		(end 77.3995 113.3255)
		(width 0.155)
		(layer "F.Cu")
		(net 151)
	)
	(segment
		(start 77.3995 114.601999)
		(end 77.5 114.702499)
		(width 0.155)
		(layer "F.Cu")
		(net 151)
	)
	(segment
		(start 76.95 108.767469)
		(end 76.8995 108.817969)
		(width 0.155)
		(layer "F.Cu")
		(net 151)
	)
	(segment
		(start 76.899425 117.564505)
		(end 76.99992 117.665)
		(width 0.155)
		(layer "F.Cu")
		(net 151)
	)
	(segment
		(start 76.8995 108.988075)
		(end 77.169091 109.257666)
		(width 0.155)
		(layer "F.Cu")
		(net 151)
	)
	(segment
		(start 77.5 114.702499)
		(end 77.5 115.115)
		(width 0.155)
		(layer "F.Cu")
		(net 151)
	)
	(segment
		(start 77.3995 116.1105)
		(end 77.3995 116.681926)
		(width 0.155)
		(layer "F.Cu")
		(net 151)
	)
	(segment
		(start 77.169091 109.257666)
		(end 77.342334 109.257666)
		(width 0.155)
		(layer "F.Cu")
		(net 151)
	)
	(segment
		(start 76.8995 108.817969)
		(end 76.8995 108.988075)
		(width 0.155)
		(layer "F.Cu")
		(net 151)
	)
	(segment
		(start 77.5 116.01)
		(end 77.3995 116.1105)
		(width 0.155)
		(layer "F.Cu")
		(net 151)
	)
	(via
		(at 77.525 113.2)
		(size 0.45)
		(drill 0.1)
		(layers "F.Cu" "B.Cu")
		(net 151)
	)
	(via
		(at 77.342334 109.257666)
		(size 0.45)
		(drill 0.1)
		(layers "F.Cu" "B.Cu")
		(net 151)
	)
	(segment
		(start 77.525 113.2)
		(end 77.374 113.049)
		(width 0.16)
		(layer "In3.Cu")
		(net 151)
	)
	(segment
		(start 77.374 113.049)
		(end 77.374 111.161718)
		(width 0.16)
		(layer "In3.Cu")
		(net 151)
	)
	(segment
		(start 77.57 110.965718)
		(end 77.57 109.75)
		(width 0.16)
		(layer "In3.Cu")
		(net 151)
	)
	(segment
		(start 77.342334 109.522334)
		(end 77.342334 109.257666)
		(width 0.16)
		(layer "In3.Cu")
		(net 151)
	)
	(segment
		(start 77.57 109.75)
		(end 77.342334 109.522334)
		(width 0.16)
		(layer "In3.Cu")
		(net 151)
	)
	(segment
		(start 77.374 111.161718)
		(end 77.57 110.965718)
		(width 0.16)
		(layer "In3.Cu")
		(net 151)
	)
	(segment
		(start 72.8245 111.761926)
		(end 71.3995 113.186926)
		(width 0.155)
		(layer "F.Cu")
		(net 152)
	)
	(segment
		(start 72.8245 109.661926)
		(end 72.8245 111.761926)
		(width 0.155)
		(layer "F.Cu")
		(net 152)
	)
	(segment
		(start 71.3995 114.601999)
		(end 71.5 114.702499)
		(width 0.155)
		(layer "F.Cu")
		(net 152)
	)
	(segment
		(start 73.35 108.767469)
		(end 73.2995 108.817969)
		(width 0.155)
		(layer "F.Cu")
		(net 152)
	)
	(segment
		(start 73.2995 108.817969)
		(end 73.2995 109.186926)
		(width 0.155)
		(layer "F.Cu")
		(net 152)
	)
	(segment
		(start 72.811925 120.8105)
		(end 73.103535 121.10211)
		(width 0.155)
		(layer "F.Cu")
		(net 152)
	)
	(segment
		(start 71.3995 116.911926)
		(end 71.1795 117.131926)
		(width 0.155)
		(layer "F.Cu")
		(net 152)
	)
	(segment
		(start 71.3995 116.398001)
		(end 71.3995 116.911926)
		(width 0.155)
		(layer "F.Cu")
		(net 152)
	)
	(segment
		(start 71.3995 113.186926)
		(end 71.3995 114.601999)
		(width 0.155)
		(layer "F.Cu")
		(net 152)
	)
	(segment
		(start 71.1795 119.368074)
		(end 71.6595 119.848074)
		(width 0.155)
		(layer "F.Cu")
		(net 152)
	)
	(segment
		(start 73.103535 121.10211)
		(end 73.30789 121.10211)
		(width 0.155)
		(layer "F.Cu")
		(net 152)
	)
	(segment
		(start 71.6595 120.258074)
		(end 72.211926 120.8105)
		(width 0.155)
		(layer "F.Cu")
		(net 152)
	)
	(segment
		(start 71.5 115.885)
		(end 71.5 116.297501)
		(width 0.155)
		(layer "F.Cu")
		(net 152)
	)
	(segment
		(start 72.211926 120.8105)
		(end 72.811925 120.8105)
		(width 0.155)
		(layer "F.Cu")
		(net 152)
	)
	(segment
		(start 71.5 116.297501)
		(end 71.3995 116.398001)
		(width 0.155)
		(layer "F.Cu")
		(net 152)
	)
	(segment
		(start 71.1795 117.131926)
		(end 71.1795 117.8195)
		(width 0.155)
		(layer "F.Cu")
		(net 152)
	)
	(segment
		(start 71.3295 117.9695)
		(end 71.405549 117.9695)
		(width 0.155)
		(layer "F.Cu")
		(net 152)
	)
	(segment
		(start 71.5 114.702499)
		(end 71.5 115.115)
		(width 0.155)
		(layer "F.Cu")
		(net 152)
	)
	(segment
		(start 73.2995 109.186926)
		(end 72.8245 109.661926)
		(width 0.155)
		(layer "F.Cu")
		(net 152)
	)
	(segment
		(start 71.6595 119.848074)
		(end 71.6595 120.258074)
		(width 0.155)
		(layer "F.Cu")
		(net 152)
	)
	(segment
		(start 71.405549 118.2695)
		(end 71.3295 118.2695)
		(width 0.155)
		(layer "F.Cu")
		(net 152)
	)
	(segment
		(start 71.5 115.115)
		(end 71.5 115.885)
		(width 0.165)
		(layer "F.Cu")
		(net 152)
	)
	(segment
		(start 71.1795 118.4195)
		(end 71.1795 119.368074)
		(width 0.155)
		(layer "F.Cu")
		(net 152)
	)
	(via
		(at 73.30789 121.10211)
		(size 0.45)
		(drill 0.1)
		(layers "F.Cu" "B.Cu")
		(net 152)
	)
	(arc
		(start 71.3295 118.2695)
		(mid 71.223434 118.313434)
		(end 71.1795 118.4195)
		(width 0.155)
		(layer "F.Cu")
		(net 152)
	)
	(arc
		(start 71.405549 117.9695)
		(mid 71.511615 118.013434)
		(end 71.555549 118.1195)
		(width 0.155)
		(layer "F.Cu")
		(net 152)
	)
	(arc
		(start 71.555549 118.1195)
		(mid 71.511615 118.225566)
		(end 71.405549 118.2695)
		(width 0.155)
		(layer "F.Cu")
		(net 152)
	)
	(arc
		(start 71.1795 117.8195)
		(mid 71.223434 117.925566)
		(end 71.3295 117.9695)
		(width 0.155)
		(layer "F.Cu")
		(net 152)
	)
	(segment
		(start 73.14992 120.065)
		(end 72.89892 120.316)
		(width 0.16)
		(layer "B.Cu")
		(net 152)
	)
	(segment
		(start 73.102828 121.10211)
		(end 73.30789 121.10211)
		(width 0.16)
		(layer "B.Cu")
		(net 152)
	)
	(segment
		(start 72.89892 120.898202)
		(end 73.102828 121.10211)
		(width 0.16)
		(layer "B.Cu")
		(net 152)
	)
	(segment
		(start 72.89892 120.316)
		(end 72.89892 120.898202)
		(width 0.16)
		(layer "B.Cu")
		(net 152)
	)
	(segment
		(start 30.815 105.685)
		(end 32.15 105.685)
		(width 0.15)
		(layer "F.Cu")
		(net 153)
	)
	(segment
		(start 30.775 105.725)
		(end 30.815 105.685)
		(width 0.15)
		(layer "F.Cu")
		(net 153)
	)
	(segment
		(start 71.1005 113.063074)
		(end 71.1005 114.601999)
		(width 0.155)
		(layer "F.Cu")
		(net 154)
	)
	(segment
		(start 72.89211 121.313535)
		(end 72.688075 121.1095)
		(width 0.155)
		(layer "F.Cu")
		(net 154)
	)
	(segment
		(start 71 114.702499)
		(end 71 115.115)
		(width 0.155)
		(layer "F.Cu")
		(net 154)
	)
	(segment
		(start 71.1005 116.398001)
		(end 71 116.297501)
		(width 0.155)
		(layer "F.Cu")
		(net 154)
	)
	(segment
		(start 72.95 108.767469)
		(end 73.0005 108.817969)
		(width 0.155)
		(layer "F.Cu")
		(net 154)
	)
	(segment
		(start 72.5255 111.638074)
		(end 71.1005 113.063074)
		(width 0.155)
		(layer "F.Cu")
		(net 154)
	)
	(segment
		(start 72.89211 121.51789)
		(end 72.89211 121.313535)
		(width 0.155)
		(layer "F.Cu")
		(net 154)
	)
	(segment
		(start 70.8805 119.491926)
		(end 70.8805 117.008074)
		(width 0.155)
		(layer "F.Cu")
		(net 154)
	)
	(segment
		(start 73.0005 109.063074)
		(end 72.5255 109.538074)
		(width 0.155)
		(layer "F.Cu")
		(net 154)
	)
	(segment
		(start 72.088074 121.1095)
		(end 71.3605 120.381926)
		(width 0.155)
		(layer "F.Cu")
		(net 154)
	)
	(segment
		(start 72.5255 109.538074)
		(end 72.5255 111.638074)
		(width 0.155)
		(layer "F.Cu")
		(net 154)
	)
	(segment
		(start 72.688075 121.1095)
		(end 72.088074 121.1095)
		(width 0.155)
		(layer "F.Cu")
		(net 154)
	)
	(segment
		(start 71 115.115)
		(end 71 115.885)
		(width 0.165)
		(layer "F.Cu")
		(net 154)
	)
	(segment
		(start 71.1005 114.601999)
		(end 71 114.702499)
		(width 0.155)
		(layer "F.Cu")
		(net 154)
	)
	(segment
		(start 70.8805 117.008074)
		(end 71.1005 116.788074)
		(width 0.155)
		(layer "F.Cu")
		(net 154)
	)
	(segment
		(start 71.3605 120.381926)
		(end 71.3605 119.971926)
		(width 0.155)
		(layer "F.Cu")
		(net 154)
	)
	(segment
		(start 71.1005 116.788074)
		(end 71.1005 116.398001)
		(width 0.155)
		(layer "F.Cu")
		(net 154)
	)
	(segment
		(start 73.0005 108.817969)
		(end 73.0005 109.063074)
		(width 0.155)
		(layer "F.Cu")
		(net 154)
	)
	(segment
		(start 71 116.297501)
		(end 71 115.885)
		(width 0.155)
		(layer "F.Cu")
		(net 154)
	)
	(segment
		(start 71.3605 119.971926)
		(end 70.8805 119.491926)
		(width 0.155)
		(layer "F.Cu")
		(net 154)
	)
	(via
		(at 72.89211 121.51789)
		(size 0.45)
		(drill 0.1)
		(layers "F.Cu" "B.Cu")
		(net 154)
	)
	(segment
		(start 72.60092 121.021638)
		(end 72.89211 121.312828)
		(width 0.16)
		(layer "B.Cu")
		(net 154)
	)
	(segment
		(start 72.34992 120.065)
		(end 72.60092 120.316)
		(width 0.16)
		(layer "B.Cu")
		(net 154)
	)
	(segment
		(start 72.60092 120.316)
		(end 72.60092 121.021638)
		(width 0.16)
		(layer "B.Cu")
		(net 154)
	)
	(segment
		(start 72.89211 121.312828)
		(end 72.89211 121.51789)
		(width 0.16)
		(layer "B.Cu")
		(net 154)
	)
	(segment
		(start 142.485 114)
		(end 143.8 114)
		(width 0.15)
		(layer "B.Cu")
		(net 155)
	)
	(segment
		(start 132.294987 86.497987)
		(end 132.25 86.453)
		(width 0.155)
		(layer "F.Cu")
		(net 156)
	)
	(segment
		(start 114.746823 79.379636)
		(end 114.746823 79.159632)
		(width 0.155)
		(layer "F.Cu")
		(net 156)
	)
	(segment
		(start 114.790757 79.053566)
		(end 114.894323 78.95)
		(width 0.155)
		(layer "F.Cu")
		(net 156)
	)
	(segment
		(start 135.307393 86.6005)
		(end 132.542475 86.6005)
		(width 0.155)
		(layer "F.Cu")
		(net 156)
	)
	(segment
		(start 114.847323 79.480136)
		(end 114.746823 79.379636)
		(width 0.155)
		(layer "F.Cu")
		(net 156)
	)
	(segment
		(start 135.865 86.25)
		(end 135.660946 86.454054)
		(width 0.155)
		(layer "F.Cu")
		(net 156)
	)
	(via
		(at 132.25 86.453)
		(size 0.45)
		(drill 0.1)
		(layers "F.Cu" "B.Cu")
		(net 156)
	)
	(via
		(at 114.894323 78.95)
		(size 0.45)
		(drill 0.1)
		(layers "F.Cu" "B.Cu")
		(net 156)
	)
	(arc
		(start 132.294987 86.497987)
		(mid 132.408535 86.573858)
		(end 132.542475 86.6005)
		(width 0.155)
		(layer "F.Cu")
		(net 156)
	)
	(arc
		(start 114.746823 79.159632)
		(mid 114.758241 79.102229)
		(end 114.790757 79.053566)
		(width 0.155)
		(layer "F.Cu")
		(net 156)
	)
	(arc
		(start 135.307393 86.6005)
		(mid 135.498734 86.56244)
		(end 135.660946 86.454054)
		(width 0.155)
		(layer "F.Cu")
		(net 156)
	)
	(segment
		(start 122.489 93.808282)
		(end 122.489 95.528282)
		(width 0.16)
		(layer "In5.Cu")
		(net 156)
	)
	(segment
		(start 114.746323 79.098)
		(end 114.746323 80.185605)
		(width 0.16)
		(layer "In5.Cu")
		(net 156)
	)
	(segment
		(start 117.089 82.528282)
		(end 117.089 85.078282)
		(width 0.16)
		(layer "In5.Cu")
		(net 156)
	)
	(segment
		(start 114.746323 80.185605)
		(end 117.089 82.528282)
		(width 0.16)
		(layer "In5.Cu")
		(net 156)
	)
	(segment
		(start 120.249 90.461)
		(end 120.249 92.688282)
		(width 0.16)
		(layer "In5.Cu")
		(net 156)
	)
	(segment
		(start 129.701 93.418282)
		(end 129.701 88.488282)
		(width 0.16)
		(layer "In5.Cu")
		(net 156)
	)
	(segment
		(start 114.894323 78.95)
		(end 114.746323 79.098)
		(width 0.16)
		(layer "In5.Cu")
		(net 156)
	)
	(segment
		(start 129.701 88.488282)
		(end 131.588282 86.601)
		(width 0.16)
		(layer "In5.Cu")
		(net 156)
	)
	(segment
		(start 132.102 86.601)
		(end 132.25 86.453)
		(width 0.16)
		(layer "In5.Cu")
		(net 156)
	)
	(segment
		(start 120.467554 90.261)
		(end 120.449 90.261)
		(width 0.16)
		(layer "In5.Cu")
		(net 156)
	)
	(segment
		(start 120.449 89.861)
		(end 120.467554 89.861)
		(width 0.16)
		(layer "In5.Cu")
		(net 156)
	)
	(segment
		(start 120.661718 93.101)
		(end 121.781718 93.101)
		(width 0.16)
		(layer "In5.Cu")
		(net 156)
	)
	(segment
		(start 127.248282 95.871)
		(end 129.701 93.418282)
		(width 0.16)
		(layer "In5.Cu")
		(net 156)
	)
	(segment
		(start 118.061718 86.051)
		(end 118.361718 86.051)
		(width 0.16)
		(layer "In5.Cu")
		(net 156)
	)
	(segment
		(start 120.249 87.938282)
		(end 120.249 89.661)
		(width 0.16)
		(layer "In5.Cu")
		(net 156)
	)
	(segment
		(start 122.489 95.528282)
		(end 122.831718 95.871)
		(width 0.16)
		(layer "In5.Cu")
		(net 156)
	)
	(segment
		(start 122.831718 95.871)
		(end 127.248282 95.871)
		(width 0.16)
		(layer "In5.Cu")
		(net 156)
	)
	(segment
		(start 118.361718 86.051)
		(end 120.249 87.938282)
		(width 0.16)
		(layer "In5.Cu")
		(net 156)
	)
	(segment
		(start 120.249 92.688282)
		(end 120.661718 93.101)
		(width 0.16)
		(layer "In5.Cu")
		(net 156)
	)
	(segment
		(start 131.588282 86.601)
		(end 132.102 86.601)
		(width 0.16)
		(layer "In5.Cu")
		(net 156)
	)
	(segment
		(start 117.089 85.078282)
		(end 118.061718 86.051)
		(width 0.16)
		(layer "In5.Cu")
		(net 156)
	)
	(segment
		(start 121.781718 93.101)
		(end 122.489 93.808282)
		(width 0.16)
		(layer "In5.Cu")
		(net 156)
	)
	(arc
		(start 120.667554 90.061)
		(mid 120.608975 90.202421)
		(end 120.467554 90.261)
		(width 0.16)
		(layer "In5.Cu")
		(net 156)
	)
	(arc
		(start 120.449 90.261)
		(mid 120.307579 90.319579)
		(end 120.249 90.461)
		(width 0.16)
		(layer "In5.Cu")
		(net 156)
	)
	(arc
		(start 120.249 89.661)
		(mid 120.307579 89.802421)
		(end 120.449 89.861)
		(width 0.16)
		(layer "In5.Cu")
		(net 156)
	)
	(arc
		(start 120.467554 89.861)
		(mid 120.608975 89.919579)
		(end 120.667554 90.061)
		(width 0.16)
		(layer "In5.Cu")
		(net 156)
	)
	(segment
		(start 132.35 92.081425)
		(end 132.501925 91.9295)
		(width 0.155)
		(layer "F.Cu")
		(net 157)
	)
	(segment
		(start 132.501925 91.9295)
		(end 133.8555 91.9295)
		(width 0.155)
		(layer "F.Cu")
		(net 157)
	)
	(segment
		(start 133.8555 91.9295)
		(end 134.236 92.31)
		(width 0.155)
		(layer "F.Cu")
		(net 157)
	)
	(segment
		(start 114.697823 71.179636)
		(end 114.597323 71.280136)
		(width 0.155)
		(layer "F.Cu")
		(net 157)
	)
	(segment
		(start 132.35 92.3)
		(end 132.35 92.081425)
		(width 0.155)
		(layer "F.Cu")
		(net 157)
	)
	(segment
		(start 114.54 70.38)
		(end 114.697823 70.537823)
		(width 0.155)
		(layer "F.Cu")
		(net 157)
	)
	(segment
		(start 114.697823 70.537823)
		(end 114.697823 71.179636)
		(width 0.155)
		(layer "F.Cu")
		(net 157)
	)
	(via
		(at 114.54 70.38)
		(size 0.45)
		(drill 0.1)
		(layers "F.Cu" "B.Cu")
		(net 157)
	)
	(via
		(at 132.35 92.3)
		(size 0.45)
		(drill 0.1)
		(layers "F.Cu" "B.Cu")
		(net 157)
	)
	(segment
		(start 129.674 82.988282)
		(end 129.674 75.988282)
		(width 0.16)
		(layer "In3.Cu")
		(net 157)
	)
	(segment
		(start 132.699 90.998282)
		(end 132.151718 90.451)
		(width 0.16)
		(layer "In3.Cu")
		(net 157)
	)
	(segment
		(start 115.198282 69.331)
		(end 114.661 69.868282)
		(width 0.16)
		(layer "In3.Cu")
		(net 157)
	)
	(segment
		(start 126.321718 69.591)
		(end 116.801718 69.591)
		(width 0.16)
		(layer "In3.Cu")
		(net 157)
	)
	(segment
		(start 116.801718 69.591)
		(end 116.541718 69.331)
		(width 0.16)
		(layer "In3.Cu")
		(net 157)
	)
	(segment
		(start 114.661 69.868282)
		(end 114.661 70.259)
		(width 0.16)
		(layer "In3.Cu")
		(net 157)
	)
	(segment
		(start 116.541718 69.331)
		(end 115.198282 69.331)
		(width 0.16)
		(layer "In3.Cu")
		(net 157)
	)
	(segment
		(start 126.949 70.218282)
		(end 126.321718 69.591)
		(width 0.16)
		(layer "In3.Cu")
		(net 157)
	)
	(segment
		(start 132.35 92.3)
		(end 132.35 92.185718)
		(width 0.16)
		(layer "In3.Cu")
		(net 157)
	)
	(segment
		(start 132.35 92.185718)
		(end 132.699 91.836718)
		(width 0.16)
		(layer "In3.Cu")
		(net 157)
	)
	(segment
		(start 130.474 90.023282)
		(end 130.474 83.788282)
		(width 0.16)
		(layer "In3.Cu")
		(net 157)
	)
	(segment
		(start 132.151718 90.451)
		(end 130.901718 90.451)
		(width 0.16)
		(layer "In3.Cu")
		(net 157)
	)
	(segment
		(start 114.661 70.259)
		(end 114.54 70.38)
		(width 0.16)
		(layer "In3.Cu")
		(net 157)
	)
	(segment
		(start 130.901718 90.451)
		(end 130.474 90.023282)
		(width 0.16)
		(layer "In3.Cu")
		(net 157)
	)
	(segment
		(start 129.674 75.988282)
		(end 126.949 73.263282)
		(width 0.16)
		(layer "In3.Cu")
		(net 157)
	)
	(segment
		(start 130.474 83.788282)
		(end 129.674 82.988282)
		(width 0.16)
		(layer "In3.Cu")
		(net 157)
	)
	(segment
		(start 132.699 91.836718)
		(end 132.699 90.998282)
		(width 0.16)
		(layer "In3.Cu")
		(net 157)
	)
	(segment
		(start 126.949 73.263282)
		(end 126.949 70.218282)
		(width 0.16)
		(layer "In3.Cu")
		(net 157)
	)
	(segment
		(start 114.403889 79.053566)
		(end 114.300323 78.95)
		(width 0.155)
		(layer "F.Cu")
		(net 158)
	)
	(segment
		(start 114.347323 79.480136)
		(end 114.447823 79.379636)
		(width 0.155)
		(layer "F.Cu")
		(net 158)
	)
	(segment
		(start 135.307393 86.8995)
		(end 132.542475 86.8995)
		(width 0.155)
		(layer "F.Cu")
		(net 158)
	)
	(segment
		(start 132.294987 87.002013)
		(end 132.25 87.047)
		(width 0.155)
		(layer "F.Cu")
		(net 158)
	)
	(segment
		(start 135.865 87.25)
		(end 135.660946 87.045946)
		(width 0.155)
		(layer "F.Cu")
		(net 158)
	)
	(segment
		(start 114.447823 79.379636)
		(end 114.447823 79.159632)
		(width 0.155)
		(layer "F.Cu")
		(net 158)
	)
	(via
		(at 114.300323 78.95)
		(size 0.45)
		(drill 0.1)
		(layers "F.Cu" "B.Cu")
		(net 158)
	)
	(via
		(at 132.25 87.047)
		(size 0.45)
		(drill 0.1)
		(layers "F.Cu" "B.Cu")
		(net 158)
	)
	(arc
		(start 135.307393 86.8995)
		(mid 135.498734 86.93756)
		(end 135.660946 87.045946)
		(width 0.155)
		(layer "F.Cu")
		(net 158)
	)
	(arc
		(start 132.542475 86.8995)
		(mid 132.408535 86.926142)
		(end 132.294987 87.002013)
		(width 0.155)
		(layer "F.Cu")
		(net 158)
	)
	(arc
		(start 114.403889 79.053566)
		(mid 114.436405 79.102229)
		(end 114.447823 79.159632)
		(width 0.155)
		(layer "F.Cu")
		(net 158)
	)
	(segment
		(start 120.538282 93.399)
		(end 121.658282 93.399)
		(width 0.16)
		(layer "In5.Cu")
		(net 158)
	)
	(segment
		(start 129.999 93.541718)
		(end 129.999 88.611718)
		(width 0.16)
		(layer "In5.Cu")
		(net 158)
	)
	(segment
		(start 127.371718 96.169)
		(end 129.999 93.541718)
		(width 0.16)
		(layer "In5.Cu")
		(net 158)
	)
	(segment
		(start 114.448323 79.098)
		(end 114.448323 80.309041)
		(width 0.16)
		(layer "In5.Cu")
		(net 158)
	)
	(segment
		(start 114.300323 78.95)
		(end 114.448323 79.098)
		(width 0.16)
		(layer "In5.Cu")
		(net 158)
	)
	(segment
		(start 132.102 86.899)
		(end 132.25 87.047)
		(width 0.16)
		(layer "In5.Cu")
		(net 158)
	)
	(segment
		(start 131.711718 86.899)
		(end 132.102 86.899)
		(width 0.16)
		(layer "In5.Cu")
		(net 158)
	)
	(segment
		(start 122.191 95.651718)
		(end 122.708282 96.169)
		(width 0.16)
		(layer "In5.Cu")
		(net 158)
	)
	(segment
		(start 117.938282 86.349)
		(end 118.238282 86.349)
		(width 0.16)
		(layer "In5.Cu")
		(net 158)
	)
	(segment
		(start 116.791 85.201718)
		(end 117.938282 86.349)
		(width 0.16)
		(layer "In5.Cu")
		(net 158)
	)
	(segment
		(start 122.191 93.931718)
		(end 122.191 95.651718)
		(width 0.16)
		(layer "In5.Cu")
		(net 158)
	)
	(segment
		(start 119.951 92.811718)
		(end 120.538282 93.399)
		(width 0.16)
		(layer "In5.Cu")
		(net 158)
	)
	(segment
		(start 114.448323 80.309041)
		(end 116.791 82.651718)
		(width 0.16)
		(layer "In5.Cu")
		(net 158)
	)
	(segment
		(start 121.658282 93.399)
		(end 122.191 93.931718)
		(width 0.16)
		(layer "In5.Cu")
		(net 158)
	)
	(segment
		(start 119.951 88.061718)
		(end 119.951 92.811718)
		(width 0.16)
		(layer "In5.Cu")
		(net 158)
	)
	(segment
		(start 122.708282 96.169)
		(end 127.371718 96.169)
		(width 0.16)
		(layer "In5.Cu")
		(net 158)
	)
	(segment
		(start 129.999 88.611718)
		(end 131.711718 86.899)
		(width 0.16)
		(layer "In5.Cu")
		(net 158)
	)
	(segment
		(start 118.238282 86.349)
		(end 119.951 88.061718)
		(width 0.16)
		(layer "In5.Cu")
		(net 158)
	)
	(segment
		(start 116.791 82.651718)
		(end 116.791 85.201718)
		(width 0.16)
		(layer "In5.Cu")
		(net 158)
	)
	(segment
		(start 103.261926 109.3505)
		(end 104.319438 109.3505)
		(width 0.155)
		(layer "F.Cu")
		(net 159)
	)
	(segment
		(start 113.496823 71.179636)
		(end 113.597323 71.280136)
		(width 0.155)
		(layer "F.Cu")
		(net 159)
	)
	(segment
		(start 104.319438 109.3505)
		(end 104.669938 109)
		(width 0.155)
		(layer "F.Cu")
		(net 159)
	)
	(segment
		(start 102.676397 108.764971)
		(end 103.261926 109.3505)
		(width 0.155)
		(layer "F.Cu")
		(net 159)
	)
	(segment
		(start 101.7995 100.411926)
		(end 101.7995 107.888074)
		(width 0.155)
		(layer "F.Cu")
		(net 159)
	)
	(segment
		(start 102.393556 108.199286)
		(end 102.393555 108.199287)
		(width 0.155)
		(layer "F.Cu")
		(net 159)
	)
	(segment
		(start 113.644323 70.44)
		(end 113.496823 70.5875)
		(width 0.155)
		(layer "F.Cu")
		(net 159)
	)
	(segment
		(start 113.496823 70.5875)
		(end 113.496823 71.179636)
		(width 0.155)
		(layer "F.Cu")
		(net 159)
	)
	(segment
		(start 102.8995 99.311926)
		(end 101.7995 100.411926)
		(width 0.155)
		(layer "F.Cu")
		(net 159)
	)
	(segment
		(start 102.678205 108.19748)
		(end 102.678205 108.197479)
		(width 0.155)
		(layer "F.Cu")
		(net 159)
	)
	(segment
		(start 101.7995 107.888074)
		(end 102.110713 108.199287)
		(width 0.155)
		(layer "F.Cu")
		(net 159)
	)
	(segment
		(start 102.393555 108.199287)
		(end 102.395363 108.19748)
		(width 0.155)
		(layer "F.Cu")
		(net 159)
	)
	(segment
		(start 102.676398 108.764971)
		(end 102.676397 108.764971)
		(width 0.155)
		(layer "F.Cu")
		(net 159)
	)
	(segment
		(start 102.678204 108.480322)
		(end 102.678205 108.480321)
		(width 0.155)
		(layer "F.Cu")
		(net 159)
	)
	(segment
		(start 102.678205 108.480321)
		(end 102.676398 108.482129)
		(width 0.155)
		(layer "F.Cu")
		(net 159)
	)
	(segment
		(start 102.27 94.658575)
		(end 102.8995 95.288075)
		(width 0.155)
		(layer "F.Cu")
		(net 159)
	)
	(segment
		(start 102.27 94.43)
		(end 102.27 94.658575)
		(width 0.155)
		(layer "F.Cu")
		(net 159)
	)
	(segment
		(start 102.8995 95.288075)
		(end 102.8995 99.311926)
		(width 0.155)
		(layer "F.Cu")
		(net 159)
	)
	(via
		(at 108.87 77.27)
		(size 0.45)
		(drill 0.1)
		(layers "F.Cu" "B.Cu")
		(net 159)
	)
	(via
		(at 113.644323 70.44)
		(size 0.45)
		(drill 0.1)
		(layers "F.Cu" "B.Cu")
		(net 159)
	)
	(via
		(at 102.27 94.43)
		(size 0.45)
		(drill 0.1)
		(layers "F.Cu" "B.Cu")
		(net 159)
	)
	(arc
		(start 102.110713 108.199287)
		(mid 102.252135 108.257865)
		(end 102.393556 108.199286)
		(width 0.155)
		(layer "F.Cu")
		(net 159)
	)
	(arc
		(start 102.676398 108.482129)
		(mid 102.617819 108.623549)
		(end 102.676398 108.764971)
		(width 0.155)
		(layer "F.Cu")
		(net 159)
	)
	(arc
		(start 102.395363 108.19748)
		(mid 102.536783 108.138901)
		(end 102.678205 108.19748)
		(width 0.155)
		(layer "F.Cu")
		(net 159)
	)
	(arc
		(start 102.678205 108.197479)
		(mid 102.736783 108.338901)
		(end 102.678204 108.480322)
		(width 0.155)
		(layer "F.Cu")
		(net 159)
	)
	(segment
		(start 102.040718 94.43)
		(end 102.27 94.43)
		(width 0.16)
		(layer "In5.Cu")
		(net 159)
	)
	(segment
		(start 108.061718 77.349)
		(end 105.561718 77.349)
		(width 0.16)
		(layer "In5.Cu")
		(net 159)
	)
	(segment
		(start 104.249 81.061718)
		(end 104.249 88.261718)
		(width 0.16)
		(layer "In5.Cu")
		(net 159)
	)
	(segment
		(start 102.174 90.336718)
		(end 102.174 93.111718)
		(width 0.16)
		(layer "In5.Cu")
		(net 159)
	)
	(segment
		(start 108.87 77.27)
		(end 108.727 77.127)
		(width 0.16)
		(layer "In5.Cu")
		(net 159)
	)
	(segment
		(start 105.561718 77.349)
		(end 105.399 77.511718)
		(width 0.16)
		(layer "In5.Cu")
		(net 159)
	)
	(segment
		(start 104.249 88.261718)
		(end 102.174 90.336718)
		(width 0.16)
		(layer "In5.Cu")
		(net 159)
	)
	(segment
		(start 102.174 93.111718)
		(end 101.749 93.536718)
		(width 0.16)
		(layer "In5.Cu")
		(net 159)
	)
	(segment
		(start 101.749 94.138282)
		(end 102.040718 94.43)
		(width 0.16)
		(layer "In5.Cu")
		(net 159)
	)
	(segment
		(start 108.283718 77.127)
		(end 108.061718 77.349)
		(width 0.16)
		(layer "In5.Cu")
		(net 159)
	)
	(segment
		(start 105.399 77.511718)
		(end 105.399 79.911718)
		(width 0.16)
		(layer "In5.Cu")
		(net 159)
	)
	(segment
		(start 108.727 77.127)
		(end 108.283718 77.127)
		(width 0.16)
		(layer "In5.Cu")
		(net 159)
	)
	(segment
		(start 101.749 93.536718)
		(end 101.749 94.138282)
		(width 0.16)
		(layer "In5.Cu")
		(net 159)
	)
	(segment
		(start 105.399 79.911718)
		(end 104.249 81.061718)
		(width 0.16)
		(layer "In5.Cu")
		(net 159)
	)
	(segment
		(start 115.0495 73.758074)
		(end 115.0495 73.188074)
		(width 0.155)
		(layer "B.Cu")
		(net 159)
	)
	(segment
		(start 115.0495 73.188074)
		(end 113.506662 71.645236)
		(width 0.155)
		(layer "B.Cu")
		(net 159)
	)
	(segment
		(start 115.4695 76.201926)
		(end 115.4695 74.178074)
		(width 0.155)
		(layer "B.Cu")
		(net 159)
	)
	(segment
		(start 112.763074 77.0995)
		(end 114.571926 77.0995)
		(width 0.155)
		(layer "B.Cu")
		(net 159)
	)
	(segment
		(start 112.388074 76.7245)
		(end 112.763074 77.0995)
		(width 0.155)
		(layer "B.Cu")
		(net 159)
	)
	(segment
		(start 114.571926 77.0995)
		(end 115.4695 76.201926)
		(width 0.155)
		(layer "B.Cu")
		(net 159)
	)
	(segment
		(start 109.0405 77.0995)
		(end 109.861926 77.0995)
		(width 0.155)
		(layer "B.Cu")
		(net 159)
	)
	(segment
		(start 115.4695 74.178074)
		(end 115.0495 73.758074)
		(width 0.155)
		(layer "B.Cu")
		(net 159)
	)
	(segment
		(start 109.861926 77.0995)
		(end 110.236926 76.7245)
		(width 0.155)
		(layer "B.Cu")
		(net 159)
	)
	(segment
		(start 113.506662 71.645236)
		(end 113.506662 70.577662)
		(width 0.155)
		(layer "B.Cu")
		(net 159)
	)
	(segment
		(start 108.87 77.27)
		(end 109.0405 77.0995)
		(width 0.155)
		(layer "B.Cu")
		(net 159)
	)
	(segment
		(start 110.236926 76.7245)
		(end 112.388074 76.7245)
		(width 0.155)
		(layer "B.Cu")
		(net 159)
	)
	(segment
		(start 113.506662 70.577662)
		(end 113.644323 70.44)
		(width 0.155)
		(layer "B.Cu")
		(net 159)
	)
	(segment
		(start 142.485 112.4)
		(end 143.05 112.4)
		(width 0.15)
		(layer "B.Cu")
		(net 160)
	)
	(segment
		(start 143.15 112.5)
		(end 143.8 112.5)
		(width 0.15)
		(layer "B.Cu")
		(net 160)
	)
	(segment
		(start 143.05 112.4)
		(end 143.15 112.5)
		(width 0.15)
		(layer "B.Cu")
		(net 160)
	)
	(segment
		(start 103.9 75.7)
		(end 103.185 75.7)
		(width 0.15)
		(layer "B.Cu")
		(net 161)
	)
	(segment
		(start 105.8 70.5)
		(end 105.8 71.3)
		(width 0.15)
		(layer "B.Cu")
		(net 161)
	)
	(segment
		(start 107.7 70.3)
		(end 106 70.3)
		(width 0.15)
		(layer "B.Cu")
		(net 161)
	)
	(segment
		(start 106 70.3)
		(end 105.8 70.5)
		(width 0.15)
		(layer "B.Cu")
		(net 161)
	)
	(segment
		(start 104.6 72.5)
		(end 104.6 75)
		(width 0.15)
		(layer "B.Cu")
		(net 161)
	)
	(segment
		(start 105.8 71.3)
		(end 104.6 72.5)
		(width 0.15)
		(layer "B.Cu")
		(net 161)
	)
	(segment
		(start 104.6 75)
		(end 103.9 75.7)
		(width 0.15)
		(layer "B.Cu")
		(net 161)
	)
	(segment
		(start 105 75.7)
		(end 105 72.7)
		(width 0.15)
		(layer "B.Cu")
		(net 162)
	)
	(segment
		(start 105 72.7)
		(end 105.9 71.8)
		(width 0.15)
		(layer "B.Cu")
		(net 162)
	)
	(segment
		(start 105.9 71.8)
		(end 107.7 71.8)
		(width 0.15)
		(layer "B.Cu")
		(net 162)
	)
	(segment
		(start 104 76.7)
		(end 105 75.7)
		(width 0.15)
		(layer "B.Cu")
		(net 162)
	)
	(segment
		(start 103.185 76.7)
		(end 104 76.7)
		(width 0.15)
		(layer "B.Cu")
		(net 162)
	)
	(segment
		(start 133.348586 90.039989)
		(end 134.241627 89.146947)
		(width 0.155)
		(layer "F.Cu")
		(net 163)
	)
	(segment
		(start 135.306566 88.956566)
		(end 135.2 88.85)
		(width 0.155)
		(layer "F.Cu")
		(net 163)
	)
	(segment
		(start 113.347323 79.053323)
		(end 113.344 79.05)
		(width 0.155)
		(layer "F.Cu")
		(net 163)
	)
	(segment
		(start 134.595181 89.0005)
		(end 134.787368 89.0005)
		(width 0.155)
		(layer "F.Cu")
		(net 163)
	)
	(segment
		(start 133.139989 90.039989)
		(end 133.348586 90.039989)
		(width 0.155)
		(layer "F.Cu")
		(net 163)
	)
	(segment
		(start 113.347323 80.205136)
		(end 113.347323 79.053323)
		(width 0.155)
		(layer "F.Cu")
		(net 163)
	)
	(segment
		(start 141.5 88.75)
		(end 141.2 88.75)
		(width 0.155)
		(layer "F.Cu")
		(net 163)
	)
	(segment
		(start 140.887368 89.0005)
		(end 135.412632 89.0005)
		(width 0.155)
		(layer "F.Cu")
		(net 163)
	)
	(segment
		(start 134.893434 88.956566)
		(end 135 88.85)
		(width 0.155)
		(layer "F.Cu")
		(net 163)
	)
	(segment
		(start 141.2 88.75)
		(end 140.993434 88.956566)
		(width 0.155)
		(layer "F.Cu")
		(net 163)
	)
	(via
		(at 113.344 79.05)
		(size 0.45)
		(drill 0.1)
		(layers "F.Cu" "B.Cu")
		(net 163)
	)
	(via
		(at 133.139989 90.039989)
		(size 0.45)
		(drill 0.1)
		(layers "F.Cu" "B.Cu")
		(net 163)
	)
	(arc
		(start 134.787368 89.0005)
		(mid 134.844771 88.989082)
		(end 134.893434 88.956566)
		(width 0.155)
		(layer "F.Cu")
		(net 163)
	)
	(arc
		(start 135.412632 89.0005)
		(mid 135.355229 88.989082)
		(end 135.306566 88.956566)
		(width 0.155)
		(layer "F.Cu")
		(net 163)
	)
	(arc
		(start 140.993434 88.956566)
		(mid 140.944771 88.989082)
		(end 140.887368 89.0005)
		(width 0.155)
		(layer "F.Cu")
		(net 163)
	)
	(arc
		(start 134.241627 89.146947)
		(mid 134.403839 89.03856)
		(end 134.595181 89.0005)
		(width 0.155)
		(layer "F.Cu")
		(net 163)
	)
	(segment
		(start 113.199 79.195)
		(end 113.199 85.638282)
		(width 0.16)
		(layer "In5.Cu")
		(net 163)
	)
	(segment
		(start 117.699 92.188282)
		(end 117.699 97.488282)
		(width 0.16)
		(layer "In5.Cu")
		(net 163)
	)
	(segment
		(start 120.311718 100.101)
		(end 122.638282 100.101)
		(width 0.16)
		(layer "In5.Cu")
		(net 163)
	)
	(segment
		(start 133.139989 90.249293)
		(end 133.139989 90.039989)
		(width 0.16)
		(layer "In5.Cu")
		(net 163)
	)
	(segment
		(start 132.801 90.588282)
		(end 133.139989 90.249293)
		(width 0.16)
		(layer "In5.Cu")
		(net 163)
	)
	(segment
		(start 119.642305 99.10229)
		(end 119.642306 99.102289)
		(width 0.16)
		(layer "In5.Cu")
		(net 163)
	)
	(segment
		(start 113.849 86.288282)
		(end 113.849 88.338282)
		(width 0.16)
		(layer "In5.Cu")
		(net 163)
	)
	(segment
		(start 124.208282 98.531)
		(end 128.758282 98.531)
		(width 0.16)
		(layer "In5.Cu")
		(net 163)
	)
	(segment
		(start 128.758282 98.531)
		(end 132.801 94.488282)
		(width 0.16)
		(layer "In5.Cu")
		(net 163)
	)
	(segment
		(start 113.199 85.638282)
		(end 113.849 86.288282)
		(width 0.16)
		(layer "In5.Cu")
		(net 163)
	)
	(segment
		(start 132.801 94.488282)
		(end 132.801 90.588282)
		(width 0.16)
		(layer "In5.Cu")
		(net 163)
	)
	(segment
		(start 122.638282 100.101)
		(end 124.208282 98.531)
		(width 0.16)
		(layer "In5.Cu")
		(net 163)
	)
	(segment
		(start 119.636755 99.426037)
		(end 120.311718 100.101)
		(width 0.16)
		(layer "In5.Cu")
		(net 163)
	)
	(segment
		(start 119.642306 99.102289)
		(end 119.636754 99.107838)
		(width 0.16)
		(layer "In5.Cu")
		(net 163)
	)
	(segment
		(start 119.318557 98.789641)
		(end 119.324108 98.784091)
		(width 0.16)
		(layer "In5.Cu")
		(net 163)
	)
	(segment
		(start 113.849 88.338282)
		(end 117.699 92.188282)
		(width 0.16)
		(layer "In5.Cu")
		(net 163)
	)
	(segment
		(start 119.318558 98.78964)
		(end 119.318557 98.789641)
		(width 0.16)
		(layer "In5.Cu")
		(net 163)
	)
	(segment
		(start 117.699 97.488282)
		(end 119.000359 98.789641)
		(width 0.16)
		(layer "In5.Cu")
		(net 163)
	)
	(segment
		(start 113.344 79.05)
		(end 113.199 79.195)
		(width 0.16)
		(layer "In5.Cu")
		(net 163)
	)
	(segment
		(start 119.636754 99.426036)
		(end 119.636755 99.426037)
		(width 0.16)
		(layer "In5.Cu")
		(net 163)
	)
	(arc
		(start 119.000359 98.789641)
		(mid 119.15946 98.855543)
		(end 119.318558 98.78964)
		(width 0.16)
		(layer "In5.Cu")
		(net 163)
	)
	(arc
		(start 119.636754 99.107838)
		(mid 119.570853 99.266937)
		(end 119.636754 99.426036)
		(width 0.16)
		(layer "In5.Cu")
		(net 163)
	)
	(arc
		(start 119.642306 98.784091)
		(mid 119.708206 98.94319)
		(end 119.642305 99.10229)
		(width 0.16)
		(layer "In5.Cu")
		(net 163)
	)
	(arc
		(start 119.324108 98.784091)
		(mid 119.483207 98.71819)
		(end 119.642306 98.784091)
		(width 0.16)
		(layer "In5.Cu")
		(net 163)
	)
	(segment
		(start 135.26 121.99)
		(end 134.65 122.6)
		(width 0.2)
		(layer "F.Cu")
		(net 164)
	)
	(segment
		(start 136.3 121.99)
		(end 135.26 121.99)
		(width 0.2)
		(layer "F.Cu")
		(net 164)
	)
	(segment
		(start 134.65 126.45)
		(end 134.7 126.5)
		(width 0.2)
		(layer "F.Cu")
		(net 164)
	)
	(segment
		(start 134.65 122.6)
		(end 134.65 126.45)
		(width 0.2)
		(layer "F.Cu")
		(net 164)
	)
	(segment
		(start 102.6005 99.188074)
		(end 102.6005 95.411925)
		(width 0.155)
		(layer "F.Cu")
		(net 165)
	)
	(segment
		(start 113.06 70.43)
		(end 113.197823 70.567823)
		(width 0.155)
		(layer "F.Cu")
		(net 165)
	)
	(segment
		(start 113.197823 71.179636)
		(end 113.097323 71.280136)
		(width 0.155)
		(layer "F.Cu")
		(net 165)
	)
	(segment
		(start 102.6005 95.411925)
		(end 102.030909 94.842334)
		(width 0.155)
		(layer "F.Cu")
		(net 165)
	)
	(segment
		(start 102.030909 94.842334)
		(end 101.857666 94.842334)
		(width 0.155)
		(layer "F.Cu")
		(net 165)
	)
	(segment
		(start 101.5005 100.288074)
		(end 102.6005 99.188074)
		(width 0.155)
		(layer "F.Cu")
		(net 165)
	)
	(segment
		(start 104.319438 109.6495)
		(end 103.138074 109.6495)
		(width 0.155)
		(layer "F.Cu")
		(net 165)
	)
	(segment
		(start 113.197823 70.567823)
		(end 113.197823 71.179636)
		(width 0.155)
		(layer "F.Cu")
		(net 165)
	)
	(segment
		(start 104.669938 110)
		(end 104.319438 109.6495)
		(width 0.155)
		(layer "F.Cu")
		(net 165)
	)
	(segment
		(start 103.138074 109.6495)
		(end 101.5005 108.011926)
		(width 0.155)
		(layer "F.Cu")
		(net 165)
	)
	(segment
		(start 101.5005 108.011926)
		(end 101.5005 100.288074)
		(width 0.155)
		(layer "F.Cu")
		(net 165)
	)
	(via
		(at 108.875 76.681)
		(size 0.45)
		(drill 0.1)
		(layers "F.Cu" "B.Cu")
		(net 165)
	)
	(via
		(at 113.06 70.43)
		(size 0.45)
		(drill 0.1)
		(layers "F.Cu" "B.Cu")
		(net 165)
	)
	(via
		(at 101.857666 94.842334)
		(size 0.45)
		(drill 0.1)
		(layers "F.Cu" "B.Cu")
		(net 165)
	)
	(segment
		(start 108.160282 76.829)
		(end 107.938282 77.051)
		(width 0.16)
		(layer "In5.Cu")
		(net 165)
	)
	(segment
		(start 105.101 79.788282)
		(end 103.951 80.938282)
		(width 0.16)
		(layer "In5.Cu")
		(net 165)
	)
	(segment
		(start 101.451 93.413282)
		(end 101.451 94.261718)
		(width 0.16)
		(layer "In5.Cu")
		(net 165)
	)
	(segment
		(start 105.101 77.388282)
		(end 105.101 79.788282)
		(width 0.16)
		(layer "In5.Cu")
		(net 165)
	)
	(segment
		(start 108.727 76.829)
		(end 108.160282 76.829)
		(width 0.16)
		(layer "In5.Cu")
		(net 165)
	)
	(segment
		(start 101.876 92.988282)
		(end 101.451 93.413282)
		(width 0.16)
		(layer "In5.Cu")
		(net 165)
	)
	(segment
		(start 103.951 88.138282)
		(end 101.876 90.213282)
		(width 0.16)
		(layer "In5.Cu")
		(net 165)
	)
	(segment
		(start 105.438282 77.051)
		(end 105.101 77.388282)
		(width 0.16)
		(layer "In5.Cu")
		(net 165)
	)
	(segment
		(start 103.951 80.938282)
		(end 103.951 88.138282)
		(width 0.16)
		(layer "In5.Cu")
		(net 165)
	)
	(segment
		(start 101.876 90.213282)
		(end 101.876 92.988282)
		(width 0.16)
		(layer "In5.Cu")
		(net 165)
	)
	(segment
		(start 101.451 94.261718)
		(end 101.857666 94.668384)
		(width 0.16)
		(layer "In5.Cu")
		(net 165)
	)
	(segment
		(start 108.875 76.681)
		(end 108.727 76.829)
		(width 0.16)
		(layer "In5.Cu")
		(net 165)
	)
	(segment
		(start 107.938282 77.051)
		(end 105.438282 77.051)
		(width 0.16)
		(layer "In5.Cu")
		(net 165)
	)
	(segment
		(start 101.857666 94.668384)
		(end 101.857666 94.842334)
		(width 0.16)
		(layer "In5.Cu")
		(net 165)
	)
	(segment
		(start 108.875 76.681)
		(end 108.9945 76.8005)
		(width 0.155)
		(layer "B.Cu")
		(net 165)
	)
	(segment
		(start 108.9945 76.8005)
		(end 109.738074 76.8005)
		(width 0.155)
		(layer "B.Cu")
		(net 165)
	)
	(segment
		(start 109.738074 76.8005)
		(end 110.113074 76.4255)
		(width 0.155)
		(layer "B.Cu")
		(net 165)
	)
	(segment
		(start 114.7505 73.881926)
		(end 114.7505 73.311926)
		(width 0.155)
		(layer "B.Cu")
		(net 165)
	)
	(segment
		(start 115.1705 76.078074)
		(end 115.1705 74.301926)
		(width 0.155)
		(layer "B.Cu")
		(net 165)
	)
	(segment
		(start 113.207662 71.769088)
		(end 113.207662 70.577662)
		(width 0.155)
		(layer "B.Cu")
		(net 165)
	)
	(segment
		(start 114.448074 76.8005)
		(end 115.1705 76.078074)
		(width 0.155)
		(layer "B.Cu")
		(net 165)
	)
	(segment
		(start 112.511926 76.4255)
		(end 112.886926 76.8005)
		(width 0.155)
		(layer "B.Cu")
		(net 165)
	)
	(segment
		(start 110.113074 76.4255)
		(end 112.511926 76.4255)
		(width 0.155)
		(layer "B.Cu")
		(net 165)
	)
	(segment
		(start 112.886926 76.8005)
		(end 114.448074 76.8005)
		(width 0.155)
		(layer "B.Cu")
		(net 165)
	)
	(segment
		(start 115.1705 74.301926)
		(end 114.7505 73.881926)
		(width 0.155)
		(layer "B.Cu")
		(net 165)
	)
	(segment
		(start 113.207662 70.577662)
		(end 113.06 70.43)
		(width 0.155)
		(layer "B.Cu")
		(net 165)
	)
	(segment
		(start 114.7505 73.311926)
		(end 113.207662 71.769088)
		(width 0.155)
		(layer "B.Cu")
		(net 165)
	)
	(segment
		(start 140.887368 89.2995)
		(end 135.412632 89.2995)
		(width 0.155)
		(layer "F.Cu")
		(net 166)
	)
	(segment
		(start 135.306566 89.343434)
		(end 135.2 89.45)
		(width 0.155)
		(layer "F.Cu")
		(net 166)
	)
	(segment
		(start 141.2 89.55)
		(end 140.993434 89.343434)
		(width 0.155)
		(layer "F.Cu")
		(net 166)
	)
	(segment
		(start 134.893434 89.343434)
		(end 135 89.45)
		(width 0.155)
		(layer "F.Cu")
		(net 166)
	)
	(segment
		(start 134.656901 89.2995)
		(end 134.787368 89.2995)
		(width 0.155)
		(layer "F.Cu")
		(net 166)
	)
	(segment
		(start 133.560011 90.251414)
		(end 134.409414 89.402012)
		(width 0.155)
		(layer "F.Cu")
		(net 166)
	)
	(segment
		(start 141.5 89.55)
		(end 141.2 89.55)
		(width 0.155)
		(layer "F.Cu")
		(net 166)
	)
	(segment
		(start 112.847323 80.205136)
		(end 112.847323 79.203455)
		(width 0.155)
		(layer "F.Cu")
		(net 166)
	)
	(segment
		(start 112.803389 79.097389)
		(end 112.756 79.05)
		(width 0.155)
		(layer "F.Cu")
		(net 166)
	)
	(segment
		(start 133.560011 90.460011)
		(end 133.560011 90.251414)
		(width 0.155)
		(layer "F.Cu")
		(net 166)
	)
	(via
		(at 112.756 79.05)
		(size 0.45)
		(drill 0.1)
		(layers "F.Cu" "B.Cu")
		(net 166)
	)
	(via
		(at 133.560011 90.460011)
		(size 0.45)
		(drill 0.1)
		(layers "F.Cu" "B.Cu")
		(net 166)
	)
	(arc
		(start 134.893434 89.343434)
		(mid 134.844771 89.310918)
		(end 134.787368 89.2995)
		(width 0.155)
		(layer "F.Cu")
		(net 166)
	)
	(arc
		(start 135.412632 89.2995)
		(mid 135.355229 89.310918)
		(end 135.306566 89.343434)
		(width 0.155)
		(layer "F.Cu")
		(net 166)
	)
	(arc
		(start 112.847323 79.203455)
		(mid 112.835905 79.146052)
		(end 112.803389 79.097389)
		(width 0.155)
		(layer "F.Cu")
		(net 166)
	)
	(arc
		(start 140.887368 89.2995)
		(mid 140.944771 89.310918)
		(end 140.993434 89.343434)
		(width 0.155)
		(layer "F.Cu")
		(net 166)
	)
	(arc
		(start 134.656901 89.2995)
		(mid 134.522962 89.326142)
		(end 134.409414 89.402012)
		(width 0.155)
		(layer "F.Cu")
		(net 166)
	)
	(segment
		(start 117.401 97.611718)
		(end 117.401 92.311718)
		(width 0.16)
		(layer "In5.Cu")
		(net 166)
	)
	(segment
		(start 133.099 90.711718)
		(end 133.099 94.611718)
		(width 0.16)
		(layer "In5.Cu")
		(net 166)
	)
	(segment
		(start 133.099 94.611718)
		(end 128.881718 98.829)
		(width 0.16)
		(layer "In5.Cu")
		(net 166)
	)
	(segment
		(start 112.901 79.195)
		(end 112.756 79.05)
		(width 0.16)
		(layer "In5.Cu")
		(net 166)
	)
	(segment
		(start 133.560011 90.460011)
		(end 133.350707 90.460011)
		(width 0.16)
		(layer "In5.Cu")
		(net 166)
	)
	(segment
		(start 128.881718 98.829)
		(end 124.331718 98.829)
		(width 0.16)
		(layer "In5.Cu")
		(net 166)
	)
	(segment
		(start 117.401 92.311718)
		(end 113.551 88.461718)
		(width 0.16)
		(layer "In5.Cu")
		(net 166)
	)
	(segment
		(start 122.761718 100.399)
		(end 120.188282 100.399)
		(width 0.16)
		(layer "In5.Cu")
		(net 166)
	)
	(segment
		(start 133.350707 90.460011)
		(end 133.099 90.711718)
		(width 0.16)
		(layer "In5.Cu")
		(net 166)
	)
	(segment
		(start 124.331718 98.829)
		(end 122.761718 100.399)
		(width 0.16)
		(layer "In5.Cu")
		(net 166)
	)
	(segment
		(start 112.901 85.761718)
		(end 112.901 79.195)
		(width 0.16)
		(layer "In5.Cu")
		(net 166)
	)
	(segment
		(start 113.551 86.411718)
		(end 112.901 85.761718)
		(width 0.16)
		(layer "In5.Cu")
		(net 166)
	)
	(segment
		(start 113.551 88.461718)
		(end 113.551 86.411718)
		(width 0.16)
		(layer "In5.Cu")
		(net 166)
	)
	(segment
		(start 120.188282 100.399)
		(end 117.401 97.611718)
		(width 0.16)
		(layer "In5.Cu")
		(net 166)
	)
	(segment
		(start 104.3995 100.061926)
		(end 103.2995 101.161926)
		(width 0.155)
		(layer "F.Cu")
		(net 167)
	)
	(segment
		(start 103.956926 106.3955)
		(end 104.319438 106.3955)
		(width 0.155)
		(layer "F.Cu")
		(net 167)
	)
	(segment
		(start 103.2995 101.161926)
		(end 103.2995 104.1005)
		(width 0.155)
		(layer "F.Cu")
		(net 167)
	)
	(segment
		(start 103.7 93.288575)
		(end 104.3995 93.988075)
		(width 0.155)
		(layer "F.Cu")
		(net 167)
	)
	(segment
		(start 103.2995 105.738074)
		(end 103.956926 106.3955)
		(width 0.155)
		(layer "F.Cu")
		(net 167)
	)
	(segment
		(start 104.3995 93.988075)
		(end 104.3995 100.061926)
		(width 0.155)
		(layer "F.Cu")
		(net 167)
	)
	(segment
		(start 112.097323 70.692635)
		(end 112.097323 72.005136)
		(width 0.155)
		(layer "F.Cu")
		(net 167)
	)
	(segment
		(start 103.2995 104.572732)
		(end 103.2995 105.738074)
		(width 0.155)
		(layer "F.Cu")
		(net 167)
	)
	(segment
		(start 111.996823 70.592135)
		(end 112.097323 70.692635)
		(width 0.155)
		(layer "F.Cu")
		(net 167)
	)
	(segment
		(start 111.996823 70.537499)
		(end 111.996823 70.592135)
		(width 0.155)
		(layer "F.Cu")
		(net 167)
	)
	(segment
		(start 112.097161 70.437161)
		(end 111.996823 70.537499)
		(width 0.155)
		(layer "F.Cu")
		(net 167)
	)
	(segment
		(start 103.7 93.06)
		(end 103.7 93.288575)
		(width 0.155)
		(layer "F.Cu")
		(net 167)
	)
	(segment
		(start 104.319438 106.3955)
		(end 104.669938 106.045)
		(width 0.155)
		(layer "F.Cu")
		(net 167)
	)
	(segment
		(start 103.491732 104.292732)
		(end 103.491732 104.3805)
		(width 0.155)
		(layer "F.Cu")
		(net 167)
	)
	(via
		(at 103.7 93.06)
		(size 0.45)
		(drill 0.1)
		(layers "F.Cu" "B.Cu")
		(net 167)
	)
	(via
		(at 112.097161 70.437161)
		(size 0.45)
		(drill 0.1)
		(layers "F.Cu" "B.Cu")
		(net 167)
	)
	(via
		(at 109.62 77.67)
		(size 0.45)
		(drill 0.1)
		(layers "F.Cu" "B.Cu")
		(net 167)
	)
	(arc
		(start 103.395616 104.196616)
		(mid 103.46358 104.224768)
		(end 103.491732 104.292732)
		(width 0.155)
		(layer "F.Cu")
		(net 167)
	)
	(arc
		(start 103.2995 104.1005)
		(mid 103.327652 104.168464)
		(end 103.395616 104.196616)
		(width 0.155)
		(layer "F.Cu")
		(net 167)
	)
	(arc
		(start 103.491732 104.3805)
		(mid 103.46358 104.448464)
		(end 103.395616 104.476616)
		(width 0.155)
		(layer "F.Cu")
		(net 167)
	)
	(arc
		(start 103.395616 104.476616)
		(mid 103.327652 104.504768)
		(end 103.2995 104.572732)
		(width 0.155)
		(layer "F.Cu")
		(net 167)
	)
	(segment
		(start 103.7 93.06)
		(end 103.470718 93.06)
		(width 0.16)
		(layer "In5.Cu")
		(net 167)
	)
	(segment
		(start 106.049 87.488282)
		(end 105.274 86.713282)
		(width 0.16)
		(layer "In5.Cu")
		(net 167)
	)
	(segment
		(start 105.274 86.713282)
		(end 105.274 81.636718)
		(width 0.16)
		(layer "In5.Cu")
		(net 167)
	)
	(segment
		(start 103.049 92.638282)
		(end 103.049 91.271718)
		(width 0.16)
		(layer "In5.Cu")
		(net 167)
	)
	(segment
		(start 106.711718 80.199)
		(end 109.411718 80.199)
		(width 0.16)
		(layer "In5.Cu")
		(net 167)
	)
	(segment
		(start 103.470718 93.06)
		(end 103.049 92.638282)
		(width 0.16)
		(layer "In5.Cu")
		(net 167)
	)
	(segment
		(start 105.274 81.636718)
		(end 106.711718 80.199)
		(width 0.16)
		(layer "In5.Cu")
		(net 167)
	)
	(segment
		(start 106.049 88.271718)
		(end 106.049 87.488282)
		(width 0.16)
		(layer "In5.Cu")
		(net 167)
	)
	(segment
		(start 103.049 91.271718)
		(end 106.049 88.271718)
		(width 0.16)
		(layer "In5.Cu")
		(net 167)
	)
	(segment
		(start 109.411718 80.199)
		(end 110.074 79.536718)
		(width 0.16)
		(layer "In5.Cu")
		(net 167)
	)
	(segment
		(start 110.074 79.536718)
		(end 110.074 78.303282)
		(width 0.16)
		(layer "In5.Cu")
		(net 167)
	)
	(segment
		(start 109.62 77.849282)
		(end 109.62 77.67)
		(width 0.16)
		(layer "In5.Cu")
		(net 167)
	)
	(segment
		(start 110.074 78.303282)
		(end 109.62 77.849282)
		(width 0.16)
		(layer "In5.Cu")
		(net 167)
	)
	(segment
		(start 105.8495 73.278797)
		(end 106.278797 72.8495)
		(width 0.155)
		(layer "B.Cu")
		(net 167)
	)
	(segment
		(start 109.62 77.67)
		(end 109.4295 77.8605)
		(width 0.155)
		(layer "B.Cu")
		(net 167)
	)
	(segment
		(start 108.431926 77.8605)
		(end 107.146926 76.5755)
		(width 0.155)
		(layer "B.Cu")
		(net 167)
	)
	(segment
		(start 111.361926 72.8495)
		(end 111.996823 72.214603)
		(width 0.155)
		(layer "B.Cu")
		(net 167)
	)
	(segment
		(start 105.8495 76.188074)
		(end 105.8495 73.278797)
		(width 0.155)
		(layer "B.Cu")
		(net 167)
	)
	(segment
		(start 106.236926 76.5755)
		(end 105.8495 76.188074)
		(width 0.155)
		(layer "B.Cu")
		(net 167)
	)
	(segment
		(start 109.4295 77.8605)
		(end 108.431926 77.8605)
		(width 0.155)
		(layer "B.Cu")
		(net 167)
	)
	(segment
		(start 111.996823 70.537499)
		(end 112.097161 70.437161)
		(width 0.155)
		(layer "B.Cu")
		(net 167)
	)
	(segment
		(start 106.278797 72.8495)
		(end 111.361926 72.8495)
		(width 0.155)
		(layer "B.Cu")
		(net 167)
	)
	(segment
		(start 111.996823 72.214603)
		(end 111.996823 70.537499)
		(width 0.155)
		(layer "B.Cu")
		(net 167)
	)
	(segment
		(start 107.146926 76.5755)
		(end 106.236926 76.5755)
		(width 0.155)
		(layer "B.Cu")
		(net 167)
	)
	(segment
		(start 65.21 80.342459)
		(end 65.347323 80.205136)
		(width 0.15)
		(layer "F.Cu")
		(net 168)
	)
	(segment
		(start 65.21 81.37)
		(end 65.21 80.342459)
		(width 0.15)
		(layer "F.Cu")
		(net 168)
	)
	(via
		(at 65.21 81.37)
		(size 0.45)
		(drill 0.1)
		(layers "F.Cu" "B.Cu")
		(net 168)
	)
	(segment
		(start 65.565 80.285)
		(end 66.05 80.285)
		(width 0.15)
		(layer "B.Cu")
		(net 168)
	)
	(segment
		(start 65.21 81.37)
		(end 65.21 80.64)
		(width 0.15)
		(layer "B.Cu")
		(net 168)
	)
	(segment
		(start 65.21 80.64)
		(end 65.565 80.285)
		(width 0.15)
		(layer "B.Cu")
		(net 168)
	)
	(segment
		(start 118.125 89.225)
		(end 118.125 87.55)
		(width 0.15)
		(layer "F.Cu")
		(net 169)
	)
	(segment
		(start 119.45 89.8)
		(end 118.7 89.8)
		(width 0.15)
		(layer "F.Cu")
		(net 169)
	)
	(segment
		(start 117.725 87.15)
		(end 117 87.15)
		(width 0.15)
		(layer "F.Cu")
		(net 169)
	)
	(segment
		(start 118.7 89.8)
		(end 118.125 89.225)
		(width 0.15)
		(layer "F.Cu")
		(net 169)
	)
	(segment
		(start 127.82 100.6)
		(end 128.47 101.25)
		(width 0.15)
		(layer "F.Cu")
		(net 169)
	)
	(segment
		(start 128.47 101.25)
		(end 129.1 101.25)
		(width 0.15)
		(layer "F.Cu")
		(net 169)
	)
	(segment
		(start 118.125 87.55)
		(end 117.725 87.15)
		(width 0.15)
		(layer "F.Cu")
		(net 169)
	)
	(via
		(at 127.82 100.6)
		(size 0.45)
		(drill 0.1)
		(layers "F.Cu" "B.Cu")
		(net 169)
	)
	(via
		(at 119.45 89.8)
		(size 0.45)
		(drill 0.1)
		(layers "F.Cu" "B.Cu")
		(net 169)
	)
	(segment
		(start 120.2 95.85)
		(end 120.21 95.85)
		(width 0.125)
		(layer "B.Cu")
		(net 169)
	)
	(segment
		(start 119.5 89.8)
		(end 120.2 90.5)
		(width 0.125)
		(layer "B.Cu")
		(net 169)
	)
	(segment
		(start 127.5 101.5)
		(end 127.82 101.18)
		(width 0.125)
		(layer "B.Cu")
		(net 169)
	)
	(segment
		(start 120.21 95.85)
		(end 120.21 96.11)
		(width 0.125)
		(layer "B.Cu")
		(net 169)
	)
	(segment
		(start 127.82 101.18)
		(end 127.82 100.6)
		(width 0.125)
		(layer "B.Cu")
		(net 169)
	)
	(segment
		(start 119.45 89.8)
		(end 119.5 89.8)
		(width 0.125)
		(layer "B.Cu")
		(net 169)
	)
	(segment
		(start 120.21 96.11)
		(end 125.6 101.5)
		(width 0.125)
		(layer "B.Cu")
		(net 169)
	)
	(segment
		(start 125.6 101.5)
		(end 127.5 101.5)
		(width 0.125)
		(layer "B.Cu")
		(net 169)
	)
	(segment
		(start 120.2 90.5)
		(end 120.2 95.85)
		(width 0.125)
		(layer "B.Cu")
		(net 169)
	)
	(segment
		(start 115.1 105.1)
		(end 113.3 105.1)
		(width 0.15)
		(layer "F.Cu")
		(net 170)
	)
	(segment
		(start 112.4 103.85)
		(end 111.6 103.05)
		(width 0.15)
		(layer "F.Cu")
		(net 170)
	)
	(segment
		(start 110.625 99.325)
		(end 110.625 88.775)
		(width 0.15)
		(layer "F.Cu")
		(net 170)
	)
	(segment
		(start 110.625 88.775)
		(end 111.75 87.65)
		(width 0.15)
		(layer "F.Cu")
		(net 170)
	)
	(segment
		(start 111.6 100.3)
		(end 110.625 99.325)
		(width 0.15)
		(layer "F.Cu")
		(net 170)
	)
	(segment
		(start 111.75 87.65)
		(end 117 87.65)
		(width 0.15)
		(layer "F.Cu")
		(net 170)
	)
	(segment
		(start 113.3 105.1)
		(end 112.4 104.2)
		(width 0.15)
		(layer "F.Cu")
		(net 170)
	)
	(segment
		(start 119.7372 109.7372)
		(end 115.1 105.1)
		(width 0.15)
		(layer "F.Cu")
		(net 170)
	)
	(segment
		(start 111.6 103.05)
		(end 111.6 100.3)
		(width 0.15)
		(layer "F.Cu")
		(net 170)
	)
	(segment
		(start 119.7372 111.8586)
		(end 119.7372 109.7372)
		(width 0.15)
		(layer "F.Cu")
		(net 170)
	)
	(segment
		(start 112.4 104.2)
		(end 112.4 103.85)
		(width 0.15)
		(layer "F.Cu")
		(net 170)
	)
	(segment
		(start 126.42 99.4)
		(end 126.57 99.55)
		(width 0.15)
		(layer "F.Cu")
		(net 171)
	)
	(segment
		(start 124.5 99.4)
		(end 126.42 99.4)
		(width 0.15)
		(layer "F.Cu")
		(net 171)
	)
	(segment
		(start 146.506566 84.956566)
		(end 146.3 84.75)
		(width 0.155)
		(layer "F.Cu")
		(net 172)
	)
	(segment
		(start 148.196434 84.756566)
		(end 148.3 84.653)
		(width 0.155)
		(layer "F.Cu")
		(net 172)
	)
	(segment
		(start 111.997491 78.273934)
		(end 111.790757 78.480668)
		(width 0.155)
		(layer "F.Cu")
		(net 172)
	)
	(segment
		(start 111.746823 79.379636)
		(end 111.847323 79.480136)
		(width 0.155)
		(layer "F.Cu")
		(net 172)
	)
	(segment
		(start 111.746823 78.586734)
		(end 111.746823 79.379636)
		(width 0.155)
		(layer "F.Cu")
		(net 172)
	)
	(segment
		(start 147.137368 84.8005)
		(end 147.012338 84.8005)
		(width 0.155)
		(layer "F.Cu")
		(net 172)
	)
	(segment
		(start 146.800206 84.888368)
		(end 146.732008 84.956566)
		(width 0.155)
		(layer "F.Cu")
		(net 172)
	)
	(segment
		(start 147.35 84.65)
		(end 147.243434 84.756566)
		(width 0.155)
		(layer "F.Cu")
		(net 172)
	)
	(segment
		(start 148.037633 84.8005)
		(end 148.090368 84.8005)
		(width 0.155)
		(layer "F.Cu")
		(net 172)
	)
	(segment
		(start 147.868935 84.693934)
		(end 147.931567 84.756566)
		(width 0.155)
		(layer "F.Cu")
		(net 172)
	)
	(segment
		(start 146.625942 85.0005)
		(end 146.612632 85.0005)
		(width 0.155)
		(layer "F.Cu")
		(net 172)
	)
	(segment
		(start 147.45 84.65)
		(end 147.762869 84.65)
		(width 0.155)
		(layer "F.Cu")
		(net 172)
	)
	(segment
		(start 112.21 78.23)
		(end 112.103557 78.23)
		(width 0.155)
		(layer "F.Cu")
		(net 172)
	)
	(via
		(at 148.3 84.653)
		(size 0.45)
		(drill 0.1)
		(layers "F.Cu" "B.Cu")
		(net 172)
	)
	(via
		(at 112.21 78.23)
		(size 0.45)
		(drill 0.1)
		(layers "F.Cu" "B.Cu")
		(net 172)
	)
	(arc
		(start 148.037633 84.8005)
		(mid 147.98023 84.789082)
		(end 147.931567 84.756566)
		(width 0.155)
		(layer "F.Cu")
		(net 172)
	)
	(arc
		(start 146.506566 84.956566)
		(mid 146.555229 84.989082)
		(end 146.612632 85.0005)
		(width 0.155)
		(layer "F.Cu")
		(net 172)
	)
	(arc
		(start 111.790757 78.480668)
		(mid 111.758241 78.529331)
		(end 111.746823 78.586734)
		(width 0.155)
		(layer "F.Cu")
		(net 172)
	)
	(arc
		(start 111.997491 78.273934)
		(mid 112.046154 78.241418)
		(end 112.103557 78.23)
		(width 0.155)
		(layer "F.Cu")
		(net 172)
	)
	(arc
		(start 147.137368 84.8005)
		(mid 147.194771 84.789082)
		(end 147.243434 84.756566)
		(width 0.155)
		(layer "F.Cu")
		(net 172)
	)
	(arc
		(start 147.012338 84.8005)
		(mid 146.897533 84.823336)
		(end 146.800206 84.888368)
		(width 0.155)
		(layer "F.Cu")
		(net 172)
	)
	(arc
		(start 146.732008 84.956566)
		(mid 146.683345 84.989082)
		(end 146.625942 85.0005)
		(width 0.155)
		(layer "F.Cu")
		(net 172)
	)
	(arc
		(start 148.196434 84.756566)
		(mid 148.147771 84.789082)
		(end 148.090368 84.8005)
		(width 0.155)
		(layer "F.Cu")
		(net 172)
	)
	(arc
		(start 147.868935 84.693934)
		(mid 147.820272 84.661418)
		(end 147.762869 84.65)
		(width 0.155)
		(layer "F.Cu")
		(net 172)
	)
	(segment
		(start 146.613282 84.801)
		(end 145.931 85.483282)
		(width 0.16)
		(layer "In5.Cu")
		(net 172)
	)
	(segment
		(start 131.201 98.538282)
		(end 131.201 99.438282)
		(width 0.16)
		(layer "In5.Cu")
		(net 172)
	)
	(segment
		(start 131.201 99.438282)
		(end 130.828282 99.811)
		(width 0.16)
		(layer "In5.Cu")
		(net 172)
	)
	(segment
		(start 139.088282 97.751)
		(end 136.211718 97.751)
		(width 0.16)
		(layer "In5.Cu")
		(net 172)
	)
	(segment
		(start 124.728282 99.811)
		(end 123.138282 101.401)
		(width 0.16)
		(layer "In5.Cu")
		(net 172)
	)
	(segment
		(start 123.138282 101.401)
		(end 119.811718 101.401)
		(width 0.16)
		(layer "In5.Cu")
		(net 172)
	)
	(segment
		(start 119.811718 101.401)
		(end 116.399 97.988282)
		(width 0.16)
		(layer "In5.Cu")
		(net 172)
	)
	(segment
		(start 145.931 93.928282)
		(end 143.718282 96.141)
		(width 0.16)
		(layer "In5.Cu")
		(net 172)
	)
	(segment
		(start 133.691 96.951)
		(end 132.788282 96.951)
		(width 0.16)
		(layer "In5.Cu")
		(net 172)
	)
	(segment
		(start 148.152 84.801)
		(end 146.613282 84.801)
		(width 0.16)
		(layer "In5.Cu")
		(net 172)
	)
	(segment
		(start 134.491 96.701)
		(end 134.491 96.521028)
		(width 0.16)
		(layer "In5.Cu")
		(net 172)
	)
	(segment
		(start 112.299 88.738282)
		(end 112.299 86.688282)
		(width 0.16)
		(layer "In5.Cu")
		(net 172)
	)
	(segment
		(start 111.910718 78.23)
		(end 112.21 78.23)
		(width 0.16)
		(layer "In5.Cu")
		(net 172)
	)
	(segment
		(start 111.609 78.531718)
		(end 111.910718 78.23)
		(width 0.16)
		(layer "In5.Cu")
		(net 172)
	)
	(segment
		(start 145.931 85.483282)
		(end 145.931 93.928282)
		(width 0.16)
		(layer "In5.Cu")
		(net 172)
	)
	(segment
		(start 132.788282 96.951)
		(end 131.201 98.538282)
		(width 0.16)
		(layer "In5.Cu")
		(net 172)
	)
	(segment
		(start 140.698282 96.141)
		(end 139.088282 97.751)
		(width 0.16)
		(layer "In5.Cu")
		(net 172)
	)
	(segment
		(start 136.211718 97.751)
		(end 135.411718 96.951)
		(width 0.16)
		(layer "In5.Cu")
		(net 172)
	)
	(segment
		(start 116.399 92.838282)
		(end 112.299 88.738282)
		(width 0.16)
		(layer "In5.Cu")
		(net 172)
	)
	(segment
		(start 133.741 96.951)
		(end 133.691 96.951)
		(width 0.16)
		(layer "In5.Cu")
		(net 172)
	)
	(segment
		(start 116.399 97.988282)
		(end 116.399 92.838282)
		(width 0.16)
		(layer "In5.Cu")
		(net 172)
	)
	(segment
		(start 143.718282 96.141)
		(end 140.698282 96.141)
		(width 0.16)
		(layer "In5.Cu")
		(net 172)
	)
	(segment
		(start 112.299 86.688282)
		(end 111.609 85.998282)
		(width 0.16)
		(layer "In5.Cu")
		(net 172)
	)
	(segment
		(start 135.411718 96.951)
		(end 134.741 96.951)
		(width 0.16)
		(layer "In5.Cu")
		(net 172)
	)
	(segment
		(start 130.828282 99.811)
		(end 124.728282 99.811)
		(width 0.16)
		(layer "In5.Cu")
		(net 172)
	)
	(segment
		(start 111.609 85.998282)
		(end 111.609 78.531718)
		(width 0.16)
		(layer "In5.Cu")
		(net 172)
	)
	(segment
		(start 133.991 96.521028)
		(end 133.991 96.701)
		(width 0.16)
		(layer "In5.Cu")
		(net 172)
	)
	(segment
		(start 148.3 84.653)
		(end 148.152 84.801)
		(width 0.16)
		(layer "In5.Cu")
		(net 172)
	)
	(arc
		(start 133.991 96.701)
		(mid 133.917777 96.877777)
		(end 133.741 96.951)
		(width 0.16)
		(layer "In5.Cu")
		(net 172)
	)
	(arc
		(start 134.741 96.951)
		(mid 134.564223 96.877777)
		(end 134.491 96.701)
		(width 0.16)
		(layer "In5.Cu")
		(net 172)
	)
	(arc
		(start 134.491 96.521028)
		(mid 134.417777 96.344251)
		(end 134.241 96.271028)
		(width 0.16)
		(layer "In5.Cu")
		(net 172)
	)
	(arc
		(start 134.241 96.271028)
		(mid 134.064223 96.344251)
		(end 133.991 96.521028)
		(width 0.16)
		(layer "In5.Cu")
		(net 172)
	)
	(segment
		(start 104.319438 106.6945)
		(end 104.669938 107.045)
		(width 0.155)
		(layer "F.Cu")
		(net 173)
	)
	(segment
		(start 103.833074 106.6945)
		(end 104.319438 106.6945)
		(width 0.155)
		(layer "F.Cu")
		(net 173)
	)
	(segment
		(start 104.1005 99.938074)
		(end 103.0005 101.038074)
		(width 0.155)
		(layer "F.Cu")
		(net 173)
	)
	(segment
		(start 103.0005 105.861926)
		(end 103.833074 106.6945)
		(width 0.155)
		(layer "F.Cu")
		(net 173)
	)
	(segment
		(start 111.51 70.605312)
		(end 111.597323 70.692635)
		(width 0.155)
		(layer "F.Cu")
		(net 173)
	)
	(segment
		(start 111.597323 70.692635)
		(end 111.597323 72.005136)
		(width 0.155)
		(layer "F.Cu")
		(net 173)
	)
	(segment
		(start 104.1005 94.111925)
		(end 104.1005 99.938074)
		(width 0.155)
		(layer "F.Cu")
		(net 173)
	)
	(segment
		(start 103.282666 93.467334)
		(end 103.455909 93.467334)
		(width 0.155)
		(layer "F.Cu")
		(net 173)
	)
	(segment
		(start 111.51 70.46)
		(end 111.51 70.605312)
		(width 0.155)
		(layer "F.Cu")
		(net 173)
	)
	(segment
		(start 103.455909 93.467334)
		(end 104.1005 94.111925)
		(width 0.155)
		(layer "F.Cu")
		(net 173)
	)
	(segment
		(start 103.0005 101.038074)
		(end 103.0005 105.861926)
		(width 0.155)
		(layer "F.Cu")
		(net 173)
	)
	(via
		(at 111.51 70.46)
		(size 0.45)
		(drill 0.1)
		(layers "F.Cu" "B.Cu")
		(net 173)
	)
	(via
		(at 109.47 78.32)
		(size 0.45)
		(drill 0.1)
		(layers "F.Cu" "B.Cu")
		(net 173)
	)
	(via
		(at 103.282666 93.467334)
		(size 0.45)
		(drill 0.1)
		(layers "F.Cu" "B.Cu")
		(net 173)
	)
	(segment
		(start 102.751 91.148282)
		(end 105.751 88.148282)
		(width 0.16)
		(layer "In5.Cu")
		(net 173)
	)
	(segment
		(start 106.588282 79.901)
		(end 109.288282 79.901)
		(width 0.16)
		(layer "In5.Cu")
		(net 173)
	)
	(segment
		(start 109.776 78.426718)
		(end 109.669282 78.32)
		(width 0.16)
		(layer "In5.Cu")
		(net 173)
	)
	(segment
		(start 109.776 79.413282)
		(end 109.776 78.426718)
		(width 0.16)
		(layer "In5.Cu")
		(net 173)
	)
	(segment
		(start 104.976 81.513282)
		(end 106.588282 79.901)
		(width 0.16)
		(layer "In5.Cu")
		(net 173)
	)
	(segment
		(start 105.751 87.611718)
		(end 104.976 86.836718)
		(width 0.16)
		(layer "In5.Cu")
		(net 173)
	)
	(segment
		(start 109.288282 79.901)
		(end 109.776 79.413282)
		(width 0.16)
		(layer "In5.Cu")
		(net 173)
	)
	(segment
		(start 102.751 92.761718)
		(end 102.751 91.148282)
		(width 0.16)
		(layer "In5.Cu")
		(net 173)
	)
	(segment
		(start 105.751 88.148282)
		(end 105.751 87.611718)
		(width 0.16)
		(layer "In5.Cu")
		(net 173)
	)
	(segment
		(start 109.669282 78.32)
		(end 109.47 78.32)
		(width 0.16)
		(layer "In5.Cu")
		(net 173)
	)
	(segment
		(start 103.282666 93.467334)
		(end 103.282666 93.293384)
		(width 0.16)
		(layer "In5.Cu")
		(net 173)
	)
	(segment
		(start 103.282666 93.293384)
		(end 102.751 92.761718)
		(width 0.16)
		(layer "In5.Cu")
		(net 173)
	)
	(segment
		(start 104.976 86.836718)
		(end 104.976 81.513282)
		(width 0.16)
		(layer "In5.Cu")
		(net 173)
	)
	(segment
		(start 111.697823 70.647823)
		(end 111.51 70.46)
		(width 0.155)
		(layer "B.Cu")
		(net 173)
	)
	(segment
		(start 105.5505 76.311926)
		(end 105.5505 73.154945)
		(width 0.155)
		(layer "B.Cu")
		(net 173)
	)
	(segment
		(start 109.47 78.32)
		(end 109.3095 78.1595)
		(width 0.155)
		(layer "B.Cu")
		(net 173)
	)
	(segment
		(start 107.023074 76.8745)
		(end 106.113074 76.8745)
		(width 0.155)
		(layer "B.Cu")
		(net 173)
	)
	(segment
		(start 106.154945 72.5505)
		(end 111.238074 72.5505)
		(width 0.155)
		(layer "B.Cu")
		(net 173)
	)
	(segment
		(start 105.5505 73.154945)
		(end 106.154945 72.5505)
		(width 0.155)
		(layer "B.Cu")
		(net 173)
	)
	(segment
		(start 111.238074 72.5505)
		(end 111.697823 72.090751)
		(width 0.155)
		(layer "B.Cu")
		(net 173)
	)
	(segment
		(start 106.113074 76.8745)
		(end 105.5505 76.311926)
		(width 0.155)
		(layer "B.Cu")
		(net 173)
	)
	(segment
		(start 111.697823 72.090751)
		(end 111.697823 70.647823)
		(width 0.155)
		(layer "B.Cu")
		(net 173)
	)
	(segment
		(start 109.3095 78.1595)
		(end 108.308074 78.1595)
		(width 0.155)
		(layer "B.Cu")
		(net 173)
	)
	(segment
		(start 108.308074 78.1595)
		(end 107.023074 76.8745)
		(width 0.155)
		(layer "B.Cu")
		(net 173)
	)
	(segment
		(start 58.249 77.35)
		(end 58.65 77.35)
		(width 0.15)
		(layer "B.Cu")
		(net 174)
	)
	(segment
		(start 56.785 76.2)
		(end 56.785 77.2)
		(width 0.15)
		(layer "B.Cu")
		(net 174)
	)
	(segment
		(start 56.785 77.2)
		(end 57.65 77.2)
		(width 0.15)
		(layer "B.Cu")
		(net 174)
	)
	(segment
		(start 58.249 77.35)
		(end 57.8 77.35)
		(width 0.15)
		(layer "B.Cu")
		(net 174)
	)
	(segment
		(start 58.65 77.35)
		(end 60.347 75.653)
		(width 0.15)
		(layer "B.Cu")
		(net 174)
	)
	(segment
		(start 57.8 77.35)
		(end 57.65 77.2)
		(width 0.15)
		(layer "B.Cu")
		(net 174)
	)
	(segment
		(start 60.347 75.653)
		(end 60.95 75.653)
		(width 0.15)
		(layer "B.Cu")
		(net 174)
	)
	(segment
		(start 147.137368 85.0995)
		(end 147.011926 85.0995)
		(width 0.155)
		(layer "F.Cu")
		(net 175)
	)
	(segment
		(start 148.037633 85.0995)
		(end 148.090368 85.0995)
		(width 0.155)
		(layer "F.Cu")
		(net 175)
	)
	(segment
		(start 111.736066 78.112509)
		(end 111.535691 78.312884)
		(width 0.155)
		(layer "F.Cu")
		(net 175)
	)
	(segment
		(start 147.45 85.25)
		(end 147.762869 85.25)
		(width 0.155)
		(layer "F.Cu")
		(net 175)
	)
	(segment
		(start 147.868935 85.206066)
		(end 147.931567 85.143434)
		(width 0.155)
		(layer "F.Cu")
		(net 175)
	)
	(segment
		(start 147.35 85.25)
		(end 147.243434 85.143434)
		(width 0.155)
		(layer "F.Cu")
		(net 175)
	)
	(segment
		(start 111.447823 78.525016)
		(end 111.447823 79.379636)
		(width 0.155)
		(layer "F.Cu")
		(net 175)
	)
	(segment
		(start 111.78 77.82)
		(end 111.78 78.006443)
		(width 0.155)
		(layer "F.Cu")
		(net 175)
	)
	(segment
		(start 146.506566 85.343434)
		(end 146.3 85.55)
		(width 0.155)
		(layer "F.Cu")
		(net 175)
	)
	(segment
		(start 111.447823 79.379636)
		(end 111.347323 79.480136)
		(width 0.155)
		(layer "F.Cu")
		(net 175)
	)
	(segment
		(start 146.687662 85.2995)
		(end 146.612632 85.2995)
		(width 0.155)
		(layer "F.Cu")
		(net 175)
	)
	(segment
		(start 147.011926 85.0995)
		(end 146.899794 85.211632)
		(width 0.155)
		(layer "F.Cu")
		(net 175)
	)
	(segment
		(start 148.196434 85.143434)
		(end 148.3 85.247)
		(width 0.155)
		(layer "F.Cu")
		(net 175)
	)
	(via
		(at 111.78 77.82)
		(size 0.45)
		(drill 0.1)
		(layers "F.Cu" "B.Cu")
		(net 175)
	)
	(via
		(at 148.3 85.247)
		(size 0.45)
		(drill 0.1)
		(layers "F.Cu" "B.Cu")
		(net 175)
	)
	(arc
		(start 146.687662 85.2995)
		(mid 146.802467 85.276664)
		(end 146.899794 85.211632)
		(width 0.155)
		(layer "F.Cu")
		(net 175)
	)
	(arc
		(start 147.137368 85.0995)
		(mid 147.194771 85.110918)
		(end 147.243434 85.143434)
		(width 0.155)
		(layer "F.Cu")
		(net 175)
	)
	(arc
		(start 147.762869 85.25)
		(mid 147.820272 85.238582)
		(end 147.868935 85.206066)
		(width 0.155)
		(layer "F.Cu")
		(net 175)
	)
	(arc
		(start 148.090368 85.0995)
		(mid 148.147771 85.110918)
		(end 148.196434 85.143434)
		(width 0.155)
		(layer "F.Cu")
		(net 175)
	)
	(arc
		(start 146.506566 85.343434)
		(mid 146.555229 85.310918)
		(end 146.612632 85.2995)
		(width 0.155)
		(layer "F.Cu")
		(net 175)
	)
	(arc
		(start 111.736066 78.112509)
		(mid 111.768582 78.063846)
		(end 111.78 78.006443)
		(width 0.155)
		(layer "F.Cu")
		(net 175)
	)
	(arc
		(start 111.535691 78.312884)
		(mid 111.470659 78.410211)
		(end 111.447823 78.525016)
		(width 0.155)
		(layer "F.Cu")
		(net 175)
	)
	(arc
		(start 148.037633 85.0995)
		(mid 147.98023 85.110918)
		(end 147.931567 85.143434)
		(width 0.155)
		(layer "F.Cu")
		(net 175)
	)
	(segment
		(start 140.821718 96.439)
		(end 139.211718 98.049)
		(width 0.16)
		(layer "In5.Cu")
		(net 175)
	)
	(segment
		(start 146.229 85.606718)
		(end 146.229 94.051718)
		(width 0.16)
		(layer "In5.Cu")
		(net 175)
	)
	(segment
		(start 116.101 92.961718)
		(end 112.001 88.861718)
		(width 0.16)
		(layer "In5.Cu")
		(net 175)
	)
	(segment
		(start 124.851718 100.109)
		(end 123.261718 101.699)
		(width 0.16)
		(layer "In5.Cu")
		(net 175)
	)
	(segment
		(start 123.261718 101.699)
		(end 119.688282 101.699)
		(width 0.16)
		(layer "In5.Cu")
		(net 175)
	)
	(segment
		(start 111.311 78.408282)
		(end 111.78 77.939282)
		(width 0.16)
		(layer "In5.Cu")
		(net 175)
	)
	(segment
		(start 131.499 98.661718)
		(end 131.499 99.561718)
		(width 0.16)
		(layer "In5.Cu")
		(net 175)
	)
	(segment
		(start 132.911718 97.249)
		(end 131.499 98.661718)
		(width 0.16)
		(layer "In5.Cu")
		(net 175)
	)
	(segment
		(start 139.211718 98.049)
		(end 136.088282 98.049)
		(width 0.16)
		(layer "In5.Cu")
		(net 175)
	)
	(segment
		(start 135.288282 97.249)
		(end 132.911718 97.249)
		(width 0.16)
		(layer "In5.Cu")
		(net 175)
	)
	(segment
		(start 136.088282 98.049)
		(end 135.288282 97.249)
		(width 0.16)
		(layer "In5.Cu")
		(net 175)
	)
	(segment
		(start 119.688282 101.699)
		(end 116.101 98.111718)
		(width 0.16)
		(layer "In5.Cu")
		(net 175)
	)
	(segment
		(start 143.841718 96.439)
		(end 140.821718 96.439)
		(width 0.16)
		(layer "In5.Cu")
		(net 175)
	)
	(segment
		(start 146.736718 85.099)
		(end 146.229 85.606718)
		(width 0.16)
		(layer "In5.Cu")
		(net 175)
	)
	(segment
		(start 116.101 98.111718)
		(end 116.101 92.961718)
		(width 0.16)
		(layer "In5.Cu")
		(net 175)
	)
	(segment
		(start 131.499 99.561718)
		(end 130.951718 100.109)
		(width 0.16)
		(layer "In5.Cu")
		(net 175)
	)
	(segment
		(start 146.229 94.051718)
		(end 143.841718 96.439)
		(width 0.16)
		(layer "In5.Cu")
		(net 175)
	)
	(segment
		(start 112.001 86.811718)
		(end 111.311 86.121718)
		(width 0.16)
		(layer "In5.Cu")
		(net 175)
	)
	(segment
		(start 112.001 88.861718)
		(end 112.001 86.811718)
		(width 0.16)
		(layer "In5.Cu")
		(net 175)
	)
	(segment
		(start 148.3 85.247)
		(end 148.152 85.099)
		(width 0.16)
		(layer "In5.Cu")
		(net 175)
	)
	(segment
		(start 130.951718 100.109)
		(end 124.851718 100.109)
		(width 0.16)
		(layer "In5.Cu")
		(net 175)
	)
	(segment
		(start 148.152 85.099)
		(end 146.736718 85.099)
		(width 0.16)
		(layer "In5.Cu")
		(net 175)
	)
	(segment
		(start 111.78 77.939282)
		(end 111.78 77.82)
		(width 0.16)
		(layer "In5.Cu")
		(net 175)
	)
	(segment
		(start 111.311 86.121718)
		(end 111.311 78.408282)
		(width 0.16)
		(layer "In5.Cu")
		(net 175)
	)
	(segment
		(start 120.1436 109.6436)
		(end 120.1436 111.8586)
		(width 0.15)
		(layer "F.Cu")
		(net 176)
	)
	(segment
		(start 111.875 100.175)
		(end 111.875 102.875)
		(width 0.15)
		(layer "F.Cu")
		(net 176)
	)
	(segment
		(start 111.875 102.875)
		(end 112.675 103.675)
		(width 0.15)
		(layer "F.Cu")
		(net 176)
	)
	(segment
		(start 112.675 103.675)
		(end 112.675 104.075)
		(width 0.15)
		(layer "F.Cu")
		(net 176)
	)
	(segment
		(start 117 88.15)
		(end 112.05 88.15)
		(width 0.15)
		(layer "F.Cu")
		(net 176)
	)
	(segment
		(start 110.925 99.225)
		(end 111.875 100.175)
		(width 0.15)
		(layer "F.Cu")
		(net 176)
	)
	(segment
		(start 110.925 89.275)
		(end 110.925 99.225)
		(width 0.15)
		(layer "F.Cu")
		(net 176)
	)
	(segment
		(start 115.3 104.8)
		(end 120.1436 109.6436)
		(width 0.15)
		(layer "F.Cu")
		(net 176)
	)
	(segment
		(start 113.4 104.8)
		(end 115.3 104.8)
		(width 0.15)
		(layer "F.Cu")
		(net 176)
	)
	(segment
		(start 112.05 88.15)
		(end 110.925 89.275)
		(width 0.15)
		(layer "F.Cu")
		(net 176)
	)
	(segment
		(start 112.675 104.075)
		(end 113.4 104.8)
		(width 0.15)
		(layer "F.Cu")
		(net 176)
	)
	(segment
		(start 79.66 89.04)
		(end 80.23 89.61)
		(width 0.15)
		(layer "F.Cu")
		(net 177)
	)
	(segment
		(start 79.09 89.04)
		(end 79.66 89.04)
		(width 0.15)
		(layer "F.Cu")
		(net 177)
	)
	(segment
		(start 81.23 89.61)
		(end 80.23 89.61)
		(width 0.15)
		(layer "F.Cu")
		(net 177)
	)
	(segment
		(start 115.8 104.2)
		(end 120.9564 109.3564)
		(width 0.15)
		(layer "F.Cu")
		(net 178)
	)
	(segment
		(start 113.3 103.9)
		(end 113.6 104.2)
		(width 0.15)
		(layer "F.Cu")
		(net 178)
	)
	(segment
		(start 117 89.15)
		(end 115.85 89.15)
		(width 0.15)
		(layer "F.Cu")
		(net 178)
	)
	(segment
		(start 115.7 89)
		(end 112.7 89)
		(width 0.15)
		(layer "F.Cu")
		(net 178)
	)
	(segment
		(start 113.6 104.2)
		(end 115.8 104.2)
		(width 0.15)
		(layer "F.Cu")
		(net 178)
	)
	(segment
		(start 112.425 99.925)
		(end 112.425 102.525)
		(width 0.15)
		(layer "F.Cu")
		(net 178)
	)
	(segment
		(start 112.7 89)
		(end 111.53 90.17)
		(width 0.15)
		(layer "F.Cu")
		(net 178)
	)
	(segment
		(start 113.3 103.4)
		(end 113.3 103.9)
		(width 0.15)
		(layer "F.Cu")
		(net 178)
	)
	(segment
		(start 112.425 102.525)
		(end 113.3 103.4)
		(width 0.15)
		(layer "F.Cu")
		(net 178)
	)
	(segment
		(start 111.53 99.03)
		(end 112.425 99.925)
		(width 0.15)
		(layer "F.Cu")
		(net 178)
	)
	(segment
		(start 115.85 89.15)
		(end 115.7 89)
		(width 0.15)
		(layer "F.Cu")
		(net 178)
	)
	(segment
		(start 111.53 90.17)
		(end 111.53 99.03)
		(width 0.15)
		(layer "F.Cu")
		(net 178)
	)
	(segment
		(start 120.9564 109.3564)
		(end 120.9564 111.8586)
		(width 0.15)
		(layer "F.Cu")
		(net 178)
	)
	(segment
		(start 83.26 127.14)
		(end 85.512 127.14)
		(width 0.125)
		(layer "F.Cu")
		(net 179)
	)
	(segment
		(start 85.951 126.701)
		(end 87.3 126.701)
		(width 0.125)
		(layer "F.Cu")
		(net 179)
	)
	(segment
		(start 85.512 127.14)
		(end 85.951 126.701)
		(width 0.125)
		(layer "F.Cu")
		(net 179)
	)
	(segment
		(start 82.29 127.14)
		(end 83.26 127.14)
		(width 0.125)
		(layer "F.Cu")
		(net 179)
	)
	(segment
		(start 83.25 126.7)
		(end 83.25 127.13)
		(width 0.125)
		(layer "F.Cu")
		(net 179)
	)
	(segment
		(start 83.25 127.13)
		(end 83.26 127.14)
		(width 0.125)
		(layer "F.Cu")
		(net 179)
	)
	(segment
		(start 81.85 126.7)
		(end 82.29 127.14)
		(width 0.125)
		(layer "F.Cu")
		(net 179)
	)
	(via
		(at 83.25 126.7)
		(size 0.45)
		(drill 0.1)
		(layers "F.Cu" "B.Cu")
		(net 179)
	)
	(via
		(at 54.9 76)
		(size 0.45)
		(drill 0.1)
		(layers "F.Cu" "B.Cu")
		(net 179)
	)
	(segment
		(start 66.8 123.3)
		(end 65.15 121.65)
		(width 0.125)
		(layer "In3.Cu")
		(net 179)
	)
	(segment
		(start 54.75 79.95)
		(end 54.75 76.15)
		(width 0.125)
		(layer "In3.Cu")
		(net 179)
	)
	(segment
		(start 62.046829 113.920437)
		(end 61.651963 113.841893)
		(width 0.125)
		(layer "In3.Cu")
		(net 179)
	)
	(segment
		(start 51.99 97.28)
		(end 51.99 82.71)
		(width 0.125)
		(layer "In3.Cu")
		(net 179)
	)
	(segment
		(start 63.493862 114.604833)
		(end 63.159112 114.38116)
		(width 0.125)
		(layer "In3.Cu")
		(net 179)
	)
	(segment
		(start 65.15 121.65)
		(end 65.15 117.9)
		(width 0.125)
		(layer "In3.Cu")
		(net 179)
	)
	(segment
		(start 51.99 82.71)
		(end 54.75 79.95)
		(width 0.125)
		(layer "In3.Cu")
		(net 179)
	)
	(segment
		(start 64.912694 116.517906)
		(end 64.758625 116.145951)
		(width 0.125)
		(layer "In3.Cu")
		(net 179)
	)
	(segment
		(start 65.029563 116.903171)
		(end 64.912694 116.517906)
		(width 0.125)
		(layer "In3.Cu")
		(net 179)
	)
	(segment
		(start 64.345167 115.456138)
		(end 64.089759 115.144923)
		(width 0.125)
		(layer "In3.Cu")
		(net 179)
	)
	(segment
		(start 64.56884 115.790888)
		(end 64.345167 115.456138)
		(width 0.125)
		(layer "In3.Cu")
		(net 179)
	)
	(segment
		(start 62.804049 114.191375)
		(end 62.432094 114.037306)
		(width 0.125)
		(layer "In3.Cu")
		(net 179)
	)
	(segment
		(start 53.25 113.8)
		(end 52.52 113.07)
		(width 0.125)
		(layer "In3.Cu")
		(net 179)
	)
	(segment
		(start 54.75 76.15)
		(end 54.9 76)
		(width 0.125)
		(layer "In3.Cu")
		(net 179)
	)
	(segment
		(start 83.25 126.7)
		(end 83 126.7)
		(width 0.125)
		(layer "In3.Cu")
		(net 179)
	)
	(segment
		(start 65.147568 117.698699)
		(end 65.108107 117.298037)
		(width 0.125)
		(layer "In3.Cu")
		(net 179)
	)
	(segment
		(start 80.5 123.3)
		(end 66.8 123.3)
		(width 0.125)
		(layer "In3.Cu")
		(net 179)
	)
	(segment
		(start 61.651963 113.841893)
		(end 61.251301 113.802432)
		(width 0.125)
		(layer "In3.Cu")
		(net 179)
	)
	(segment
		(start 63.805077 114.860241)
		(end 63.493862 114.604833)
		(width 0.125)
		(layer "In3.Cu")
		(net 179)
	)
	(segment
		(start 64.089759 115.144923)
		(end 63.805077 114.860241)
		(width 0.125)
		(layer "In3.Cu")
		(net 179)
	)
	(segment
		(start 63.159112 114.38116)
		(end 62.804049 114.191375)
		(width 0.125)
		(layer "In3.Cu")
		(net 179)
	)
	(segment
		(start 65.108107 117.298037)
		(end 65.029563 116.903171)
		(width 0.125)
		(layer "In3.Cu")
		(net 179)
	)
	(segment
		(start 52.52 97.81)
		(end 51.99 97.28)
		(width 0.125)
		(layer "In3.Cu")
		(net 179)
	)
	(segment
		(start 61.251301 113.802432)
		(end 61.05 113.8)
		(width 0.125)
		(layer "In3.Cu")
		(net 179)
	)
	(segment
		(start 83 126.7)
		(end 81 124.7)
		(width 0.125)
		(layer "In3.Cu")
		(net 179)
	)
	(segment
		(start 61.05 113.8)
		(end 53.25 113.8)
		(width 0.125)
		(layer "In3.Cu")
		(net 179)
	)
	(segment
		(start 65.15 117.9)
		(end 65.147568 117.698699)
		(width 0.125)
		(layer "In3.Cu")
		(net 179)
	)
	(segment
		(start 52.52 113.07)
		(end 52.52 97.81)
		(width 0.125)
		(layer "In3.Cu")
		(net 179)
	)
	(segment
		(start 64.758625 116.145951)
		(end 64.56884 115.790888)
		(width 0.125)
		(layer "In3.Cu")
		(net 179)
	)
	(segment
		(start 62.432094 114.037306)
		(end 62.046829 113.920437)
		(width 0.125)
		(layer "In3.Cu")
		(net 179)
	)
	(segment
		(start 81 123.8)
		(end 80.5 123.3)
		(width 0.125)
		(layer "In3.Cu")
		(net 179)
	)
	(segment
		(start 81 124.7)
		(end 81 123.8)
		(width 0.125)
		(layer "In3.Cu")
		(net 179)
	)
	(segment
		(start 70.9 72.4)
		(end 70.9 70.55)
		(width 0.15)
		(layer "B.Cu")
		(net 179)
	)
	(segment
		(start 71.125 72.625)
		(end 70.9 72.4)
		(width 0.15)
		(layer "B.Cu")
		(net 179)
	)
	(segment
		(start 72.3 75.215)
		(end 71.301 75.215)
		(width 0.15)
		(layer "B.Cu")
		(net 179)
	)
	(segment
		(start 57.25 70.65)
		(end 60.955 70.65)
		(width 0.15)
		(layer "B.Cu")
		(net 179)
	)
	(segment
		(start 65.067677 71.072323)
		(end 70.377677 71.072323)
		(width 0.15)
		(layer "B.Cu")
		(net 179)
	)
	(segment
		(start 71.3 75.216)
		(end 71.125 75.041)
		(width 0.15)
		(layer "B.Cu")
		(net 179)
	)
	(segment
		(start 71.125 75.041)
		(end 71.125 72.625)
		(width 0.15)
		(layer "B.Cu")
		(net 179)
	)
	(segment
		(start 63.615 72.525)
		(end 65.067677 71.072323)
		(width 0.15)
		(layer "B.Cu")
		(net 179)
	)
	(segment
		(start 70.377677 71.072323)
		(end 70.9 70.55)
		(width 0.15)
		(layer "B.Cu")
		(net 179)
	)
	(segment
		(start 60.955 70.65)
		(end 62.83 72.525)
		(width 0.15)
		(layer "B.Cu")
		(net 179)
	)
	(segment
		(start 62.83 72.525)
		(end 63.615 72.525)
		(width 0.15)
		(layer "B.Cu")
		(net 179)
	)
	(segment
		(start 71.301 75.215)
		(end 71.3 75.216)
		(width 0.15)
		(layer "B.Cu")
		(net 179)
	)
	(segment
		(start 54.9 76)
		(end 55.44 75.46)
		(width 0.15)
		(layer "B.Cu")
		(net 179)
	)
	(segment
		(start 55.44 72.46)
		(end 57.25 70.65)
		(width 0.15)
		(layer "B.Cu")
		(net 179)
	)
	(segment
		(start 55.44 75.46)
		(end 55.44 72.46)
		(width 0.15)
		(layer "B.Cu")
		(net 179)
	)
	(segment
		(start 133.925 127.125)
		(end 134.7 127.9)
		(width 0.2)
		(layer "F.Cu")
		(net 180)
	)
	(segment
		(start 133.925 122.36)
		(end 133.925 127.125)
		(width 0.2)
		(layer "F.Cu")
		(net 180)
	)
	(segment
		(start 134.7 121.585)
		(end 133.925 122.36)
		(width 0.2)
		(layer "F.Cu")
		(net 180)
	)
	(segment
		(start 132.69 121.99)
		(end 132.95 122.25)
		(width 0.2)
		(layer "F.Cu")
		(net 181)
	)
	(segment
		(start 132.95 126.35)
		(end 132.8 126.5)
		(width 0.2)
		(layer "F.Cu")
		(net 181)
	)
	(segment
		(start 132.1 121.99)
		(end 132.69 121.99)
		(width 0.2)
		(layer "F.Cu")
		(net 181)
	)
	(segment
		(start 132.95 122.25)
		(end 132.95 126.35)
		(width 0.2)
		(layer "F.Cu")
		(net 181)
	)
	(segment
		(start 133.7 122.1)
		(end 133.6 122.2)
		(width 0.2)
		(layer "F.Cu")
		(net 182)
	)
	(segment
		(start 133.7 121.585)
		(end 133.7 122.1)
		(width 0.2)
		(layer "F.Cu")
		(net 182)
	)
	(segment
		(start 133.6 122.2)
		(end 133.6 127.1)
		(width 0.2)
		(layer "F.Cu")
		(net 182)
	)
	(segment
		(start 133.6 127.1)
		(end 132.8 127.9)
		(width 0.2)
		(layer "F.Cu")
		(net 182)
	)
	(segment
		(start 113.66 91.4)
		(end 113.29 91.77)
		(width 0.15)
		(layer "F.Cu")
		(net 183)
	)
	(segment
		(start 117 90.65)
		(end 115.95 90.65)
		(width 0.15)
		(layer "F.Cu")
		(net 183)
	)
	(segment
		(start 122.015 104.365)
		(end 122.015 106.97)
		(width 0.125)
		(layer "F.Cu")
		(net 183)
	)
	(segment
		(start 113.29 91.77)
		(end 113.09 91.97)
		(width 0.15)
		(layer "F.Cu")
		(net 183)
	)
	(segment
		(start 112.8 98.76)
		(end 112.98 98.94)
		(width 0.15)
		(layer "F.Cu")
		(net 183)
	)
	(segment
		(start 112.31 91.97)
		(end 112.035 92.245)
		(width 0.15)
		(layer "F.Cu")
		(net 183)
	)
	(segment
		(start 114.1 91.4)
		(end 113.66 91.4)
		(width 0.15)
		(layer "F.Cu")
		(net 183)
	)
	(segment
		(start 111.945 92.335)
		(end 111.945 93.18)
		(width 0.15)
		(layer "F.Cu")
		(net 183)
	)
	(segment
		(start 111.945 97.905)
		(end 112.8 98.76)
		(width 0.15)
		(layer "F.Cu")
		(net 183)
	)
	(segment
		(start 114.1 91.4)
		(end 114.6 91.4)
		(width 0.15)
		(layer "F.Cu")
		(net 183)
	)
	(segment
		(start 115.7 90.4)
		(end 115.035 90.4)
		(width 0.15)
		(layer "F.Cu")
		(net 183)
	)
	(segment
		(start 112.53 91.97)
		(end 112.31 91.97)
		(width 0.15)
		(layer "F.Cu")
		(net 183)
	)
	(segment
		(start 114.6 91.4)
		(end 115.035 90.965)
		(width 0.15)
		(layer "F.Cu")
		(net 183)
	)
	(segment
		(start 113.09 91.97)
		(end 112.53 91.97)
		(width 0.15)
		(layer "F.Cu")
		(net 183)
	)
	(segment
		(start 122.015 106.97)
		(end 123.265 108.22)
		(width 0.125)
		(layer "F.Cu")
		(net 183)
	)
	(segment
		(start 115.035 90.965)
		(end 115.035 90.4)
		(width 0.15)
		(layer "F.Cu")
		(net 183)
	)
	(segment
		(start 112.035 92.245)
		(end 111.945 92.335)
		(width 0.15)
		(layer "F.Cu")
		(net 183)
	)
	(segment
		(start 111.945 93.18)
		(end 111.945 97.905)
		(width 0.15)
		(layer "F.Cu")
		(net 183)
	)
	(segment
		(start 122.525 103.855)
		(end 122.015 104.365)
		(width 0.125)
		(layer "F.Cu")
		(net 183)
	)
	(segment
		(start 115.95 90.65)
		(end 115.7 90.4)
		(width 0.15)
		(layer "F.Cu")
		(net 183)
	)
	(segment
		(start 112.98 98.94)
		(end 113.885 98.94)
		(width 0.15)
		(layer "F.Cu")
		(net 183)
	)
	(segment
		(start 123.265 108.22)
		(end 123.915 108.22)
		(width 0.125)
		(layer "F.Cu")
		(net 183)
	)
	(segment
		(start 123.915 108.22)
		(end 127.905 112.21)
		(width 0.125)
		(layer "F.Cu")
		(net 183)
	)
	(via
		(at 122.525 103.855)
		(size 0.45)
		(drill 0.1)
		(layers "F.Cu" "B.Cu")
		(net 183)
	)
	(via
		(at 113.885 98.94)
		(size 0.45)
		(drill 0.1)
		(layers "F.Cu" "B.Cu")
		(net 183)
	)
	(segment
		(start 121.575 100.955)
		(end 122.095 101.475)
		(width 0.15)
		(layer "B.Cu")
		(net 183)
	)
	(segment
		(start 122.095 101.475)
		(end 122.095 103.215)
		(width 0.15)
		(layer "B.Cu")
		(net 183)
	)
	(segment
		(start 114.74 99.795)
		(end 117.645 99.795)
		(width 0.15)
		(layer "B.Cu")
		(net 183)
	)
	(segment
		(start 117.645 99.795)
		(end 118.46 99.795)
		(width 0.15)
		(layer "B.Cu")
		(net 183)
	)
	(segment
		(start 118.46 99.795)
		(end 118.58 99.915)
		(width 0.15)
		(layer "B.Cu")
		(net 183)
	)
	(segment
		(start 120.6 99.98)
		(end 121.575 100.955)
		(width 0.15)
		(layer "B.Cu")
		(net 183)
	)
	(segment
		(start 122.095 103.425)
		(end 122.525 103.855)
		(width 0.15)
		(layer "B.Cu")
		(net 183)
	)
	(segment
		(start 118.58 99.915)
		(end 118.645 99.98)
		(width 0.15)
		(layer "B.Cu")
		(net 183)
	)
	(segment
		(start 113.885 98.94)
		(end 114.74 99.795)
		(width 0.15)
		(layer "B.Cu")
		(net 183)
	)
	(segment
		(start 119.845 99.98)
		(end 120.6 99.98)
		(width 0.15)
		(layer "B.Cu")
		(net 183)
	)
	(segment
		(start 118.645 99.98)
		(end 119.845 99.98)
		(width 0.15)
		(layer "B.Cu")
		(net 183)
	)
	(segment
		(start 122.095 103.215)
		(end 122.095 103.425)
		(width 0.15)
		(layer "B.Cu")
		(net 183)
	)
	(segment
		(start 129.1 105.615)
		(end 129.1 102.65)
		(width 0.15)
		(layer "F.Cu")
		(net 184)
	)
	(segment
		(start 127.9 107.415)
		(end 127.9 106.815)
		(width 0.15)
		(layer "F.Cu")
		(net 184)
	)
	(segment
		(start 127.9 106.815)
		(end 129.1 105.615)
		(width 0.15)
		(layer "F.Cu")
		(net 184)
	)
	(segment
		(start 49.88 111.32)
		(end 50.18 111.02)
		(width 0.15)
		(layer "F.Cu")
		(net 185)
	)
	(segment
		(start 49.698897 112.524001)
		(end 50.085333 112.910437)
		(width 0.2)
		(layer "F.Cu")
		(net 185)
	)
	(segment
		(start 50.085333 112.910437)
		(end 50.085333 112.9241)
		(width 0.2)
		(layer "F.Cu")
		(net 185)
	)
	(segment
		(start 56.25 112.475)
		(end 50.534433 112.475)
		(width 0.2)
		(layer "F.Cu")
		(net 185)
	)
	(segment
		(start 50.534433 112.475)
		(end 50.085333 112.9241)
		(width 0.2)
		(layer "F.Cu")
		(net 185)
	)
	(segment
		(start 48.7 117.15)
		(end 48.7 112.9)
		(width 0.2)
		(layer "F.Cu")
		(net 185)
	)
	(segment
		(start 48.7 112.9)
		(end 49.075999 112.524001)
		(width 0.2)
		(layer "F.Cu")
		(net 185)
	)
	(segment
		(start 48.85 117.65)
		(end 48.85 117.3)
		(width 0.2)
		(layer "F.Cu")
		(net 185)
	)
	(segment
		(start 49.075999 112.524001)
		(end 49.698897 112.524001)
		(width 0.2)
		(layer "F.Cu")
		(net 185)
	)
	(segment
		(start 48.85 117.3)
		(end 48.7 117.15)
		(width 0.2)
		(layer "F.Cu")
		(net 185)
	)
	(segment
		(start 48.28 111.32)
		(end 49.88 111.32)
		(width 0.15)
		(layer "F.Cu")
		(net 185)
	)
	(segment
		(start 50.18 111.02)
		(end 50.18 110.325)
		(width 0.15)
		(layer "F.Cu")
		(net 185)
	)
	(via
		(at 48.85 117.65)
		(size 0.45)
		(drill 0.1)
		(layers "F.Cu" "B.Cu")
		(net 185)
	)
	(via
		(at 50.085333 112.9241)
		(size 0.45)
		(drill 0.1)
		(layers "F.Cu" "B.Cu")
		(net 185)
	)
	(via
		(at 56.25 112.475)
		(size 0.45)
		(drill 0.1)
		(layers "F.Cu" "B.Cu")
		(net 185)
	)
	(via
		(at 50.18 110.325)
		(size 0.45)
		(drill 0.1)
		(layers "F.Cu" "B.Cu")
		(net 185)
	)
	(via
		(at 48.28 111.32)
		(size 0.45)
		(drill 0.1)
		(layers "F.Cu" "B.Cu")
		(net 185)
	)
	(segment
		(start 50.03 110.475)
		(end 50.18 110.325)
		(width 0.15)
		(layer "B.Cu")
		(net 185)
	)
	(segment
		(start 43.2 123.56)
		(end 43.77 122.99)
		(width 0.15)
		(layer "B.Cu")
		(net 185)
	)
	(segment
		(start 51.05 115.35)
		(end 51.7 115.35)
		(width 0.15)
		(layer "B.Cu")
		(net 185)
	)
	(segment
		(start 50.03 110.8745)
		(end 50.03 111.101536)
		(width 0.15)
		(layer "B.Cu")
		(net 185)
	)
	(segment
		(start 50.23 113.75)
		(end 50.23 113.068767)
		(width 0.15)
		(layer "B.Cu")
		(net 185)
	)
	(segment
		(start 47.07 118.703603)
		(end 47.07 121.64)
		(width 0.2)
		(layer "B.Cu")
		(net 185)
	)
	(segment
		(start 48.85 117.65)
		(end 48.85 117.6)
		(width 0.2)
		(layer "B.Cu")
		(net 185)
	)
	(segment
		(start 50.45 116)
		(end 49.5 116.95)
		(width 0.15)
		(layer "B.Cu")
		(net 185)
	)
	(segment
		(start 48.410999 112.549001)
		(end 48.28 112.68)
		(width 0.15)
		(layer "B.Cu")
		(net 185)
	)
	(segment
		(start 52.07 110.15)
		(end 52.029383 110.109383)
		(width 0.15)
		(layer "B.Cu")
		(net 185)
	)
	(segment
		(start 47.6 110.77)
		(end 48.15 111.32)
		(width 0.15)
		(layer "B.Cu")
		(net 185)
	)
	(segment
		(start 56.965 111.752703)
		(end 56.965 111.45)
		(width 0.13)
		(layer "B.Cu")
		(net 185)
	)
	(segment
		(start 49.53 112.529001)
		(end 49.55 112.549001)
		(width 0.15)
		(layer "B.Cu")
		(net 185)
	)
	(segment
		(start 49.55 112.549001)
		(end 48.410999 112.549001)
		(width 0.15)
		(layer "B.Cu")
		(net 185)
	)
	(segment
		(start 51.7 115.35)
		(end 51.9 115.15)
		(width 0.15)
		(layer "B.Cu")
		(net 185)
	)
	(segment
		(start 47.07 121.64)
		(end 47.07 122.36)
		(width 0.15)
		(layer "B.Cu")
		(net 185)
	)
	(segment
		(start 50.990617 110.109383)
		(end 50.775 110.325)
		(width 0.15)
		(layer "B.Cu")
		(net 185)
	)
	(segment
		(start 50.455 115.945)
		(end 51.05 115.35)
		(width 0.15)
		(layer "B.Cu")
		(net 185)
	)
	(segment
		(start 56.25 112.467703)
		(end 56.965 111.752703)
		(width 0.13)
		(layer "B.Cu")
		(net 185)
	)
	(segment
		(start 49.710234 112.549001)
		(end 50.085333 112.9241)
		(width 0.15)
		(layer "B.Cu")
		(net 185)
	)
	(segment
		(start 56.25 112.475)
		(end 56.25 112.467703)
		(width 0.13)
		(layer "B.Cu")
		(net 185)
	)
	(segment
		(start 49.53 111.7745)
		(end 49.53 112.529001)
		(width 0.15)
		(layer "B.Cu")
		(net 185)
	)
	(segment
		(start 46.523 122.97)
		(end 46.233 122.68)
		(width 0.15)
		(layer "B.Cu")
		(net 185)
	)
	(segment
		(start 50.23 113.068767)
		(end 50.085333 112.9241)
		(width 0.15)
		(layer "B.Cu")
		(net 185)
	)
	(segment
		(start 44.08 122.68)
		(end 43.77 122.99)
		(width 0.15)
		(layer "B.Cu")
		(net 185)
	)
	(segment
		(start 50.03 110.8745)
		(end 50.03 110.475)
		(width 0.15)
		(layer "B.Cu")
		(net 185)
	)
	(segment
		(start 43.77 124.87)
		(end 43.2 124.3)
		(width 0.15)
		(layer "B.Cu")
		(net 185)
	)
	(segment
		(start 47.891603 117.882)
		(end 47.07 118.703603)
		(width 0.2)
		(layer "B.Cu")
		(net 185)
	)
	(segment
		(start 48.85 117.6)
		(end 49.5 116.95)
		(width 0.2)
		(layer "B.Cu")
		(net 185)
	)
	(segment
		(start 48.618 117.882)
		(end 47.891603 117.882)
		(width 0.2)
		(layer "B.Cu")
		(net 185)
	)
	(segment
		(start 55.4 112.475)
		(end 55.2 112.275)
		(width 0.13)
		(layer "B.Cu")
		(net 185)
	)
	(segment
		(start 49.53 111.601536)
		(end 49.53 111.7745)
		(width 0.15)
		(layer "B.Cu")
		(net 185)
	)
	(segment
		(start 48.15 111.32)
		(end 48.28 111.32)
		(width 0.15)
		(layer "B.Cu")
		(net 185)
	)
	(segment
		(start 56.25 112.475)
		(end 55.4 112.475)
		(width 0.13)
		(layer "B.Cu")
		(net 185)
	)
	(segment
		(start 50.775 110.325)
		(end 50.18 110.325)
		(width 0.15)
		(layer "B.Cu")
		(net 185)
	)
	(segment
		(start 47.07 122.36)
		(end 46.523 122.907)
		(width 0.15)
		(layer "B.Cu")
		(net 185)
	)
	(segment
		(start 48.85 117.65)
		(end 48.618 117.882)
		(width 0.2)
		(layer "B.Cu")
		(net 185)
	)
	(segment
		(start 51.5 113.575)
		(end 50.405 113.575)
		(width 0.15)
		(layer "B.Cu")
		(net 185)
	)
	(segment
		(start 43.2 124.3)
		(end 43.2 123.56)
		(width 0.15)
		(layer "B.Cu")
		(net 185)
	)
	(segment
		(start 49.710234 112.549001)
		(end 49.55 112.549001)
		(width 0.15)
		(layer "B.Cu")
		(net 185)
	)
	(segment
		(start 50.03 111.101536)
		(end 49.53 111.601536)
		(width 0.15)
		(layer "B.Cu")
		(net 185)
	)
	(segment
		(start 51.9 115.15)
		(end 52.425 115.15)
		(width 0.15)
		(layer "B.Cu")
		(net 185)
	)
	(segment
		(start 46.233 122.68)
		(end 44.08 122.68)
		(width 0.15)
		(layer "B.Cu")
		(net 185)
	)
	(segment
		(start 50.405 113.575)
		(end 50.23 113.75)
		(width 0.15)
		(layer "B.Cu")
		(net 185)
	)
	(segment
		(start 50.455 116)
		(end 50.455 115.945)
		(width 0.15)
		(layer "B.Cu")
		(net 185)
	)
	(segment
		(start 52.029383 110.109383)
		(end 50.990617 110.109383)
		(width 0.15)
		(layer "B.Cu")
		(net 185)
	)
	(segment
		(start 50.455 116)
		(end 50.45 116)
		(width 0.15)
		(layer "B.Cu")
		(net 185)
	)
	(segment
		(start 47.54 110.77)
		(end 47.6 110.77)
		(width 0.15)
		(layer "B.Cu")
		(net 185)
	)
	(segment
		(start 46.523 122.907)
		(end 46.523 122.97)
		(width 0.15)
		(layer "B.Cu")
		(net 185)
	)
	(segment
		(start 77.7005 107.016969)
		(end 78.405543 107.016969)
		(width 0.155)
		(layer "F.Cu")
		(net 186)
	)
	(segment
		(start 79.038074 107.6495)
		(end 81.0645 107.6495)
		(width 0.155)
		(layer "F.Cu")
		(net 186)
	)
	(segment
		(start 77.65 107.067469)
		(end 77.7005 107.016969)
		(width 0.155)
		(layer "F.Cu")
		(net 186)
	)
	(segment
		(start 78.405543 107.016969)
		(end 79.038074 107.6495)
		(width 0.155)
		(layer "F.Cu")
		(net 186)
	)
	(segment
		(start 81.0645 107.6495)
		(end 81.415 108)
		(width 0.155)
		(layer "F.Cu")
		(net 186)
	)
	(segment
		(start 79.061926 105.2495)
		(end 81.0645 105.2495)
		(width 0.155)
		(layer "F.Cu")
		(net 187)
	)
	(segment
		(start 77.7005 105.816969)
		(end 78.494457 105.816969)
		(width 0.155)
		(layer "F.Cu")
		(net 187)
	)
	(segment
		(start 77.65 105.867469)
		(end 77.7005 105.816969)
		(width 0.155)
		(layer "F.Cu")
		(net 187)
	)
	(segment
		(start 78.494457 105.816969)
		(end 79.061926 105.2495)
		(width 0.155)
		(layer "F.Cu")
		(net 187)
	)
	(segment
		(start 81.0645 105.2495)
		(end 81.415 105.6)
		(width 0.155)
		(layer "F.Cu")
		(net 187)
	)
	(segment
		(start 114.85 93.65)
		(end 117 93.65)
		(width 0.15)
		(layer "F.Cu")
		(net 188)
	)
	(segment
		(start 58.3 109.95)
		(end 59.05 109.95)
		(width 0.15)
		(layer "F.Cu")
		(net 189)
	)
	(segment
		(start 58 113.45)
		(end 57.8 113.25)
		(width 0.15)
		(layer "F.Cu")
		(net 189)
	)
	(segment
		(start 57.8 110.45)
		(end 58.3 109.95)
		(width 0.15)
		(layer "F.Cu")
		(net 189)
	)
	(segment
		(start 57.8 113.25)
		(end 57.8 110.45)
		(width 0.15)
		(layer "F.Cu")
		(net 189)
	)
	(segment
		(start 114.65 92)
		(end 113.7 92)
		(width 0.15)
		(layer "F.Cu")
		(net 192)
	)
	(segment
		(start 112.974229 94.574229)
		(end 113.55 95.15)
		(width 0.15)
		(layer "F.Cu")
		(net 192)
	)
	(segment
		(start 114.55 95.15)
		(end 114.85 94.85)
		(width 0.15)
		(layer "F.Cu")
		(net 192)
	)
	(segment
		(start 117 91.15)
		(end 115.5 91.15)
		(width 0.15)
		(layer "F.Cu")
		(net 192)
	)
	(segment
		(start 113.7 92)
		(end 112.974229 92.725771)
		(width 0.15)
		(layer "F.Cu")
		(net 192)
	)
	(segment
		(start 112.974229 92.725771)
		(end 112.974229 94.574229)
		(width 0.15)
		(layer "F.Cu")
		(net 192)
	)
	(segment
		(start 113.55 95.15)
		(end 114.55 95.15)
		(width 0.15)
		(layer "F.Cu")
		(net 192)
	)
	(segment
		(start 115.5 91.15)
		(end 114.65 92)
		(width 0.15)
		(layer "F.Cu")
		(net 192)
	)
	(segment
		(start 77.65 106.667469)
		(end 77.7005 106.717969)
		(width 0.155)
		(layer "F.Cu")
		(net 193)
	)
	(segment
		(start 79.161926 107.3505)
		(end 81.0645 107.3505)
		(width 0.155)
		(layer "F.Cu")
		(net 193)
	)
	(segment
		(start 77.7005 106.717969)
		(end 78.529395 106.717969)
		(width 0.155)
		(layer "F.Cu")
		(net 193)
	)
	(segment
		(start 81.0645 107.3505)
		(end 81.415 107)
		(width 0.155)
		(layer "F.Cu")
		(net 193)
	)
	(segment
		(start 78.529395 106.717969)
		(end 79.161926 107.3505)
		(width 0.155)
		(layer "F.Cu")
		(net 193)
	)
	(segment
		(start 77.65 105.467469)
		(end 77.7005 105.517969)
		(width 0.155)
		(layer "F.Cu")
		(net 194)
	)
	(segment
		(start 78.370605 105.517969)
		(end 78.938074 104.9505)
		(width 0.155)
		(layer "F.Cu")
		(net 194)
	)
	(segment
		(start 81.0645 104.9505)
		(end 81.415 104.6)
		(width 0.155)
		(layer "F.Cu")
		(net 194)
	)
	(segment
		(start 77.7005 105.517969)
		(end 78.370605 105.517969)
		(width 0.155)
		(layer "F.Cu")
		(net 194)
	)
	(segment
		(start 78.938074 104.9505)
		(end 81.0645 104.9505)
		(width 0.155)
		(layer "F.Cu")
		(net 194)
	)
	(segment
		(start 115.65 94.65)
		(end 117 94.65)
		(width 0.15)
		(layer "F.Cu")
		(net 195)
	)
	(segment
		(start 114.85 94.45)
		(end 115.45 94.45)
		(width 0.15)
		(layer "F.Cu")
		(net 195)
	)
	(segment
		(start 115.45 94.45)
		(end 115.65 94.65)
		(width 0.15)
		(layer "F.Cu")
		(net 195)
	)
	(via
		(at 60.35 112.75)
		(size 0.45)
		(drill 0.1)
		(layers "F.Cu" "B.Cu")
		(free yes)
		(net 196)
	)
	(via
		(at 59.85 113.3)
		(size 0.45)
		(drill 0.1)
		(layers "F.Cu" "B.Cu")
		(free yes)
		(net 196)
	)
	(via
		(at 59.85 112.75)
		(size 0.45)
		(drill 0.1)
		(layers "F.Cu" "B.Cu")
		(free yes)
		(net 196)
	)
	(via
		(at 59.85 112.2)
		(size 0.45)
		(drill 0.1)
		(layers "F.Cu" "B.Cu")
		(free yes)
		(net 196)
	)
	(via
		(at 60.35 112.2)
		(size 0.45)
		(drill 0.1)
		(layers "F.Cu" "B.Cu")
		(free yes)
		(net 196)
	)
	(via
		(at 60.35 113.3)
		(size 0.45)
		(drill 0.1)
		(layers "F.Cu" "B.Cu")
		(free yes)
		(net 196)
	)
	(segment
		(start 47.465 125.445)
		(end 47.99 124.92)
		(width 0.155)
		(layer "B.Cu")
		(net 196)
	)
	(segment
		(start 45.175 124.945)
		(end 45.2 124.92)
		(width 0.155)
		(layer "B.Cu")
		(net 196)
	)
	(segment
		(start 46.725 125.445)
		(end 47.465 125.445)
		(width 0.155)
		(layer "B.Cu")
		(net 196)
	)
	(segment
		(start 68.165 117.07)
		(end 65.32 117.07)
		(width 0.15)
		(layer "B.Cu")
		(net 196)
	)
	(segment
		(start 46.525 124.92)
		(end 46.525 125.245)
		(width 0.155)
		(layer "B.Cu")
		(net 196)
	)
	(segment
		(start 60.35 114.325)
		(end 60.35 113.3)
		(width 0.15)
		(layer "B.Cu")
		(net 196)
	)
	(segment
		(start 46.525 125.245)
		(end 46.725 125.445)
		(width 0.155)
		(layer "B.Cu")
		(net 196)
	)
	(segment
		(start 65.32 117.07)
		(end 62.77 114.52)
		(width 0.15)
		(layer "B.Cu")
		(net 196)
	)
	(segment
		(start 60 123.8)
		(end 56.3 123.8)
		(width 0.2)
		(layer "B.Cu")
		(net 196)
	)
	(segment
		(start 50.575 124.575)
		(end 51.25 123.9)
		(width 0.155)
		(layer "B.Cu")
		(net 196)
	)
	(segment
		(start 60.545 114.52)
		(end 60.35 114.325)
		(width 0.15)
		(layer "B.Cu")
		(net 196)
	)
	(segment
		(start 60.55 124.35)
		(end 60 123.8)
		(width 0.2)
		(layer "B.Cu")
		(net 196)
	)
	(segment
		(start 48.5 124.575)
		(end 48.157 124.918)
		(width 0.155)
		(layer "B.Cu")
		(net 196)
	)
	(segment
		(start 48.5 124.575)
		(end 50.575 124.575)
		(width 0.155)
		(layer "B.Cu")
		(net 196)
	)
	(segment
		(start 45.2 124.92)
		(end 46.525 124.92)
		(width 0.155)
		(layer "B.Cu")
		(net 196)
	)
	(segment
		(start 48.157 124.918)
		(end 47.825 124.918)
		(width 0.155)
		(layer "B.Cu")
		(net 196)
	)
	(segment
		(start 62.77 114.52)
		(end 60.545 114.52)
		(width 0.15)
		(layer "B.Cu")
		(net 196)
	)
	(segment
		(start 74.2495 110.131969)
		(end 74.6 110.482469)
		(width 0.155)
		(layer "F.Cu")
		(net 197)
	)
	(segment
		(start 74.4995 109.611926)
		(end 74.2495 109.861926)
		(width 0.155)
		(layer "F.Cu")
		(net 197)
	)
	(segment
		(start 74.55 108.767469)
		(end 74.4995 108.817969)
		(width 0.155)
		(layer "F.Cu")
		(net 197)
	)
	(segment
		(start 74.4995 108.817969)
		(end 74.4995 109.611926)
		(width 0.155)
		(layer "F.Cu")
		(net 197)
	)
	(segment
		(start 74.2495 109.861926)
		(end 74.2495 110.131969)
		(width 0.155)
		(layer "F.Cu")
		(net 197)
	)
	(segment
		(start 74.2495 111.802969)
		(end 74.6 111.452469)
		(width 0.155)
		(layer "F.Cu")
		(net 198)
	)
	(segment
		(start 73 115.115)
		(end 73 114.702499)
		(width 0.155)
		(layer "F.Cu")
		(net 198)
	)
	(segment
		(start 72.89492 117.167365)
		(end 72.89492 117.56)
		(width 0.165)
		(layer "F.Cu")
		(net 198)
	)
	(segment
		(start 72.89492 117.56)
		(end 72.99992 117.665)
		(width 0.165)
		(layer "F.Cu")
		(net 198)
	)
	(segment
		(start 74.2495 112.436926)
		(end 74.2495 111.802969)
		(width 0.155)
		(layer "F.Cu")
		(net 198)
	)
	(segment
		(start 73 115.885)
		(end 73 116.297501)
		(width 0.165)
		(layer "F.Cu")
		(net 198)
	)
	(segment
		(start 73 115.115)
		(end 73 115.885)
		(width 0.165)
		(layer "F.Cu")
		(net 198)
	)
	(segment
		(start 72.895 116.402501)
		(end 72.895 117.167285)
		(width 0.165)
		(layer "F.Cu")
		(net 198)
	)
	(segment
		(start 72.895 117.167285)
		(end 72.89492 117.167365)
		(width 0.165)
		(layer "F.Cu")
		(net 198)
	)
	(segment
		(start 73 114.702499)
		(end 72.8995 114.601999)
		(width 0.155)
		(layer "F.Cu")
		(net 198)
	)
	(segment
		(start 72.8995 114.601999)
		(end 72.8995 113.786926)
		(width 0.155)
		(layer "F.Cu")
		(net 198)
	)
	(segment
		(start 73 116.297501)
		(end 72.895 116.402501)
		(width 0.165)
		(layer "F.Cu")
		(net 198)
	)
	(segment
		(start 72.8995 113.786926)
		(end 74.2495 112.436926)
		(width 0.155)
		(layer "F.Cu")
		(net 198)
	)
	(segment
		(start 115.65 94.15)
		(end 117 94.15)
		(width 0.15)
		(layer "F.Cu")
		(net 199)
	)
	(segment
		(start 114.85 94.05)
		(end 115.55 94.05)
		(width 0.15)
		(layer "F.Cu")
		(net 199)
	)
	(segment
		(start 115.55 94.05)
		(end 115.65 94.15)
		(width 0.15)
		(layer "F.Cu")
		(net 199)
	)
	(segment
		(start 75.4005 109.511926)
		(end 75.9505 110.061926)
		(width 0.155)
		(layer "F.Cu")
		(net 200)
	)
	(segment
		(start 75.35 108.767469)
		(end 75.4005 108.817969)
		(width 0.155)
		(layer "F.Cu")
		(net 200)
	)
	(segment
		(start 75.9505 110.131969)
		(end 75.6 110.482469)
		(width 0.155)
		(layer "F.Cu")
		(net 200)
	)
	(segment
		(start 75.9505 110.061926)
		(end 75.9505 110.131969)
		(width 0.155)
		(layer "F.Cu")
		(net 200)
	)
	(segment
		(start 75.4005 108.817969)
		(end 75.4005 109.511926)
		(width 0.155)
		(layer "F.Cu")
		(net 200)
	)
	(segment
		(start 78.038074 112.6245)
		(end 78.6005 113.186926)
		(width 0.155)
		(layer "F.Cu")
		(net 201)
	)
	(segment
		(start 78.5 115.885)
		(end 78.5 116.297501)
		(width 0.155)
		(layer "F.Cu")
		(net 201)
	)
	(segment
		(start 77.8305 119.908074)
		(end 77.8305 120.438074)
		(width 0.155)
		(layer "F.Cu")
		(net 201)
	)
	(segment
		(start 78.6005 113.186926)
		(end 78.6005 114.601999)
		(width 0.155)
		(layer "F.Cu")
		(net 201)
	)
	(segment
		(start 76.338074 112.6245)
		(end 78.038074 112.6245)
		(width 0.155)
		(layer "F.Cu")
		(net 201)
	)
	(segment
		(start 78.5 115.115)
		(end 78.5 115.885)
		(width 0.165)
		(layer "F.Cu")
		(net 201)
	)
	(segment
		(start 75.6 111.452469)
		(end 75.9505 111.802969)
		(width 0.155)
		(layer "F.Cu")
		(net 201)
	)
	(segment
		(start 77.2305 121.038074)
		(end 77.2305 121.3925)
		(width 0.155)
		(layer "F.Cu")
		(net 201)
	)
	(segment
		(start 75.9505 111.802969)
		(end 75.9505 112.236926)
		(width 0.155)
		(layer "F.Cu")
		(net 201)
	)
	(segment
		(start 78.5 114.702499)
		(end 78.5 115.115)
		(width 0.155)
		(layer "F.Cu")
		(net 201)
	)
	(segment
		(start 78.6005 114.601999)
		(end 78.5 114.702499)
		(width 0.155)
		(layer "F.Cu")
		(net 201)
	)
	(segment
		(start 77.8305 120.438074)
		(end 77.2305 121.038074)
		(width 0.155)
		(layer "F.Cu")
		(net 201)
	)
	(segment
		(start 78.5 116.297501)
		(end 78.6005 116.398001)
		(width 0.155)
		(layer "F.Cu")
		(net 201)
	)
	(segment
		(start 75.9505 112.236926)
		(end 76.338074 112.6245)
		(width 0.155)
		(layer "F.Cu")
		(net 201)
	)
	(segment
		(start 78.6005 119.138074)
		(end 77.8305 119.908074)
		(width 0.155)
		(layer "F.Cu")
		(net 201)
	)
	(segment
		(start 78.6005 116.398001)
		(end 78.6005 119.138074)
		(width 0.155)
		(layer "F.Cu")
		(net 201)
	)
	(segment
		(start 77.2305 121.3925)
		(end 77.083 121.54)
		(width 0.155)
		(layer "F.Cu")
		(net 201)
	)
	(via
		(at 77.083 121.54)
		(size 0.45)
		(drill 0.1)
		(layers "F.Cu" "B.Cu")
		(net 201)
	)
	(segment
		(start 76.34992 120.065)
		(end 76.60042 120.3155)
		(width 0.155)
		(layer "B.Cu")
		(net 201)
	)
	(segment
		(start 76.60042 120.601846)
		(end 77.2305 121.231926)
		(width 0.155)
		(layer "B.Cu")
		(net 201)
	)
	(segment
		(start 77.2305 121.3925)
		(end 77.083 121.54)
		(width 0.155)
		(layer "B.Cu")
		(net 201)
	)
	(segment
		(start 77.2305 121.231926)
		(end 77.2305 121.3925)
		(width 0.155)
		(layer "B.Cu")
		(net 201)
	)
	(segment
		(start 76.60042 120.3155)
		(end 76.60042 120.601846)
		(width 0.155)
		(layer "B.Cu")
		(net 201)
	)
	(segment
		(start 134.7905 76.7105)
		(end 136.271926 76.7105)
		(width 0.155)
		(layer "B.Cu")
		(net 204)
	)
	(segment
		(start 133.516 76.485)
		(end 133.516 75.938168)
		(width 0.155)
		(layer "B.Cu")
		(net 204)
	)
	(segment
		(start 134.565 75.938168)
		(end 134.565 76.485)
		(width 0.155)
		(layer "B.Cu")
		(net 204)
	)
	(segment
		(start 142.161926 82.6005)
		(end 143.0495 82.6005)
		(width 0.155)
		(layer "B.Cu")
		(net 204)
	)
	(segment
		(start 143.0495 82.6005)
		(end 143.15 82.5)
		(width 0.155)
		(layer "B.Cu")
		(net 204)
	)
	(segment
		(start 124.038851 73.7504)
		(end 124.092551 73.8041)
		(width 0.155)
		(layer "B.Cu")
		(net 204)
	)
	(segment
		(start 123.6007 73.7504)
		(end 124.038851 73.7504)
		(width 0.155)
		(layer "B.Cu")
		(net 204)
	)
	(segment
		(start 126.344474 73.8041)
		(end 126.618074 73.5305)
		(width 0.155)
		(layer "B.Cu")
		(net 204)
	)
	(segment
		(start 128.581926 73.5305)
		(end 131.761926 76.7105)
		(width 0.155)
		(layer "B.Cu")
		(net 204)
	)
	(segment
		(start 136.271926 76.7105)
		(end 142.161926 82.6005)
		(width 0.155)
		(layer "B.Cu")
		(net 204)
	)
	(segment
		(start 124.092551 73.8041)
		(end 126.344474 73.8041)
		(width 0.155)
		(layer "B.Cu")
		(net 204)
	)
	(segment
		(start 131.761926 76.7105)
		(end 133.2905 76.7105)
		(width 0.155)
		(layer "B.Cu")
		(net 204)
	)
	(segment
		(start 126.618074 73.5305)
		(end 128.581926 73.5305)
		(width 0.155)
		(layer "B.Cu")
		(net 204)
	)
	(arc
		(start 134.565 76.485)
		(mid 134.631047 76.644453)
		(end 134.7905 76.7105)
		(width 0.155)
		(layer "B.Cu")
		(net 204)
	)
	(arc
		(start 133.2905 76.7105)
		(mid 133.449953 76.644453)
		(end 133.516 76.485)
		(width 0.155)
		(layer "B.Cu")
		(net 204)
	)
	(arc
		(start 134.0405 75.413668)
		(mid 134.411378 75.56729)
		(end 134.565 75.938168)
		(width 0.155)
		(layer "B.Cu")
		(net 204)
	)
	(arc
		(start 133.516 75.938168)
		(mid 133.669622 75.56729)
		(end 134.0405 75.413668)
		(width 0.155)
		(layer "B.Cu")
		(net 204)
	)
	(segment
		(start 126.741926 73.8295)
		(end 128.458074 73.8295)
		(width 0.155)
		(layer "B.Cu")
		(net 205)
	)
	(segment
		(start 134.7905 77.0095)
		(end 136.148074 77.0095)
		(width 0.155)
		(layer "B.Cu")
		(net 205)
	)
	(segment
		(start 123.6007 74.1568)
		(end 124.038851 74.1568)
		(width 0.155)
		(layer "B.Cu")
		(net 205)
	)
	(segment
		(start 133.815 76.485)
		(end 133.815 75.938168)
		(width 0.155)
		(layer "B.Cu")
		(net 205)
	)
	(segment
		(start 143.0495 82.8995)
		(end 143.15 83)
		(width 0.155)
		(layer "B.Cu")
		(net 205)
	)
	(segment
		(start 124.038851 74.1568)
		(end 124.092551 74.1031)
		(width 0.155)
		(layer "B.Cu")
		(net 205)
	)
	(segment
		(start 126.468326 74.1031)
		(end 126.741926 73.8295)
		(width 0.155)
		(layer "B.Cu")
		(net 205)
	)
	(segment
		(start 142.038074 82.8995)
		(end 143.0495 82.8995)
		(width 0.155)
		(layer "B.Cu")
		(net 205)
	)
	(segment
		(start 128.458074 73.8295)
		(end 131.638074 77.0095)
		(width 0.155)
		(layer "B.Cu")
		(net 205)
	)
	(segment
		(start 131.638074 77.0095)
		(end 133.2905 77.0095)
		(width 0.155)
		(layer "B.Cu")
		(net 205)
	)
	(segment
		(start 124.092551 74.1031)
		(end 126.468326 74.1031)
		(width 0.155)
		(layer "B.Cu")
		(net 205)
	)
	(segment
		(start 134.266 75.938168)
		(end 134.266 76.485)
		(width 0.155)
		(layer "B.Cu")
		(net 205)
	)
	(segment
		(start 136.148074 77.0095)
		(end 142.038074 82.8995)
		(width 0.155)
		(layer "B.Cu")
		(net 205)
	)
	(arc
		(start 133.815 75.938168)
		(mid 133.881047 75.778715)
		(end 134.0405 75.712668)
		(width 0.155)
		(layer "B.Cu")
		(net 205)
	)
	(arc
		(start 134.266 76.485)
		(mid 134.419622 76.855878)
		(end 134.7905 77.0095)
		(width 0.155)
		(layer "B.Cu")
		(net 205)
	)
	(arc
		(start 133.2905 77.0095)
		(mid 133.661378 76.855878)
		(end 133.815 76.485)
		(width 0.155)
		(layer "B.Cu")
		(net 205)
	)
	(arc
		(start 134.0405 75.712668)
		(mid 134.199953 75.778715)
		(end 134.266 75.938168)
		(width 0.155)
		(layer "B.Cu")
		(net 205)
	)
	(segment
		(start 128.018326 74.6069)
		(end 123.712551 74.6069)
		(width 0.155)
		(layer "B.Cu")
		(net 206)
	)
	(segment
		(start 139.2895 82.178074)
		(end 135.761926 78.6505)
		(width 0.155)
		(layer "B.Cu")
		(net 206)
	)
	(segment
		(start 143.15 83.5)
		(end 142.7 83.5)
		(width 0.155)
		(layer "B.Cu")
		(net 206)
	)
	(segment
		(start 139.2895 82.788074)
		(end 139.2895 82.178074)
		(width 0.155)
		(layer "B.Cu")
		(net 206)
	)
	(segment
		(start 140.101926 83.6005)
		(end 139.2895 82.788074)
		(width 0.155)
		(layer "B.Cu")
		(net 206)
	)
	(segment
		(start 123.712551 74.6069)
		(end 123.668851 74.5632)
		(width 0.155)
		(layer "B.Cu")
		(net 206)
	)
	(segment
		(start 123.668851 74.5632)
		(end 123.3832 74.5632)
		(width 0.155)
		(layer "B.Cu")
		(net 206)
	)
	(segment
		(start 132.061926 78.6505)
		(end 128.018326 74.6069)
		(width 0.155)
		(layer "B.Cu")
		(net 206)
	)
	(segment
		(start 142.5995 83.6005)
		(end 140.101926 83.6005)
		(width 0.155)
		(layer "B.Cu")
		(net 206)
	)
	(segment
		(start 123.3832 74.5632)
		(end 123.38 74.56)
		(width 0.155)
		(layer "B.Cu")
		(net 206)
	)
	(segment
		(start 142.7 83.5)
		(end 142.5995 83.6005)
		(width 0.155)
		(layer "B.Cu")
		(net 206)
	)
	(segment
		(start 135.761926 78.6505)
		(end 132.061926 78.6505)
		(width 0.155)
		(layer "B.Cu")
		(net 206)
	)
	(segment
		(start 127.894474 74.9059)
		(end 123.712551 74.9059)
		(width 0.155)
		(layer "B.Cu")
		(net 207)
	)
	(segment
		(start 123.648851 74.9696)
		(end 123.3896 74.9696)
		(width 0.155)
		(layer "B.Cu")
		(net 207)
	)
	(segment
		(start 138.9905 82.301926)
		(end 135.638074 78.9495)
		(width 0.155)
		(layer "B.Cu")
		(net 207)
	)
	(segment
		(start 139.978074 83.8995)
		(end 138.9905 82.911926)
		(width 0.155)
		(layer "B.Cu")
		(net 207)
	)
	(segment
		(start 131.938074 78.9495)
		(end 127.894474 74.9059)
		(width 0.155)
		(layer "B.Cu")
		(net 207)
	)
	(segment
		(start 138.9905 82.911926)
		(end 138.9905 82.301926)
		(width 0.155)
		(layer "B.Cu")
		(net 207)
	)
	(segment
		(start 142.5995 83.8995)
		(end 139.978074 83.8995)
		(width 0.155)
		(layer "B.Cu")
		(net 207)
	)
	(segment
		(start 142.7 84)
		(end 142.5995 83.8995)
		(width 0.155)
		(layer "B.Cu")
		(net 207)
	)
	(segment
		(start 143.15 84)
		(end 142.7 84)
		(width 0.155)
		(layer "B.Cu")
		(net 207)
	)
	(segment
		(start 123.3896 74.9696)
		(end 123.38 74.96)
		(width 0.155)
		(layer "B.Cu")
		(net 207)
	)
	(segment
		(start 135.638074 78.9495)
		(end 131.938074 78.9495)
		(width 0.155)
		(layer "B.Cu")
		(net 207)
	)
	(segment
		(start 123.712551 74.9059)
		(end 123.648851 74.9696)
		(width 0.155)
		(layer "B.Cu")
		(net 207)
	)
	(via
		(at 113.66 74.4906)
		(size 0.45)
		(drill 0.1)
		(layers "F.Cu" "B.Cu")
		(net 212)
	)
	(via
		(at 139.45211 91.71211)
		(size 0.45)
		(drill 0.1)
		(layers "F.Cu" "B.Cu")
		(net 212)
	)
	(segment
		(start 124.271718 76.439)
		(end 124.855359 75.855359)
		(width 0.16)
		(layer "In5.Cu")
		(net 212)
	)
	(segment
		(start 139.657172 91.71211)
		(end 139.45211 91.71211)
		(width 0.16)
		(layer "In5.Cu")
		(net 212)
	)
	(segment
		(start 142.838282 91.561)
		(end 139.808282 91.561)
		(width 0.16)
		(layer "In5.Cu")
		(net 212)
	)
	(segment
		(start 135.498282 77.089)
		(end 143.241 84.831718)
		(width 0.16)
		(layer "In5.Cu")
		(net 212)
	)
	(segment
		(start 125.425082 75.576554)
		(end 125.421043 75.572515)
		(width 0.16)
		(layer "In5.Cu")
		(net 212)
	)
	(segment
		(start 113.66 74.4906)
		(end 113.808 74.3426)
		(width 0.16)
		(layer "In5.Cu")
		(net 212)
	)
	(segment
		(start 143.241 84.831718)
		(end 143.241 91.158282)
		(width 0.16)
		(layer "In5.Cu")
		(net 212)
	)
	(segment
		(start 125.421043 75.289672)
		(end 126.041718 74.669)
		(width 0.16)
		(layer "In5.Cu")
		(net 212)
	)
	(segment
		(start 126.041718 74.669)
		(end 127.998282 74.669)
		(width 0.16)
		(layer "In5.Cu")
		(net 212)
	)
	(segment
		(start 125.425082 75.859398)
		(end 125.425082 75.859397)
		(width 0.16)
		(layer "In5.Cu")
		(net 212)
	)
	(segment
		(start 120.568282 75.609)
		(end 121.398282 76.439)
		(width 0.16)
		(layer "In5.Cu")
		(net 212)
	)
	(segment
		(start 143.241 91.158282)
		(end 142.838282 91.561)
		(width 0.16)
		(layer "In5.Cu")
		(net 212)
	)
	(segment
		(start 116.778112 75.511)
		(end 116.876112 75.609)
		(width 0.16)
		(layer "In5.Cu")
		(net 212)
	)
	(segment
		(start 125.138201 75.855359)
		(end 125.142239 75.859397)
		(width 0.16)
		(layer "In5.Cu")
		(net 212)
	)
	(segment
		(start 115.568282 75.609)
		(end 116.323888 75.609)
		(width 0.16)
		(layer "In5.Cu")
		(net 212)
	)
	(segment
		(start 125.421042 75.289672)
		(end 125.421043 75.289672)
		(width 0.16)
		(layer "In5.Cu")
		(net 212)
	)
	(segment
		(start 127.998282 74.669)
		(end 130.418282 77.089)
		(width 0.16)
		(layer "In5.Cu")
		(net 212)
	)
	(segment
		(start 116.876112 75.609)
		(end 120.568282 75.609)
		(width 0.16)
		(layer "In5.Cu")
		(net 212)
	)
	(segment
		(start 139.808282 91.561)
		(end 139.657172 91.71211)
		(width 0.16)
		(layer "In5.Cu")
		(net 212)
	)
	(segment
		(start 113.808 74.3426)
		(end 114.301882 74.3426)
		(width 0.16)
		(layer "In5.Cu")
		(net 212)
	)
	(segment
		(start 121.398282 76.439)
		(end 124.271718 76.439)
		(width 0.16)
		(layer "In5.Cu")
		(net 212)
	)
	(segment
		(start 116.421888 75.511)
		(end 116.778112 75.511)
		(width 0.16)
		(layer "In5.Cu")
		(net 212)
	)
	(segment
		(start 125.425082 75.576553)
		(end 125.425082 75.576554)
		(width 0.16)
		(layer "In5.Cu")
		(net 212)
	)
	(segment
		(start 130.418282 77.089)
		(end 135.498282 77.089)
		(width 0.16)
		(layer "In5.Cu")
		(net 212)
	)
	(segment
		(start 114.301882 74.3426)
		(end 115.568282 75.609)
		(width 0.16)
		(layer "In5.Cu")
		(net 212)
	)
	(segment
		(start 116.323888 75.609)
		(end 116.421888 75.511)
		(width 0.16)
		(layer "In5.Cu")
		(net 212)
	)
	(arc
		(start 125.421043 75.572515)
		(mid 125.362464 75.431094)
		(end 125.421042 75.289672)
		(width 0.16)
		(layer "In5.Cu")
		(net 212)
	)
	(arc
		(start 125.142239 75.859397)
		(mid 125.28366 75.917976)
		(end 125.425082 75.859398)
		(width 0.16)
		(layer "In5.Cu")
		(net 212)
	)
	(arc
		(start 124.855359 75.855359)
		(mid 124.99678 75.796781)
		(end 125.138201 75.855359)
		(width 0.16)
		(layer "In5.Cu")
		(net 212)
	)
	(arc
		(start 125.425082 75.859397)
		(mid 125.483661 75.717975)
		(end 125.425082 75.576553)
		(width 0.16)
		(layer "In5.Cu")
		(net 212)
	)
	(segment
		(start 139.768075 91.6005)
		(end 142.149499 91.6005)
		(width 0.155)
		(layer "B.Cu")
		(net 212)
	)
	(segment
		(start 139.656465 91.71211)
		(end 139.768075 91.6005)
		(width 0.155)
		(layer "B.Cu")
		(net 212)
	)
	(segment
		(start 112.52 74.43)
		(end 112.5705 74.3795)
		(width 0.155)
		(layer "B.Cu")
		(net 212)
	)
	(segment
		(start 142.149499 91.6005)
		(end 142.249999 91.5)
		(width 0.155)
		(layer "B.Cu")
		(net 212)
	)
	(segment
		(start 142.249999 91.5)
		(end 143.15 91.5)
		(width 0.155)
		(layer "B.Cu")
		(net 212)
	)
	(segment
		(start 112.5705 74.3795)
		(end 113.5489 74.3795)
		(width 0.155)
		(layer "B.Cu")
		(net 212)
	)
	(segment
		(start 113.5489 74.3795)
		(end 113.66 74.4906)
		(width 0.155)
		(layer "B.Cu")
		(net 212)
	)
	(segment
		(start 139.45211 91.71211)
		(end 139.656465 91.71211)
		(width 0.155)
		(layer "B.Cu")
		(net 212)
	)
	(via
		(at 113.66 73.8966)
		(size 0.45)
		(drill 0.1)
		(layers "F.Cu" "B.Cu")
		(net 213)
	)
	(via
		(at 139.86789 92.12789)
		(size 0.45)
		(drill 0.1)
		(layers "F.Cu" "B.Cu")
		(net 213)
	)
	(segment
		(start 125.918282 74.371)
		(end 124.148282 76.141)
		(width 0.16)
		(layer "In5.Cu")
		(net 213)
	)
	(segment
		(start 143.539 91.281718)
		(end 143.539 84.708282)
		(width 0.16)
		(layer "In5.Cu")
		(net 213)
	)
	(segment
		(start 115.691718 75.311)
		(end 116.20048 75.311)
		(width 0.16)
		(layer "In5.Cu")
		(net 213)
	)
	(segment
		(start 115.691718 75.311)
		(end 114.425318 74.0446)
		(width 0.16)
		(layer "In5.Cu")
		(net 213)
	)
	(segment
		(start 124.148282 76.141)
		(end 121.521718 76.141)
		(width 0.16)
		(layer "In5.Cu")
		(net 213)
	)
	(segment
		(start 130.541718 76.791)
		(end 128.121718 74.371)
		(width 0.16)
		(layer "In5.Cu")
		(net 213)
	)
	(segment
		(start 128.121718 74.371)
		(end 125.918282 74.371)
		(width 0.16)
		(layer "In5.Cu")
		(net 213)
	)
	(segment
		(start 116.999519 75.311)
		(end 120.691718 75.311)
		(width 0.16)
		(layer "In5.Cu")
		(net 213)
	)
	(segment
		(start 113.808 74.0446)
		(end 113.66 73.8966)
		(width 0.16)
		(layer "In5.Cu")
		(net 213)
	)
	(segment
		(start 135.621718 76.791)
		(end 130.541718 76.791)
		(width 0.16)
		(layer "In5.Cu")
		(net 213)
	)
	(segment
		(start 143.539 84.708282)
		(end 135.621718 76.791)
		(width 0.16)
		(layer "In5.Cu")
		(net 213)
	)
	(segment
		(start 139.86789 92.12789)
		(end 139.86789 91.922828)
		(width 0.16)
		(layer "In5.Cu")
		(net 213)
	)
	(segment
		(start 139.86789 91.922828)
		(end 139.931718 91.859)
		(width 0.16)
		(layer "In5.Cu")
		(net 213)
	)
	(segment
		(start 116.20048 75.311)
		(end 116.298461 75.21302)
		(width 0.16)
		(layer "In5.Cu")
		(net 213)
	)
	(segment
		(start 116.298461 75.21302)
		(end 116.90154 75.21302)
		(width 0.16)
		(layer "In5.Cu")
		(net 213)
	)
	(segment
		(start 121.521718 76.141)
		(end 120.691718 75.311)
		(width 0.16)
		(layer "In5.Cu")
		(net 213)
	)
	(segment
		(start 142.961718 91.859)
		(end 143.539 91.281718)
		(width 0.16)
		(layer "In5.Cu")
		(net 213)
	)
	(segment
		(start 139.931718 91.859)
		(end 142.961718 91.859)
		(width 0.16)
		(layer "In5.Cu")
		(net 213)
	)
	(segment
		(start 114.425318 74.0446)
		(end 113.808 74.0446)
		(width 0.16)
		(layer "In5.Cu")
		(net 213)
	)
	(segment
		(start 116.90154 75.21302)
		(end 116.999519 75.311)
		(width 0.16)
		(layer "In5.Cu")
		(net 213)
	)
	(segment
		(start 142.249999 92)
		(end 143.15 92)
		(width 0.155)
		(layer "B.Cu")
		(net 213)
	)
	(segment
		(start 112.5705 74.0805)
		(end 113.4761 74.0805)
		(width 0.155)
		(layer "B.Cu")
		(net 213)
	)
	(segment
		(start 139.86789 92.12789)
		(end 139.86789 91.923535)
		(width 0.155)
		(layer "B.Cu")
		(net 213)
	)
	(segment
		(start 139.891925 91.8995)
		(end 142.149499 91.8995)
		(width 0.155)
		(layer "B.Cu")
		(net 213)
	)
	(segment
		(start 139.86789 91.923535)
		(end 139.891925 91.8995)
		(width 0.155)
		(layer "B.Cu")
		(net 213)
	)
	(segment
		(start 113.4761 74.0805)
		(end 113.66 73.8966)
		(width 0.155)
		(layer "B.Cu")
		(net 213)
	)
	(segment
		(start 142.149499 91.8995)
		(end 142.249999 92)
		(width 0.155)
		(layer "B.Cu")
		(net 213)
	)
	(segment
		(start 112.52 74.03)
		(end 112.5705 74.0805)
		(width 0.155)
		(layer "B.Cu")
		(net 213)
	)
	(via
		(at 113.189989 75.550011)
		(size 0.45)
		(drill 0.1)
		(layers "F.Cu" "B.Cu")
		(net 214)
	)
	(via
		(at 137.72211 92.36211)
		(size 0.45)
		(drill 0.1)
		(layers "F.Cu" "B.Cu")
		(net 214)
	)
	(segment
		(start 115.748282 76.509)
		(end 117.469282 78.23)
		(width 0.16)
		(layer "In5.Cu")
		(net 214)
	)
	(segment
		(start 119.648282 79.849)
		(end 120.591 79.849)
		(width 0.16)
		(layer "In5.Cu")
		(net 214)
	)
	(segment
		(start 137.927172 92.36211)
		(end 137.72211 92.36211)
		(width 0.16)
		(layer "In5.Cu")
		(net 214)
	)
	(segment
		(start 138.86 90.489282)
		(end 138.591 90.758282)
		(width 0.16)
		(layer "In5.Cu")
		(net 214)
	)
	(segment
		(start 118.941 79.141718)
		(end 119.648282 79.849)
		(width 0.16)
		(layer "In5.Cu")
		(net 214)
	)
	(segment
		(start 138.591 91.698282)
		(end 137.927172 92.36211)
		(width 0.16)
		(layer "In5.Cu")
		(net 214)
	)
	(segment
		(start 124.788282 78.999)
		(end 125.489282 79.7)
		(width 0.16)
		(layer "In5.Cu")
		(net 214)
	)
	(segment
		(start 121.191 80.070086)
		(end 121.191 80.049)
		(width 0.16)
		(layer "In5.Cu")
		(net 214)
	)
	(segment
		(start 121.391 79.849)
		(end 122.961718 79.849)
		(width 0.16)
		(layer "In5.Cu")
		(net 214)
	)
	(segment
		(start 138.86 89.67)
		(end 138.86 90.489282)
		(width 0.16)
		(layer "In5.Cu")
		(net 214)
	)
	(segment
		(start 137.811 84.781718)
		(end 137.811 88.621)
		(width 0.16)
		(layer "In5.Cu")
		(net 214)
	)
	(segment
		(start 118.941 78.591718)
		(end 118.941 79.141718)
		(width 0.16)
		(layer "In5.Cu")
		(net 214)
	)
	(segment
		(start 117.469282 78.23)
		(end 118.579282 78.23)
		(width 0.16)
		(layer "In5.Cu")
		(net 214)
	)
	(segment
		(start 136.861 83.831718)
		(end 137.811 84.781718)
		(width 0.16)
		(layer "In5.Cu")
		(net 214)
	)
	(segment
		(start 120.791 80.049)
		(end 120.791 80.070086)
		(width 0.16)
		(layer "In5.Cu")
		(net 214)
	)
	(segment
		(start 137.811 88.621)
		(end 138.86 89.67)
		(width 0.16)
		(layer "In5.Cu")
		(net 214)
	)
	(segment
		(start 125.489282 79.7)
		(end 126.470718 79.7)
		(width 0.16)
		(layer "In5.Cu")
		(net 214)
	)
	(segment
		(start 136.861 83.016)
		(end 136.861 83.831718)
		(width 0.16)
		(layer "In5.Cu")
		(net 214)
	)
	(segment
		(start 123.811718 78.999)
		(end 124.788282 78.999)
		(width 0.16)
		(layer "In5.Cu")
		(net 214)
	)
	(segment
		(start 113.399293 75.550011)
		(end 114.358282 76.509)
		(width 0.16)
		(layer "In5.Cu")
		(net 214)
	)
	(segment
		(start 126.470718 79.7)
		(end 127.071718 79.099)
		(width 0.16)
		(layer "In5.Cu")
		(net 214)
	)
	(segment
		(start 118.579282 78.23)
		(end 118.941 78.591718)
		(width 0.16)
		(layer "In5.Cu")
		(net 214)
	)
	(segment
		(start 132.944 79.099)
		(end 136.861 83.016)
		(width 0.16)
		(layer "In5.Cu")
		(net 214)
	)
	(segment
		(start 113.189989 75.550011)
		(end 113.399293 75.550011)
		(width 0.16)
		(layer "In5.Cu")
		(net 214)
	)
	(segment
		(start 138.591 90.758282)
		(end 138.591 91.698282)
		(width 0.16)
		(layer "In5.Cu")
		(net 214)
	)
	(segment
		(start 114.358282 76.509)
		(end 115.748282 76.509)
		(width 0.16)
		(layer "In5.Cu")
		(net 214)
	)
	(segment
		(start 122.961718 79.849)
		(end 123.811718 78.999)
		(width 0.16)
		(layer "In5.Cu")
		(net 214)
	)
	(segment
		(start 127.071718 79.099)
		(end 132.944 79.099)
		(width 0.16)
		(layer "In5.Cu")
		(net 214)
	)
	(arc
		(start 121.191 80.049)
		(mid 121.249579 79.907579)
		(end 121.391 79.849)
		(width 0.16)
		(layer "In5.Cu")
		(net 214)
	)
	(arc
		(start 120.791 80.070086)
		(mid 120.849579 80.211507)
		(end 120.991 80.270086)
		(width 0.16)
		(layer "In5.Cu")
		(net 214)
	)
	(arc
		(start 120.591 79.849)
		(mid 120.732421 79.907579)
		(end 120.791 80.049)
		(width 0.16)
		(layer "In5.Cu")
		(net 214)
	)
	(arc
		(start 120.991 80.270086)
		(mid 121.132421 80.211507)
		(end 121.191 80.070086)
		(width 0.16)
		(layer "In5.Cu")
		(net 214)
	)
	(segment
		(start 112.52 75.23)
		(end 112.7945 75.23)
		(width 0.155)
		(layer "B.Cu")
		(net 214)
	)
	(segment
		(start 138.691926 92.1705)
		(end 139.271926 92.7505)
		(width 0.155)
		(layer "B.Cu")
		(net 214)
	)
	(segment
		(start 139.898074 92.7505)
		(end 140.168074 92.4805)
		(width 0.155)
		(layer "B.Cu")
		(net 214)
	)
	(segment
		(start 141.73 92.6)
		(end 143.05 92.6)
		(width 0.155)
		(layer "B.Cu")
		(net 214)
	)
	(segment
		(start 139.271926 92.7505)
		(end 139.898074 92.7505)
		(width 0.155)
		(layer "B.Cu")
		(net 214)
	)
	(segment
		(start 143.05 92.6)
		(end 143.15 92.5)
		(width 0.155)
		(layer "B.Cu")
		(net 214)
	)
	(segment
		(start 113.189989 75.341414)
		(end 113.048075 75.1995)
		(width 0.155)
		(layer "B.Cu")
		(net 214)
	)
	(segment
		(start 112.7945 75.23)
		(end 112.825 75.1995)
		(width 0.155)
		(layer "B.Cu")
		(net 214)
	)
	(segment
		(start 113.189989 75.550011)
		(end 113.189989 75.341414)
		(width 0.155)
		(layer "B.Cu")
		(net 214)
	)
	(segment
		(start 140.168074 92.4805)
		(end 141.6105 92.4805)
		(width 0.155)
		(layer "B.Cu")
		(net 214)
	)
	(segment
		(start 137.72211 92.36211)
		(end 137.926465 92.36211)
		(width 0.155)
		(layer "B.Cu")
		(net 214)
	)
	(segment
		(start 141.6105 92.4805)
		(end 141.73 92.6)
		(width 0.155)
		(layer "B.Cu")
		(net 214)
	)
	(segment
		(start 137.926465 92.36211)
		(end 138.118075 92.1705)
		(width 0.155)
		(layer "B.Cu")
		(net 214)
	)
	(segment
		(start 113.048075 75.1995)
		(end 112.825 75.1995)
		(width 0.155)
		(layer "B.Cu")
		(net 214)
	)
	(segment
		(start 138.118075 92.1705)
		(end 138.691926 92.1705)
		(width 0.155)
		(layer "B.Cu")
		(net 214)
	)
	(via
		(at 138.13789 92.77789)
		(size 0.45)
		(drill 0.1)
		(layers "F.Cu" "B.Cu")
		(net 215)
	)
	(via
		(at 113.610011 75.129989)
		(size 0.45)
		(drill 0.1)
		(layers "F.Cu" "B.Cu")
		(net 215)
	)
	(segment
		(start 115.871718 76.211)
		(end 117.580718 77.92)
		(width 0.16)
		(layer "In5.Cu")
		(net 215)
	)
	(segment
		(start 138.889 91.821718)
		(end 138.13789 92.572828)
		(width 0.16)
		(layer "In5.Cu")
		(net 215)
	)
	(segment
		(start 139.15 90.620718)
		(end 138.889 90.881718)
		(width 0.16)
		(layer "In5.Cu")
		(net 215)
	)
	(segment
		(start 137.159 82.889)
		(end 137.159 83.708282)
		(width 0.16)
		(layer "In5.Cu")
		(net 215)
	)
	(segment
		(start 124.911718 78.701)
		(end 125.610718 79.4)
		(width 0.16)
		(layer "In5.Cu")
		(net 215)
	)
	(segment
		(start 126.349282 79.4)
		(end 126.948282 78.801)
		(width 0.16)
		(layer "In5.Cu")
		(net 215)
	)
	(segment
		(start 118.690718 77.92)
		(end 119.239 78.468282)
		(width 0.16)
		(layer "In5.Cu")
		(net 215)
	)
	(segment
		(start 117.580718 77.92)
		(end 118.690718 77.92)
		(width 0.16)
		(layer "In5.Cu")
		(net 215)
	)
	(segment
		(start 113.610011 75.129989)
		(end 113.610011 75.339293)
		(width 0.16)
		(layer "In5.Cu")
		(net 215)
	)
	(segment
		(start 125.610718 79.4)
		(end 126.349282 79.4)
		(width 0.16)
		(layer "In5.Cu")
		(net 215)
	)
	(segment
		(start 122.838282 79.551)
		(end 123.688282 78.701)
		(width 0.16)
		(layer "In5.Cu")
		(net 215)
	)
	(segment
		(start 126.948282 78.801)
		(end 133.071 78.801)
		(width 0.16)
		(layer "In5.Cu")
		(net 215)
	)
	(segment
		(start 119.239 79.018282)
		(end 119.771718 79.551)
		(width 0.16)
		(layer "In5.Cu")
		(net 215)
	)
	(segment
		(start 113.610011 75.339293)
		(end 114.481718 76.211)
		(width 0.16)
		(layer "In5.Cu")
		(net 215)
	)
	(segment
		(start 138.13789 92.572828)
		(end 138.13789 92.77789)
		(width 0.16)
		(layer "In5.Cu")
		(net 215)
	)
	(segment
		(start 133.071 78.801)
		(end 137.159 82.889)
		(width 0.16)
		(layer "In5.Cu")
		(net 215)
	)
	(segment
		(start 114.481718 76.211)
		(end 115.871718 76.211)
		(width 0.16)
		(layer "In5.Cu")
		(net 215)
	)
	(segment
		(start 137.159 83.708282)
		(end 138.109 84.658282)
		(width 0.16)
		(layer "In5.Cu")
		(net 215)
	)
	(segment
		(start 138.109 88.509)
		(end 139.15 89.55)
		(width 0.16)
		(layer "In5.Cu")
		(net 215)
	)
	(segment
		(start 139.15 89.55)
		(end 139.15 90.620718)
		(width 0.16)
		(layer "In5.Cu")
		(net 215)
	)
	(segment
		(start 138.889 90.881718)
		(end 138.889 91.821718)
		(width 0.16)
		(layer "In5.Cu")
		(net 215)
	)
	(segment
		(start 119.239 78.468282)
		(end 119.239 79.018282)
		(width 0.16)
		(layer "In5.Cu")
		(net 215)
	)
	(segment
		(start 123.688282 78.701)
		(end 124.911718 78.701)
		(width 0.16)
		(layer "In5.Cu")
		(net 215)
	)
	(segment
		(start 119.771718 79.551)
		(end 122.838282 79.551)
		(width 0.16)
		(layer "In5.Cu")
		(net 215)
	)
	(segment
		(start 138.109 84.658282)
		(end 138.109 88.509)
		(width 0.16)
		(layer "In5.Cu")
		(net 215)
	)
	(segment
		(start 113.171925 74.9005)
		(end 112.825 74.9005)
		(width 0.155)
		(layer "B.Cu")
		(net 215)
	)
	(segment
		(start 141.4795 92.7795)
		(end 141.6 92.9)
		(width 0.155)
		(layer "B.Cu")
		(net 215)
	)
	(segment
		(start 112.52 74.83)
		(end 112.7545 74.83)
		(width 0.155)
		(layer "B.Cu")
		(net 215)
	)
	(segment
		(start 143.05 92.9)
		(end 143.15 93)
		(width 0.155)
		(layer "B.Cu")
		(net 215)
	)
	(segment
		(start 138.13789 92.77789)
		(end 138.13789 92.573535)
		(width 0.155)
		(layer "B.Cu")
		(net 215)
	)
	(segment
		(start 140.291926 92.7795)
		(end 141.4795 92.7795)
		(width 0.155)
		(layer "B.Cu")
		(net 215)
	)
	(segment
		(start 112.7545 74.83)
		(end 112.825 74.9005)
		(width 0.155)
		(layer "B.Cu")
		(net 215)
	)
	(segment
		(start 140.021926 93.0495)
		(end 140.291926 92.7795)
		(width 0.155)
		(layer "B.Cu")
		(net 215)
	)
	(segment
		(start 138.241925 92.4695)
		(end 138.568074 92.4695)
		(width 0.155)
		(layer "B.Cu")
		(net 215)
	)
	(segment
		(start 113.401414 75.129989)
		(end 113.171925 74.9005)
		(width 0.155)
		(layer "B.Cu")
		(net 215)
	)
	(segment
		(start 138.13789 92.573535)
		(end 138.241925 92.4695)
		(width 0.155)
		(layer "B.Cu")
		(net 215)
	)
	(segment
		(start 113.610011 75.129989)
		(end 113.401414 75.129989)
		(width 0.155)
		(layer "B.Cu")
		(net 215)
	)
	(segment
		(start 138.568074 92.4695)
		(end 139.148074 93.0495)
		(width 0.155)
		(layer "B.Cu")
		(net 215)
	)
	(segment
		(start 141.6 92.9)
		(end 143.05 92.9)
		(width 0.155)
		(layer "B.Cu")
		(net 215)
	)
	(segment
		(start 139.148074 93.0495)
		(end 140.021926 93.0495)
		(width 0.155)
		(layer "B.Cu")
		(net 215)
	)
	(segment
		(start 115.85 97.35)
		(end 115.5 97)
		(width 0.15)
		(layer "F.Cu")
		(net 216)
	)
	(segment
		(start 117 98.15)
		(end 116.05 98.15)
		(width 0.15)
		(layer "F.Cu")
		(net 216)
	)
	(segment
		(start 115.85 97.95)
		(end 115.85 97.35)
		(width 0.15)
		(layer "F.Cu")
		(net 216)
	)
	(segment
		(start 115.5 97)
		(end 115.085 97)
		(width 0.15)
		(layer "F.Cu")
		(net 216)
	)
	(segment
		(start 116.05 98.15)
		(end 115.85 97.95)
		(width 0.15)
		(layer "F.Cu")
		(net 216)
	)
	(segment
		(start 137.6 98.4)
		(end 136.285 98.4)
		(width 0.15)
		(layer "B.Cu")
		(net 217)
	)
	(segment
		(start 138.25 98.5075)
		(end 137.7075 98.5075)
		(width 0.15)
		(layer "B.Cu")
		(net 217)
	)
	(segment
		(start 137.7075 98.5075)
		(end 137.6 98.4)
		(width 0.15)
		(layer "B.Cu")
		(net 217)
	)
	(segment
		(start 125.48 112.275)
		(end 125.975 112.275)
		(width 0.125)
		(layer "F.Cu")
		(net 218)
	)
	(segment
		(start 121.085 101.795)
		(end 121.085 107.88)
		(width 0.125)
		(layer "F.Cu")
		(net 218)
	)
	(segment
		(start 125.975 112.275)
		(end 126.92 113.22)
		(width 0.125)
		(layer "F.Cu")
		(net 218)
	)
	(segment
		(start 126.92 113.22)
		(end 127.905 113.22)
		(width 0.125)
		(layer "F.Cu")
		(net 218)
	)
	(segment
		(start 121.085 107.88)
		(end 125.48 112.275)
		(width 0.125)
		(layer "F.Cu")
		(net 218)
	)
	(segment
		(start 116.981 99.12)
		(end 118.41 99.12)
		(width 0.125)
		(layer "F.Cu")
		(net 218)
	)
	(segment
		(start 118.41 99.12)
		(end 121.085 101.795)
		(width 0.125)
		(layer "F.Cu")
		(net 218)
	)
	(segment
		(start 137.4 99.4)
		(end 137.7025 99.0975)
		(width 0.15)
		(layer "B.Cu")
		(net 219)
	)
	(segment
		(start 136.285 99.4)
		(end 137.4 99.4)
		(width 0.15)
		(layer "B.Cu")
		(net 219)
	)
	(segment
		(start 137.7025 99.0975)
		(end 138.25 99.0975)
		(width 0.15)
		(layer "B.Cu")
		(net 219)
	)
	(segment
		(start 125.795 112.64)
		(end 127.38 114.225)
		(width 0.125)
		(layer "F.Cu")
		(net 220)
	)
	(segment
		(start 116.981 99.62)
		(end 118.395 99.62)
		(width 0.125)
		(layer "F.Cu")
		(net 220)
	)
	(segment
		(start 125.415 112.64)
		(end 125.795 112.64)
		(width 0.125)
		(layer "F.Cu")
		(net 220)
	)
	(segment
		(start 120.74 101.965)
		(end 120.74 107.965)
		(width 0.125)
		(layer "F.Cu")
		(net 220)
	)
	(segment
		(start 127.38 114.225)
		(end 127.905 114.225)
		(width 0.125)
		(layer "F.Cu")
		(net 220)
	)
	(segment
		(start 120.74 107.965)
		(end 125.415 112.64)
		(width 0.125)
		(layer "F.Cu")
		(net 220)
	)
	(segment
		(start 118.395 99.62)
		(end 120.74 101.965)
		(width 0.125)
		(layer "F.Cu")
		(net 220)
	)
	(segment
		(start 115.5 99.8)
		(end 115.085 99.8)
		(width 0.15)
		(layer "F.Cu")
		(net 221)
	)
	(segment
		(start 117 100.15)
		(end 115.85 100.15)
		(width 0.15)
		(layer "F.Cu")
		(net 221)
	)
	(segment
		(start 115.85 100.15)
		(end 115.5 99.8)
		(width 0.15)
		(layer "F.Cu")
		(net 221)
	)
	(segment
		(start 115.085 100.8)
		(end 115.8 100.8)
		(width 0.15)
		(layer "F.Cu")
		(net 223)
	)
	(segment
		(start 115.95 100.65)
		(end 117 100.65)
		(width 0.15)
		(layer "F.Cu")
		(net 223)
	)
	(segment
		(start 115.8 100.8)
		(end 115.95 100.65)
		(width 0.15)
		(layer "F.Cu")
		(net 223)
	)
	(segment
		(start 116.981 101.12)
		(end 119.365 101.12)
		(width 0.125)
		(layer "F.Cu")
		(net 225)
	)
	(segment
		(start 120.4 102.155)
		(end 120.4 108.1)
		(width 0.125)
		(layer "F.Cu")
		(net 225)
	)
	(segment
		(start 125.675 113.005)
		(end 127.905 115.235)
		(width 0.125)
		(layer "F.Cu")
		(net 225)
	)
	(segment
		(start 119.365 101.12)
		(end 120.4 102.155)
		(width 0.125)
		(layer "F.Cu")
		(net 225)
	)
	(segment
		(start 125.305 113.005)
		(end 125.675 113.005)
		(width 0.125)
		(layer "F.Cu")
		(net 225)
	)
	(segment
		(start 120.4 108.1)
		(end 125.305 113.005)
		(width 0.125)
		(layer "F.Cu")
		(net 225)
	)
	(via
		(at 84.73 76.73)
		(size 0.45)
		(drill 0.1)
		(layers "F.Cu" "B.Cu")
		(net 234)
	)
	(via
		(at 116.460011 74.419989)
		(size 0.45)
		(drill 0.1)
		(layers "F.Cu" "B.Cu")
		(net 234)
	)
	(segment
		(start 90.298282 73.441)
		(end 89.098282 73.441)
		(width 0.16)
		(layer "In5.Cu")
		(net 234)
	)
	(segment
		(start 109.081718 72.321)
		(end 97.378282 72.321)
		(width 0.16)
		(layer "In5.Cu")
		(net 234)
	)
	(segment
		(start 90.858282 72.881)
		(end 90.298282 73.441)
		(width 0.16)
		(layer "In5.Cu")
		(net 234)
	)
	(segment
		(start 89.098282 73.441)
		(end 85.578282 76.961)
		(width 0.16)
		(layer "In5.Cu")
		(net 234)
	)
	(segment
		(start 116.250707 74.419989)
		(end 115.681718 73.851)
		(width 0.16)
		(layer "In5.Cu")
		(net 234)
	)
	(segment
		(start 116.460011 74.419989)
		(end 116.250707 74.419989)
		(width 0.16)
		(layer "In5.Cu")
		(net 234)
	)
	(segment
		(start 115.391718 73.851)
		(end 114.291718 72.751)
		(width 0.16)
		(layer "In5.Cu")
		(net 234)
	)
	(segment
		(start 109.511718 72.751)
		(end 109.081718 72.321)
		(width 0.16)
		(layer "In5.Cu")
		(net 234)
	)
	(segment
		(start 114.291718 72.751)
		(end 109.511718 72.751)
		(width 0.16)
		(layer "In5.Cu")
		(net 234)
	)
	(segment
		(start 96.818282 72.881)
		(end 90.858282 72.881)
		(width 0.16)
		(layer "In5.Cu")
		(net 234)
	)
	(segment
		(start 115.681718 73.851)
		(end 115.391718 73.851)
		(width 0.16)
		(layer "In5.Cu")
		(net 234)
	)
	(segment
		(start 85.578282 76.961)
		(end 84.961 76.961)
		(width 0.16)
		(layer "In5.Cu")
		(net 234)
	)
	(segment
		(start 97.378282 72.321)
		(end 96.818282 72.881)
		(width 0.16)
		(layer "In5.Cu")
		(net 234)
	)
	(segment
		(start 84.961 76.961)
		(end 84.73 76.73)
		(width 0.16)
		(layer "In5.Cu")
		(net 234)
	)
	(segment
		(start 79.6055 74.1005)
		(end 79.6055 75.356926)
		(width 0.155)
		(layer "B.Cu")
		(net 234)
	)
	(segment
		(start 119.23 74.55)
		(end 119.1795 74.6005)
		(width 0.155)
		(layer "B.Cu")
		(net 234)
	)
	(segment
		(start 79.505 74)
		(end 79.6055 74.1005)
		(width 0.155)
		(layer "B.Cu")
		(net 234)
	)
	(segment
		(start 84.961926 78.4095)
		(end 85.5295 77.841926)
		(width 0.155)
		(layer "B.Cu")
		(net 234)
	)
	(segment
		(start 85.126926 76.8455)
		(end 84.8455 76.8455)
		(width 0.155)
		(layer "B.Cu")
		(net 234)
	)
	(segment
		(start 117.141926 75.3105)
		(end 116.460011 74.628586)
		(width 0.155)
		(layer "B.Cu")
		(net 234)
	)
	(segment
		(start 82.658074 78.4095)
		(end 84.961926 78.4095)
		(width 0.155)
		(layer "B.Cu")
		(net 234)
	)
	(segment
		(start 84.8455 76.8455)
		(end 84.73 76.73)
		(width 0.155)
		(layer "B.Cu")
		(net 234)
	)
	(segment
		(start 85.5295 77.248074)
		(end 85.126926 76.8455)
		(width 0.155)
		(layer "B.Cu")
		(net 234)
	)
	(segment
		(start 116.460011 74.628586)
		(end 116.460011 74.419989)
		(width 0.155)
		(layer "B.Cu")
		(net 234)
	)
	(segment
		(start 117.818074 75.3105)
		(end 117.141926 75.3105)
		(width 0.155)
		(layer "B.Cu")
		(net 234)
	)
	(segment
		(start 118.528074 74.6005)
		(end 117.818074 75.3105)
		(width 0.155)
		(layer "B.Cu")
		(net 234)
	)
	(segment
		(start 79.6055 75.356926)
		(end 82.658074 78.4095)
		(width 0.155)
		(layer "B.Cu")
		(net 234)
	)
	(segment
		(start 119.1795 74.6005)
		(end 118.528074 74.6005)
		(width 0.155)
		(layer "B.Cu")
		(net 234)
	)
	(segment
		(start 85.5295 77.841926)
		(end 85.5295 77.248074)
		(width 0.155)
		(layer "B.Cu")
		(net 234)
	)
	(via
		(at 84.67 77.32)
		(size 0.45)
		(drill 0.1)
		(layers "F.Cu" "B.Cu")
		(net 235)
	)
	(via
		(at 116.039989 74.840011)
		(size 0.45)
		(drill 0.1)
		(layers "F.Cu" "B.Cu")
		(net 235)
	)
	(segment
		(start 87.464959 76.452723)
		(end 87.122595 76.110359)
		(width 0.16)
		(layer "In5.Cu")
		(net 235)
	)
	(segment
		(start 85.701718 77.259)
		(end 84.731 77.259)
		(width 0.16)
		(layer "In5.Cu")
		(net 235)
	)
	(segment
		(start 115.558282 74.149)
		(end 115.268282 74.149)
		(width 0.16)
		(layer "In5.Cu")
		(net 235)
	)
	(segment
		(start 116.039989 74.630707)
		(end 115.558282 74.149)
		(width 0.16)
		(layer "In5.Cu")
		(net 235)
	)
	(segment
		(start 96.941718 73.179)
		(end 90.989 73.179)
		(width 0.16)
		(layer "In5.Cu")
		(net 235)
	)
	(segment
		(start 116.039989 74.840011)
		(end 116.039989 74.630707)
		(width 0.16)
		(layer "In5.Cu")
		(net 235)
	)
	(segment
		(start 108.958282 72.619)
		(end 97.501718 72.619)
		(width 0.16)
		(layer "In5.Cu")
		(net 235)
	)
	(segment
		(start 84.731 77.259)
		(end 84.67 77.32)
		(width 0.16)
		(layer "In5.Cu")
		(net 235)
	)
	(segment
		(start 87.737195 76.180486)
		(end 87.737195 76.180485)
		(width 0.16)
		(layer "In5.Cu")
		(net 235)
	)
	(segment
		(start 115.268282 74.149)
		(end 114.168282 73.049)
		(width 0.16)
		(layer "In5.Cu")
		(net 235)
	)
	(segment
		(start 90.989 73.179)
		(end 90.985359 73.175359)
		(width 0.16)
		(layer "In5.Cu")
		(net 235)
	)
	(segment
		(start 90.421718 73.739)
		(end 89.221718 73.739)
		(width 0.16)
		(layer "In5.Cu")
		(net 235)
	)
	(segment
		(start 109.388282 73.049)
		(end 108.958282 72.619)
		(width 0.16)
		(layer "In5.Cu")
		(net 235)
	)
	(segment
		(start 86.850359 76.110359)
		(end 85.701718 77.259)
		(width 0.16)
		(layer "In5.Cu")
		(net 235)
	)
	(segment
		(start 114.168282 73.049)
		(end 109.388282 73.049)
		(width 0.16)
		(layer "In5.Cu")
		(net 235)
	)
	(segment
		(start 90.985359 73.175359)
		(end 90.421718 73.739)
		(width 0.16)
		(layer "In5.Cu")
		(net 235)
	)
	(segment
		(start 97.501718 72.619)
		(end 96.941718 73.179)
		(width 0.16)
		(layer "In5.Cu")
		(net 235)
	)
	(segment
		(start 87.39483 75.838121)
		(end 87.737195 76.180486)
		(width 0.16)
		(layer "In5.Cu")
		(net 235)
	)
	(segment
		(start 89.221718 73.739)
		(end 87.39483 75.565885)
		(width 0.16)
		(layer "In5.Cu")
		(net 235)
	)
	(arc
		(start 87.122595 76.110359)
		(mid 86.986477 76.053977)
		(end 86.850359 76.110359)
		(width 0.16)
		(layer "In5.Cu")
		(net 235)
	)
	(arc
		(start 87.737195 76.180485)
		(mid 87.793577 76.316604)
		(end 87.737195 76.452723)
		(width 0.16)
		(layer "In5.Cu")
		(net 235)
	)
	(arc
		(start 87.39483 75.565885)
		(mid 87.338448 75.702003)
		(end 87.39483 75.838121)
		(width 0.16)
		(layer "In5.Cu")
		(net 235)
	)
	(arc
		(start 87.737195 76.452723)
		(mid 87.601077 76.509105)
		(end 87.464959 76.452723)
		(width 0.16)
		(layer "In5.Cu")
		(net 235)
	)
	(segment
		(start 79.9045 74.1005)
		(end 79.9045 75.233074)
		(width 0.155)
		(layer "B.Cu")
		(net 235)
	)
	(segment
		(start 79.9045 75.233074)
		(end 82.781926 78.1105)
		(width 0.155)
		(layer "B.Cu")
		(net 235)
	)
	(segment
		(start 85.003074 77.1445)
		(end 84.8455 77.1445)
		(width 0.155)
		(layer "B.Cu")
		(net 235)
	)
	(segment
		(start 80.005 74)
		(end 79.9045 74.1005)
		(width 0.155)
		(layer "B.Cu")
		(net 235)
	)
	(segment
		(start 119.1795 74.8995)
		(end 118.651926 74.8995)
		(width 0.155)
		(layer "B.Cu")
		(net 235)
	)
	(segment
		(start 84.838074 78.1105)
		(end 85.2305 77.718074)
		(width 0.155)
		(layer "B.Cu")
		(net 235)
	)
	(segment
		(start 117.018074 75.6095)
		(end 116.248586 74.840011)
		(width 0.155)
		(layer "B.Cu")
		(net 235)
	)
	(segment
		(start 85.2305 77.718074)
		(end 85.2305 77.371926)
		(width 0.155)
		(layer "B.Cu")
		(net 235)
	)
	(segment
		(start 116.248586 74.840011)
		(end 116.039989 74.840011)
		(width 0.155)
		(layer "B.Cu")
		(net 235)
	)
	(segment
		(start 117.941926 75.6095)
		(end 117.018074 75.6095)
		(width 0.155)
		(layer "B.Cu")
		(net 235)
	)
	(segment
		(start 119.23 74.95)
		(end 119.1795 74.8995)
		(width 0.155)
		(layer "B.Cu")
		(net 235)
	)
	(segment
		(start 85.2305 77.371926)
		(end 85.003074 77.1445)
		(width 0.155)
		(layer "B.Cu")
		(net 235)
	)
	(segment
		(start 82.781926 78.1105)
		(end 84.838074 78.1105)
		(width 0.155)
		(layer "B.Cu")
		(net 235)
	)
	(segment
		(start 84.8455 77.1445)
		(end 84.67 77.32)
		(width 0.155)
		(layer "B.Cu")
		(net 235)
	)
	(segment
		(start 118.651926 74.8995)
		(end 117.941926 75.6095)
		(width 0.155)
		(layer "B.Cu")
		(net 235)
	)
	(via
		(at 78.75 76.38)
		(size 0.45)
		(drill 0.1)
		(layers "F.Cu" "B.Cu")
		(net 236)
	)
	(via
		(at 117.71 74.27)
		(size 0.45)
		(drill 0.1)
		(layers "F.Cu" "B.Cu")
		(net 236)
	)
	(segment
		(start 87.771 72.671)
		(end 90.018282 72.671)
		(width 0.16)
		(layer "In5.Cu")
		(net 236)
	)
	(segment
		(start 117.381436 74.27)
		(end 117.71 74.27)
		(width 0.16)
		(layer "In5.Cu")
		(net 236)
	)
	(segment
		(start 90.958282 71.731)
		(end 96.068282 71.731)
		(width 0.16)
		(layer "In5.Cu")
		(net 236)
	)
	(segment
		(start 87.235583 73.282584)
		(end 87.235583 73.133583)
		(width 0.16)
		(layer "In5.Cu")
		(net 236)
	)
	(segment
		(start 82.788486 73.003889)
		(end 82.852842 73.068245)
		(width 0.16)
		(layer "In5.Cu")
		(net 236)
	)
	(segment
		(start 115.180718 72.09)
		(end 115.681718 72.591)
		(width 0.16)
		(layer "In5.Cu")
		(net 236)
	)
	(segment
		(start 83.568282 72.671)
		(end 84.971 72.671)
		(width 0.16)
		(layer "In5.Cu")
		(net 236)
	)
	(segment
		(start 82.111 74.128282)
		(end 82.534641 73.704641)
		(width 0.16)
		(layer "In5.Cu")
		(net 236)
	)
	(segment
		(start 86.998166 73.447167)
		(end 87.071 73.447167)
		(width 0.16)
		(layer "In5.Cu")
		(net 236)
	)
	(segment
		(start 90.018282 72.671)
		(end 90.958282 71.731)
		(width 0.16)
		(layer "In5.Cu")
		(net 236)
	)
	(segment
		(start 96.518282 71.281)
		(end 109.121718 71.281)
		(width 0.16)
		(layer "In5.Cu")
		(net 236)
	)
	(segment
		(start 117.179 72.958282)
		(end 117.179 74.067564)
		(width 0.16)
		(layer "In5.Cu")
		(net 236)
	)
	(segment
		(start 83.17104 73.068245)
		(end 83.568282 72.671)
		(width 0.16)
		(layer "In5.Cu")
		(net 236)
	)
	(segment
		(start 78.881 76.511)
		(end 81.428282 76.511)
		(width 0.16)
		(layer "In5.Cu")
		(net 236)
	)
	(segment
		(start 87.698166 72.671)
		(end 87.771 72.671)
		(width 0.16)
		(layer "In5.Cu")
		(net 236)
	)
	(segment
		(start 96.068282 71.731)
		(end 96.518282 71.281)
		(width 0.16)
		(layer "In5.Cu")
		(net 236)
	)
	(segment
		(start 82.111 75.828282)
		(end 82.111 74.128282)
		(width 0.16)
		(layer "In5.Cu")
		(net 236)
	)
	(segment
		(start 86.833583 73.133583)
		(end 86.833583 73.282584)
		(width 0.16)
		(layer "In5.Cu")
		(net 236)
	)
	(segment
		(start 78.75 76.38)
		(end 78.881 76.511)
		(width 0.16)
		(layer "In5.Cu")
		(net 236)
	)
	(segment
		(start 109.121718 71.281)
		(end 109.930718 72.09)
		(width 0.16)
		(layer "In5.Cu")
		(net 236)
	)
	(segment
		(start 85.648166 73.497167)
		(end 85.671 73.497167)
		(width 0.16)
		(layer "In5.Cu")
		(net 236)
	)
	(segment
		(start 109.930718 72.09)
		(end 115.180718 72.09)
		(width 0.16)
		(layer "In5.Cu")
		(net 236)
	)
	(segment
		(start 85.860583 73.307584)
		(end 85.860583 73.158583)
		(width 0.16)
		(layer "In5.Cu")
		(net 236)
	)
	(segment
		(start 116.811718 72.591)
		(end 117.179 72.958282)
		(width 0.16)
		(layer "In5.Cu")
		(net 236)
	)
	(segment
		(start 86.348166 72.671)
		(end 86.371 72.671)
		(width 0.16)
		(layer "In5.Cu")
		(net 236)
	)
	(segment
		(start 82.788486 73.00389)
		(end 82.788486 73.003889)
		(width 0.16)
		(layer "In5.Cu")
		(net 236)
	)
	(segment
		(start 85.458583 73.158583)
		(end 85.458583 73.307584)
		(width 0.16)
		(layer "In5.Cu")
		(net 236)
	)
	(segment
		(start 81.428282 76.511)
		(end 82.111 75.828282)
		(width 0.16)
		(layer "In5.Cu")
		(net 236)
	)
	(segment
		(start 117.179 74.067564)
		(end 117.381436 74.27)
		(width 0.16)
		(layer "In5.Cu")
		(net 236)
	)
	(segment
		(start 82.534641 73.386443)
		(end 82.470286 73.322088)
		(width 0.16)
		(layer "In5.Cu")
		(net 236)
	)
	(segment
		(start 115.681718 72.591)
		(end 116.811718 72.591)
		(width 0.16)
		(layer "In5.Cu")
		(net 236)
	)
	(arc
		(start 87.235583 73.133583)
		(mid 87.37107 72.806487)
		(end 87.698166 72.671)
		(width 0.16)
		(layer "In5.Cu")
		(net 236)
	)
	(arc
		(start 86.371 72.671)
		(mid 86.698096 72.806487)
		(end 86.833583 73.133583)
		(width 0.16)
		(layer "In5.Cu")
		(net 236)
	)
	(arc
		(start 86.833583 73.282584)
		(mid 86.881788 73.398962)
		(end 86.998166 73.447167)
		(width 0.16)
		(layer "In5.Cu")
		(net 236)
	)
	(arc
		(start 82.470286 73.00389)
		(mid 82.629387 72.937988)
		(end 82.788486 73.00389)
		(width 0.16)
		(layer "In5.Cu")
		(net 236)
	)
	(arc
		(start 82.470286 73.322088)
		(mid 82.404385 73.162989)
		(end 82.470286 73.00389)
		(width 0.16)
		(layer "In5.Cu")
		(net 236)
	)
	(arc
		(start 82.852842 73.068245)
		(mid 83.011941 73.134146)
		(end 83.17104 73.068245)
		(width 0.16)
		(layer "In5.Cu")
		(net 236)
	)
	(arc
		(start 84.971 72.671)
		(mid 85.315773 72.81381)
		(end 85.458583 73.158583)
		(width 0.16)
		(layer "In5.Cu")
		(net 236)
	)
	(arc
		(start 82.534641 73.704641)
		(mid 82.600542 73.545542)
		(end 82.534641 73.386443)
		(width 0.16)
		(layer "In5.Cu")
		(net 236)
	)
	(arc
		(start 85.860583 73.158583)
		(mid 86.003393 72.81381)
		(end 86.348166 72.671)
		(width 0.16)
		(layer "In5.Cu")
		(net 236)
	)
	(arc
		(start 85.671 73.497167)
		(mid 85.805055 73.441639)
		(end 85.860583 73.307584)
		(width 0.16)
		(layer "In5.Cu")
		(net 236)
	)
	(arc
		(start 87.071 73.447167)
		(mid 87.187378 73.398962)
		(end 87.235583 73.282584)
		(width 0.16)
		(layer "In5.Cu")
		(net 236)
	)
	(arc
		(start 85.458583 73.307584)
		(mid 85.514111 73.441639)
		(end 85.648166 73.497167)
		(width 0.16)
		(layer "In5.Cu")
		(net 236)
	)
	(segment
		(start 118.4596 73.7404)
		(end 119.0093 73.7404)
		(width 0.155)
		(layer "B.Cu")
		(net 236)
	)
	(segment
		(start 117.71 74.27)
		(end 117.93 74.27)
		(width 0.155)
		(layer "B.Cu")
		(net 236)
	)
	(segment
		(start 78.8805 76.5105)
		(end 78.918074 76.5105)
		(width 0.155)
		(layer "B.Cu")
		(net 236)
	)
	(segment
		(start 78.75 76.38)
		(end 78.8805 76.5105)
		(width 0.155)
		(layer "B.Cu")
		(net 236)
	)
	(segment
		(start 78.6055 74.1005)
		(end 78.505 74)
		(width 0.155)
		(layer "B.Cu")
		(net 236)
	)
	(segment
		(start 78.918074 76.5105)
		(end 79.0805 76.348074)
		(width 0.155)
		(layer "B.Cu")
		(net 236)
	)
	(segment
		(start 79.0805 75.921926)
		(end 78.6055 75.446926)
		(width 0.155)
		(layer "B.Cu")
		(net 236)
	)
	(segment
		(start 78.6055 75.446926)
		(end 78.6055 74.1005)
		(width 0.155)
		(layer "B.Cu")
		(net 236)
	)
	(segment
		(start 117.93 74.27)
		(end 118.4596 73.7404)
		(width 0.155)
		(layer "B.Cu")
		(net 236)
	)
	(segment
		(start 79.0805 76.348074)
		(end 79.0805 75.921926)
		(width 0.155)
		(layer "B.Cu")
		(net 236)
	)
	(via
		(at 117.5 74.81)
		(size 0.45)
		(drill 0.1)
		(layers "F.Cu" "B.Cu")
		(net 237)
	)
	(via
		(at 78.74 76.97)
		(size 0.45)
		(drill 0.1)
		(layers "F.Cu" "B.Cu")
		(net 237)
	)
	(segment
		(start 116.881 74.191)
		(end 117.5 74.81)
		(width 0.16)
		(layer "In5.Cu")
		(net 237)
	)
	(segment
		(start 87.533583 73.282584)
		(end 87.533583 73.133583)
		(width 0.16)
		(layer "In5.Cu")
		(net 237)
	)
	(segment
		(start 82.409 75.951718)
		(end 82.409 74.251718)
		(width 0.16)
		(layer "In5.Cu")
		(net 237)
	)
	(segment
		(start 90.141718 72.969)
		(end 91.081718 72.029)
		(width 0.16)
		(layer "In5.Cu")
		(net 237)
	)
	(segment
		(start 83.691718 72.969)
		(end 84.971 72.969)
		(width 0.16)
		(layer "In5.Cu")
		(net 237)
	)
	(segment
		(start 81.551718 76.809)
		(end 82.409 75.951718)
		(width 0.16)
		(layer "In5.Cu")
		(net 237)
	)
	(segment
		(start 116.688282 72.889)
		(end 116.881 73.081718)
		(width 0.16)
		(layer "In5.Cu")
		(net 237)
	)
	(segment
		(start 115.558282 72.889)
		(end 116.688282 72.889)
		(width 0.16)
		(layer "In5.Cu")
		(net 237)
	)
	(segment
		(start 87.698166 72.969)
		(end 87.771 72.969)
		(width 0.16)
		(layer "In5.Cu")
		(net 237)
	)
	(segment
		(start 86.348166 72.969)
		(end 86.371 72.969)
		(width 0.16)
		(layer "In5.Cu")
		(net 237)
	)
	(segment
		(start 109.809282 72.39)
		(end 115.059282 72.39)
		(width 0.16)
		(layer "In5.Cu")
		(net 237)
	)
	(segment
		(start 91.081718 72.029)
		(end 96.191718 72.029)
		(width 0.16)
		(layer "In5.Cu")
		(net 237)
	)
	(segment
		(start 115.059282 72.39)
		(end 115.558282 72.889)
		(width 0.16)
		(layer "In5.Cu")
		(net 237)
	)
	(segment
		(start 96.191718 72.029)
		(end 96.641718 71.579)
		(width 0.16)
		(layer "In5.Cu")
		(net 237)
	)
	(segment
		(start 86.158583 73.307584)
		(end 86.158583 73.158583)
		(width 0.16)
		(layer "In5.Cu")
		(net 237)
	)
	(segment
		(start 78.74 76.97)
		(end 78.901 76.809)
		(width 0.16)
		(layer "In5.Cu")
		(net 237)
	)
	(segment
		(start 86.998166 73.745167)
		(end 87.071 73.745167)
		(width 0.16)
		(layer "In5.Cu")
		(net 237)
	)
	(segment
		(start 108.998282 71.579)
		(end 109.809282 72.39)
		(width 0.16)
		(layer "In5.Cu")
		(net 237)
	)
	(segment
		(start 82.409 74.251718)
		(end 83.691718 72.969)
		(width 0.16)
		(layer "In5.Cu")
		(net 237)
	)
	(segment
		(start 78.901 76.809)
		(end 81.551718 76.809)
		(width 0.16)
		(layer "In5.Cu")
		(net 237)
	)
	(segment
		(start 116.881 73.081718)
		(end 116.881 74.191)
		(width 0.16)
		(layer "In5.Cu")
		(net 237)
	)
	(segment
		(start 85.648166 73.795167)
		(end 85.671 73.795167)
		(width 0.16)
		(layer "In5.Cu")
		(net 237)
	)
	(segment
		(start 85.160583 73.158583)
		(end 85.160583 73.307584)
		(width 0.16)
		(layer "In5.Cu")
		(net 237)
	)
	(segment
		(start 86.535583 73.133583)
		(end 86.535583 73.282584)
		(width 0.16)
		(layer "In5.Cu")
		(net 237)
	)
	(segment
		(start 96.641718 71.579)
		(end 108.998282 71.579)
		(width 0.16)
		(layer "In5.Cu")
		(net 237)
	)
	(segment
		(start 87.771 72.969)
		(end 90.141718 72.969)
		(width 0.16)
		(layer "In5.Cu")
		(net 237)
	)
	(arc
		(start 86.371 72.969)
		(mid 86.487378 73.017205)
		(end 86.535583 73.133583)
		(width 0.16)
		(layer "In5.Cu")
		(net 237)
	)
	(arc
		(start 86.158583 73.158583)
		(mid 86.214111 73.024528)
		(end 86.348166 72.969)
		(width 0.16)
		(layer "In5.Cu")
		(net 237)
	)
	(arc
		(start 84.971 72.969)
		(mid 85.105055 73.024528)
		(end 85.160583 73.158583)
		(width 0.16)
		(layer "In5.Cu")
		(net 237)
	)
	(arc
		(start 87.533583 73.133583)
		(mid 87.581788 73.017205)
		(end 87.698166 72.969)
		(width 0.16)
		(layer "In5.Cu")
		(net 237)
	)
	(arc
		(start 85.671 73.795167)
		(mid 86.015773 73.652357)
		(end 86.158583 73.307584)
		(width 0.16)
		(layer "In5.Cu")
		(net 237)
	)
	(arc
		(start 87.071 73.745167)
		(mid 87.398096 73.60968)
		(end 87.533583 73.282584)
		(width 0.16)
		(layer "In5.Cu")
		(net 237)
	)
	(arc
		(start 85.160583 73.307584)
		(mid 85.303393 73.652357)
		(end 85.648166 73.795167)
		(width 0.16)
		(layer "In5.Cu")
		(net 237)
	)
	(arc
		(start 86.535583 73.282584)
		(mid 86.67107 73.60968)
		(end 86.998166 73.745167)
		(width 0.16)
		(layer "In5.Cu")
		(net 237)
	)
	(segment
		(start 79.3795 76.471926)
		(end 79.3795 75.798074)
		(width 0.155)
		(layer "B.Cu")
		(net 237)
	)
	(segment
		(start 118.5032 74.1468)
		(end 119.0093 74.1468)
		(width 0.155)
		(layer "B.Cu")
		(net 237)
	)
	(segment
		(start 79.041926 76.8095)
		(end 79.3795 76.471926)
		(width 0.155)
		(layer "B.Cu")
		(net 237)
	)
	(segment
		(start 79.3795 75.798074)
		(end 78.9045 75.323074)
		(width 0.155)
		(layer "B.Cu")
		(net 237)
	)
	(segment
		(start 117.84 74.81)
		(end 118.5032 74.1468)
		(width 0.155)
		(layer "B.Cu")
		(net 237)
	)
	(segment
		(start 117.5 74.81)
		(end 117.84 74.81)
		(width 0.155)
		(layer "B.Cu")
		(net 237)
	)
	(segment
		(start 78.9045 74.1005)
		(end 79.005 74)
		(width 0.155)
		(layer "B.Cu")
		(net 237)
	)
	(segment
		(start 78.9005 76.8095)
		(end 79.041926 76.8095)
		(width 0.155)
		(layer "B.Cu")
		(net 237)
	)
	(segment
		(start 78.74 76.97)
		(end 78.9005 76.8095)
		(width 0.155)
		(layer "B.Cu")
		(net 237)
	)
	(segment
		(start 78.9045 75.323074)
		(end 78.9045 74.1005)
		(width 0.155)
		(layer "B.Cu")
		(net 237)
	)
	(via
		(at 106.64 74.007)
		(size 0.45)
		(drill 0.1)
		(layers "F.Cu" "B.Cu")
		(net 238)
	)
	(via
		(at 88.94789 75.67789)
		(size 0.45)
		(drill 0.1)
		(layers "F.Cu" "B.Cu")
		(net 238)
	)
	(segment
		(start 89.911718 74.509)
		(end 88.94789 75.472828)
		(width 0.16)
		(layer "In5.Cu")
		(net 238)
	)
	(segment
		(start 98.651135 73.460269)
		(end 98.570865 73.460269)
		(width 0.16)
		(layer "In5.Cu")
		(net 238)
	)
	(segment
		(start 106.492 73.859)
		(end 102.861718 73.859)
		(width 0.16)
		(layer "In5.Cu")
		(net 238)
	)
	(segment
		(start 101.385 74.505)
		(end 101.385 74.823731)
		(width 0.16)
		(layer "In5.Cu")
		(net 238)
	)
	(segment
		(start 98.837 74.823731)
		(end 98.837 73.646134)
		(width 0.16)
		(layer "In5.Cu")
		(net 238)
	)
	(segment
		(start 99.885 73.646134)
		(end 99.885 74.823731)
		(width 0.16)
		(layer "In5.Cu")
		(net 238)
	)
	(segment
		(start 91.431718 74.509)
		(end 89.911718 74.509)
		(width 0.16)
		(layer "In5.Cu")
		(net 238)
	)
	(segment
		(start 91.661718 74.279)
		(end 91.431718 74.509)
		(width 0.16)
		(layer "In5.Cu")
		(net 238)
	)
	(segment
		(start 106.64 74.007)
		(end 106.492 73.859)
		(width 0.16)
		(layer "In5.Cu")
		(net 238)
	)
	(segment
		(start 98.385 73.646134)
		(end 98.385 74.823731)
		(width 0.16)
		(layer "In5.Cu")
		(net 238)
	)
	(segment
		(start 100.337 74.823731)
		(end 100.337 73.646134)
		(width 0.16)
		(layer "In5.Cu")
		(net 238)
	)
	(segment
		(start 91.661718 74.279)
		(end 97.111 74.279)
		(width 0.16)
		(layer "In5.Cu")
		(net 238)
	)
	(segment
		(start 100.151135 73.460269)
		(end 100.070865 73.460269)
		(width 0.16)
		(layer "In5.Cu")
		(net 238)
	)
	(segment
		(start 88.94789 75.472828)
		(end 88.94789 75.67789)
		(width 0.16)
		(layer "In5.Cu")
		(net 238)
	)
	(segment
		(start 102.441718 74.279)
		(end 101.611 74.279)
		(width 0.16)
		(layer "In5.Cu")
		(net 238)
	)
	(segment
		(start 102.861718 73.859)
		(end 102.441718 74.279)
		(width 0.16)
		(layer "In5.Cu")
		(net 238)
	)
	(segment
		(start 97.337 74.823731)
		(end 97.337 74.505)
		(width 0.16)
		(layer "In5.Cu")
		(net 238)
	)
	(arc
		(start 99.885 74.823731)
		(mid 99.731524 75.194255)
		(end 99.361 75.347731)
		(width 0.16)
		(layer "In5.Cu")
		(net 238)
	)
	(arc
		(start 98.570865 73.460269)
		(mid 98.439439 73.514708)
		(end 98.385 73.646134)
		(width 0.16)
		(layer "In5.Cu")
		(net 238)
	)
	(arc
		(start 100.070865 73.460269)
		(mid 99.939439 73.514708)
		(end 99.885 73.646134)
		(width 0.16)
		(layer "In5.Cu")
		(net 238)
	)
	(arc
		(start 98.837 73.646134)
		(mid 98.782561 73.514708)
		(end 98.651135 73.460269)
		(width 0.16)
		(layer "In5.Cu")
		(net 238)
	)
	(arc
		(start 101.385 74.823731)
		(mid 101.231524 75.194255)
		(end 100.861 75.347731)
		(width 0.16)
		(layer "In5.Cu")
		(net 238)
	)
	(arc
		(start 99.361 75.347731)
		(mid 98.990476 75.194255)
		(end 98.837 74.823731)
		(width 0.16)
		(layer "In5.Cu")
		(net 238)
	)
	(arc
		(start 101.611 74.279)
		(mid 101.451194 74.345194)
		(end 101.385 74.505)
		(width 0.16)
		(layer "In5.Cu")
		(net 238)
	)
	(arc
		(start 97.861 75.347731)
		(mid 97.490476 75.194255)
		(end 97.337 74.823731)
		(width 0.16)
		(layer "In5.Cu")
		(net 238)
	)
	(arc
		(start 100.337 73.646134)
		(mid 100.282561 73.514708)
		(end 100.151135 73.460269)
		(width 0.16)
		(layer "In5.Cu")
		(net 238)
	)
	(arc
		(start 98.385 74.823731)
		(mid 98.231524 75.194255)
		(end 97.861 75.347731)
		(width 0.16)
		(layer "In5.Cu")
		(net 238)
	)
	(arc
		(start 100.861 75.347731)
		(mid 100.490476 75.194255)
		(end 100.337 74.823731)
		(width 0.16)
		(layer "In5.Cu")
		(net 238)
	)
	(arc
		(start 97.337 74.505)
		(mid 97.270806 74.345194)
		(end 97.111 74.279)
		(width 0.16)
		(layer "In5.Cu")
		(net 238)
	)
	(segment
		(start 87.6055 74.1005)
		(end 87.6055 75.296926)
		(width 0.155)
		(layer "B.Cu")
		(net 238)
	)
	(segment
		(start 87.505 74)
		(end 87.6055 74.1005)
		(width 0.155)
		(layer "B.Cu")
		(net 238)
	)
	(segment
		(start 88.743535 75.67789)
		(end 88.94789 75.67789)
		(width 0.155)
		(layer "B.Cu")
		(net 238)
	)
	(segment
		(start 87.6055 75.296926)
		(end 88.158074 75.8495)
		(width 0.155)
		(layer "B.Cu")
		(net 238)
	)
	(segment
		(start 88.571925 75.8495)
		(end 88.743535 75.67789)
		(width 0.155)
		(layer "B.Cu")
		(net 238)
	)
	(segment
		(start 107.478074 73.8595)
		(end 106.7875 73.8595)
		(width 0.155)
		(layer "B.Cu")
		(net 238)
	)
	(segment
		(start 108.075374 74.4568)
		(end 107.478074 73.8595)
		(width 0.155)
		(layer "B.Cu")
		(net 238)
	)
	(segment
		(start 106.7875 73.8595)
		(end 106.64 74.007)
		(width 0.155)
		(layer "B.Cu")
		(net 238)
	)
	(segment
		(start 108.3593 74.4568)
		(end 108.075374 74.4568)
		(width 0.155)
		(layer "B.Cu")
		(net 238)
	)
	(segment
		(start 88.158074 75.8495)
		(end 88.571925 75.8495)
		(width 0.155)
		(layer "B.Cu")
		(net 238)
	)
	(via
		(at 106.64 73.413)
		(size 0.45)
		(drill 0.1)
		(layers "F.Cu" "B.Cu")
		(net 239)
	)
	(via
		(at 88.53211 75.26211)
		(size 0.45)
		(drill 0.1)
		(layers "F.Cu" "B.Cu")
		(net 239)
	)
	(segment
		(start 97.635 74.505)
		(end 97.635 74.823731)
		(width 0.16)
		(layer "In5.Cu")
		(net 239)
	)
	(segment
		(start 93.014684 73.715316)
		(end 93.149 73.715316)
		(width 0.16)
		(layer "In5.Cu")
		(net 239)
	)
	(segment
		(start 99.135 73.646134)
		(end 99.135 74.823731)
		(width 0.16)
		(layer "In5.Cu")
		(net 239)
	)
	(segment
		(start 88.737172 75.26211)
		(end 89.788282 74.211)
		(width 0.16)
		(layer "In5.Cu")
		(net 239)
	)
	(segment
		(start 100.070865 73.162269)
		(end 100.151135 73.162269)
		(width 0.16)
		(layer "In5.Cu")
		(net 239)
	)
	(segment
		(start 93.814684 73.715316)
		(end 93.949 73.715316)
		(width 0.16)
		(layer "In5.Cu")
		(net 239)
	)
	(segment
		(start 94.214684 73.981)
		(end 97.111 73.981)
		(width 0.16)
		(layer "In5.Cu")
		(net 239)
	)
	(segment
		(start 93.414684 73.981)
		(end 93.549 73.981)
		(width 0.16)
		(layer "In5.Cu")
		(net 239)
	)
	(segment
		(start 91.538282 73.981)
		(end 92.749 73.981)
		(width 0.16)
		(layer "In5.Cu")
		(net 239)
	)
	(segment
		(start 100.635 73.646134)
		(end 100.635 74.823731)
		(width 0.16)
		(layer "In5.Cu")
		(net 239)
	)
	(segment
		(start 106.492 73.561)
		(end 106.64 73.413)
		(width 0.16)
		(layer "In5.Cu")
		(net 239)
	)
	(segment
		(start 101.611 73.981)
		(end 102.318282 73.981)
		(width 0.16)
		(layer "In5.Cu")
		(net 239)
	)
	(segment
		(start 98.570865 73.162269)
		(end 98.651135 73.162269)
		(width 0.16)
		(layer "In5.Cu")
		(net 239)
	)
	(segment
		(start 99.587 74.823731)
		(end 99.587 73.646134)
		(width 0.16)
		(layer "In5.Cu")
		(net 239)
	)
	(segment
		(start 89.788282 74.211)
		(end 91.308282 74.211)
		(width 0.16)
		(layer "In5.Cu")
		(net 239)
	)
	(segment
		(start 91.308282 74.211)
		(end 91.538282 73.981)
		(width 0.16)
		(layer "In5.Cu")
		(net 239)
	)
	(segment
		(start 102.318282 73.981)
		(end 102.735673 73.563609)
		(width 0.16)
		(layer "In5.Cu")
		(net 239)
	)
	(segment
		(start 98.087 74.823731)
		(end 98.087 73.646134)
		(width 0.16)
		(layer "In5.Cu")
		(net 239)
	)
	(segment
		(start 103.378 73.563609)
		(end 104.842948 73.561)
		(width 0.16)
		(layer "In5.Cu")
		(net 239)
	)
	(segment
		(start 88.53211 75.26211)
		(end 88.737172 75.26211)
		(width 0.16)
		(layer "In5.Cu")
		(net 239)
	)
	(segment
		(start 104.842948 73.561)
		(end 106.492 73.561)
		(width 0.16)
		(layer "In5.Cu")
		(net 239)
	)
	(segment
		(start 101.087 74.823731)
		(end 101.087 74.505)
		(width 0.16)
		(layer "In5.Cu")
		(net 239)
	)
	(segment
		(start 102.735673 73.563609)
		(end 103.378 73.563609)
		(width 0.16)
		(layer "In5.Cu")
		(net 239)
	)
	(arc
		(start 97.635 74.823731)
		(mid 97.701194 74.983537)
		(end 97.861 75.049731)
		(width 0.16)
		(layer "In5.Cu")
		(net 239)
	)
	(arc
		(start 101.087 74.505)
		(mid 101.240476 74.134476)
		(end 101.611 73.981)
		(width 0.16)
		(layer "In5.Cu")
		(net 239)
	)
	(arc
		(start 93.681842 73.848158)
		(mid 93.720751 73.754225)
		(end 93.814684 73.715316)
		(width 0.16)
		(layer "In5.Cu")
		(net 239)
	)
	(arc
		(start 98.651135 73.162269)
		(mid 98.993279 73.30399)
		(end 99.135 73.646134)
		(width 0.16)
		(layer "In5.Cu")
		(net 239)
	)
	(arc
		(start 92.749 73.981)
		(mid 92.842933 73.942091)
		(end 92.881842 73.848158)
		(width 0.16)
		(layer "In5.Cu")
		(net 239)
	)
	(arc
		(start 93.281842 73.848158)
		(mid 93.320751 73.942091)
		(end 93.414684 73.981)
		(width 0.16)
		(layer "In5.Cu")
		(net 239)
	)
	(arc
		(start 99.587 73.646134)
		(mid 99.728721 73.30399)
		(end 100.070865 73.162269)
		(width 0.16)
		(layer "In5.Cu")
		(net 239)
	)
	(arc
		(start 93.949 73.715316)
		(mid 94.042933 73.754225)
		(end 94.081842 73.848158)
		(width 0.16)
		(layer "In5.Cu")
		(net 239)
	)
	(arc
		(start 100.861 75.049731)
		(mid 101.020806 74.983537)
		(end 101.087 74.823731)
		(width 0.16)
		(layer "In5.Cu")
		(net 239)
	)
	(arc
		(start 94.081842 73.848158)
		(mid 94.120751 73.942091)
		(end 94.214684 73.981)
		(width 0.16)
		(layer "In5.Cu")
		(net 239)
	)
	(arc
		(start 99.135 74.823731)
		(mid 99.201194 74.983537)
		(end 99.361 75.049731)
		(width 0.16)
		(layer "In5.Cu")
		(net 239)
	)
	(arc
		(start 100.151135 73.162269)
		(mid 100.493279 73.30399)
		(end 100.635 73.646134)
		(width 0.16)
		(layer "In5.Cu")
		(net 239)
	)
	(arc
		(start 93.549 73.981)
		(mid 93.642933 73.942091)
		(end 93.681842 73.848158)
		(width 0.16)
		(layer "In5.Cu")
		(net 239)
	)
	(arc
		(start 97.861 75.049731)
		(mid 98.020806 74.983537)
		(end 98.087 74.823731)
		(width 0.16)
		(layer "In5.Cu")
		(net 239)
	)
	(arc
		(start 99.361 75.049731)
		(mid 99.520806 74.983537)
		(end 99.587 74.823731)
		(width 0.16)
		(layer "In5.Cu")
		(net 239)
	)
	(arc
		(start 92.881842 73.848158)
		(mid 92.920751 73.754225)
		(end 93.014684 73.715316)
		(width 0.16)
		(layer "In5.Cu")
		(net 239)
	)
	(arc
		(start 98.087 73.646134)
		(mid 98.228721 73.30399)
		(end 98.570865 73.162269)
		(width 0.16)
		(layer "In5.Cu")
		(net 239)
	)
	(arc
		(start 100.635 74.823731)
		(mid 100.701194 74.983537)
		(end 100.861 75.049731)
		(width 0.16)
		(layer "In5.Cu")
		(net 239)
	)
	(arc
		(start 97.111 73.981)
		(mid 97.481524 74.134476)
		(end 97.635 74.505)
		(width 0.16)
		(layer "In5.Cu")
		(net 239)
	)
	(arc
		(start 93.149 73.715316)
		(mid 93.242933 73.754225)
		(end 93.281842 73.848158)
		(width 0.16)
		(layer "In5.Cu")
		(net 239)
	)
	(segment
		(start 108.0948 74.0504)
		(end 108.0885 74.0441)
		(width 0.155)
		(layer "B.Cu")
		(net 239)
	)
	(segment
		(start 107.601926 73.5605)
		(end 106.7875 73.5605)
		(width 0.155)
		(layer "B.Cu")
		(net 239)
	)
	(segment
		(start 88.005 74)
		(end 87.9045 74.1005)
		(width 0.155)
		(layer "B.Cu")
		(net 239)
	)
	(segment
		(start 88.448075 75.5505)
		(end 88.53211 75.466465)
		(width 0.155)
		(layer "B.Cu")
		(net 239)
	)
	(segment
		(start 108.0885 74.0441)
		(end 108.085526 74.0441)
		(width 0.155)
		(layer "B.Cu")
		(net 239)
	)
	(segment
		(start 87.9045 74.1005)
		(end 87.9045 75.173074)
		(width 0.155)
		(layer "B.Cu")
		(net 239)
	)
	(segment
		(start 106.7875 73.5605)
		(end 106.64 73.413)
		(width 0.155)
		(layer "B.Cu")
		(net 239)
	)
	(segment
		(start 88.53211 75.466465)
		(end 88.53211 75.26211)
		(width 0.155)
		(layer "B.Cu")
		(net 239)
	)
	(segment
		(start 108.3593 74.0504)
		(end 108.0948 74.0504)
		(width 0.155)
		(layer "B.Cu")
		(net 239)
	)
	(segment
		(start 88.281926 75.5505)
		(end 88.448075 75.5505)
		(width 0.155)
		(layer "B.Cu")
		(net 239)
	)
	(segment
		(start 87.9045 75.173074)
		(end 88.281926 75.5505)
		(width 0.155)
		(layer "B.Cu")
		(net 239)
	)
	(segment
		(start 108.085526 74.0441)
		(end 107.601926 73.5605)
		(width 0.155)
		(layer "B.Cu")
		(net 239)
	)
	(via
		(at 90.87789 77.37789)
		(size 0.45)
		(drill 0.1)
		(layers "F.Cu" "B.Cu")
		(net 240)
	)
	(via
		(at 106.64 75.02)
		(size 0.45)
		(drill 0.1)
		(layers "F.Cu" "B.Cu")
		(net 240)
	)
	(segment
		(start 92.041718 76.009)
		(end 96.898282 76.009)
		(width 0.16)
		(layer "In5.Cu")
		(net 240)
	)
	(segment
		(start 103.452718 74.808)
		(end 106.428 74.808)
		(width 0.16)
		(layer "In5.Cu")
		(net 240)
	)
	(segment
		(start 90.87789 77.172828)
		(end 92.041718 76.009)
		(width 0.16)
		(layer "In5.Cu")
		(net 240)
	)
	(segment
		(start 90.87789 77.37789)
		(end 90.87789 77.172828)
		(width 0.16)
		(layer "In5.Cu")
		(net 240)
	)
	(segment
		(start 97.638282 76.749)
		(end 101.511718 76.749)
		(width 0.16)
		(layer "In5.Cu")
		(net 240)
	)
	(segment
		(start 96.898282 76.009)
		(end 97.638282 76.749)
		(width 0.16)
		(layer "In5.Cu")
		(net 240)
	)
	(segment
		(start 106.428 74.808)
		(end 106.64 75.02)
		(width 0.16)
		(layer "In5.Cu")
		(net 240)
	)
	(segment
		(start 101.511718 76.749)
		(end 103.452718 74.808)
		(width 0.16)
		(layer "In5.Cu")
		(net 240)
	)
	(segment
		(start 90.673535 77.37789)
		(end 90.87789 77.37789)
		(width 0.155)
		(layer "B.Cu")
		(net 240)
	)
	(segment
		(start 89.868074 77.4995)
		(end 90.551925 77.4995)
		(width 0.155)
		(layer "B.Cu")
		(net 240)
	)
	(segment
		(start 90.551925 77.4995)
		(end 90.673535 77.37789)
		(width 0.155)
		(layer "B.Cu")
		(net 240)
	)
	(segment
		(start 88.505 74)
		(end 88.6055 74.1005)
		(width 0.155)
		(layer "B.Cu")
		(net 240)
	)
	(segment
		(start 107.837449 75.1559)
		(end 107.951149 75.2696)
		(width 0.155)
		(layer "B.Cu")
		(net 240)
	)
	(segment
		(start 88.6055 74.716926)
		(end 89.5105 75.621926)
		(width 0.155)
		(layer "B.Cu")
		(net 240)
	)
	(segment
		(start 107.024475 75.1559)
		(end 107.837449 75.1559)
		(width 0.155)
		(layer "B.Cu")
		(net 240)
	)
	(segment
		(start 88.6055 74.1005)
		(end 88.6055 74.716926)
		(width 0.155)
		(layer "B.Cu")
		(net 240)
	)
	(segment
		(start 89.5105 75.621926)
		(end 89.5105 77.141926)
		(width 0.155)
		(layer "B.Cu")
		(net 240)
	)
	(segment
		(start 89.5105 77.141926)
		(end 89.868074 77.4995)
		(width 0.155)
		(layer "B.Cu")
		(net 240)
	)
	(segment
		(start 106.64 75.02)
		(end 106.888575 75.02)
		(width 0.155)
		(layer "B.Cu")
		(net 240)
	)
	(segment
		(start 107.951149 75.2696)
		(end 108.3593 75.2696)
		(width 0.155)
		(layer "B.Cu")
		(net 240)
	)
	(segment
		(start 106.888575 75.02)
		(end 107.024475 75.1559)
		(width 0.155)
		(layer "B.Cu")
		(net 240)
	)
	(via
		(at 90.46211 76.96211)
		(size 0.45)
		(drill 0.1)
		(layers "F.Cu" "B.Cu")
		(net 241)
	)
	(via
		(at 106.94 74.51)
		(size 0.45)
		(drill 0.1)
		(layers "F.Cu" "B.Cu")
		(net 241)
	)
	(segment
		(start 90.667172 76.96211)
		(end 91.918282 75.711)
		(width 0.16)
		(layer "In5.Cu")
		(net 241)
	)
	(segment
		(start 90.46211 76.96211)
		(end 90.667172 76.96211)
		(width 0.16)
		(layer "In5.Cu")
		(net 241)
	)
	(segment
		(start 93.202914 75.711)
		(end 93.4 75.711)
		(width 0.16)
		(layer "In5.Cu")
		(net 241)
	)
	(segment
		(start 93.4 75.711)
		(end 97.021718 75.711)
		(width 0.16)
		(layer "In5.Cu")
		(net 241)
	)
	(segment
		(start 97.761718 76.451)
		(end 101.388282 76.451)
		(width 0.16)
		(layer "In5.Cu")
		(net 241)
	)
	(segment
		(start 97.021718 75.711)
		(end 97.761718 76.451)
		(width 0.16)
		(layer "In5.Cu")
		(net 241)
	)
	(segment
		(start 103.329282 74.51)
		(end 106.94 74.51)
		(width 0.16)
		(layer "In5.Cu")
		(net 241)
	)
	(segment
		(start 101.388282 76.451)
		(end 103.329282 74.51)
		(width 0.16)
		(layer "In5.Cu")
		(net 241)
	)
	(segment
		(start 91.918282 75.711)
		(end 92.2 75.711)
		(width 0.16)
		(layer "In5.Cu")
		(net 241)
	)
	(segment
		(start 92.602914 75.308086)
		(end 92.8 75.308086)
		(width 0.16)
		(layer "In5.Cu")
		(net 241)
	)
	(arc
		(start 93.001457 75.509543)
		(mid 93.060462 75.651995)
		(end 93.202914 75.711)
		(width 0.16)
		(layer "In5.Cu")
		(net 241)
	)
	(arc
		(start 92.401457 75.509543)
		(mid 92.460462 75.367091)
		(end 92.602914 75.308086)
		(width 0.16)
		(layer "In5.Cu")
		(net 241)
	)
	(arc
		(start 92.8 75.308086)
		(mid 92.942452 75.367091)
		(end 93.001457 75.509543)
		(width 0.16)
		(layer "In5.Cu")
		(net 241)
	)
	(arc
		(start 92.2 75.711)
		(mid 92.342452 75.651995)
		(end 92.401457 75.509543)
		(width 0.16)
		(layer "In5.Cu")
		(net 241)
	)
	(segment
		(start 107.843749 74.8632)
		(end 108.3593 74.8632)
		(width 0.155)
		(layer "B.Cu")
		(net 241)
	)
	(segment
		(start 89.005 74)
		(end 88.9045 74.1005)
		(width 0.155)
		(layer "B.Cu")
		(net 241)
	)
	(segment
		(start 90.46211 77.166465)
		(end 90.46211 76.96211)
		(width 0.155)
		(layer "B.Cu")
		(net 241)
	)
	(segment
		(start 90.428075 77.2005)
		(end 90.46211 77.166465)
		(width 0.155)
		(layer "B.Cu")
		(net 241)
	)
	(segment
		(start 106.94 74.648575)
		(end 107.148325 74.8569)
		(width 0.155)
		(layer "B.Cu")
		(net 241)
	)
	(segment
		(start 107.837449 74.8569)
		(end 107.843749 74.8632)
		(width 0.155)
		(layer "B.Cu")
		(net 241)
	)
	(segment
		(start 107.148325 74.8569)
		(end 107.837449 74.8569)
		(width 0.155)
		(layer "B.Cu")
		(net 241)
	)
	(segment
		(start 89.991926 77.2005)
		(end 90.428075 77.2005)
		(width 0.155)
		(layer "B.Cu")
		(net 241)
	)
	(segment
		(start 89.8095 75.498074)
		(end 89.8095 77.018074)
		(width 0.155)
		(layer "B.Cu")
		(net 241)
	)
	(segment
		(start 88.9045 74.593074)
		(end 89.8095 75.498074)
		(width 0.155)
		(layer "B.Cu")
		(net 241)
	)
	(segment
		(start 88.9045 74.1005)
		(end 88.9045 74.593074)
		(width 0.155)
		(layer "B.Cu")
		(net 241)
	)
	(segment
		(start 89.8095 77.018074)
		(end 89.991926 77.2005)
		(width 0.155)
		(layer "B.Cu")
		(net 241)
	)
	(segment
		(start 106.94 74.51)
		(end 106.94 74.648575)
		(width 0.155)
		(layer "B.Cu")
		(net 241)
	)
	(segment
		(start 69.69 82.79)
		(end 69.69 84.12)
		(width 0.125)
		(layer "F.Cu")
		(net 242)
	)
	(segment
		(start 69.69 84.12)
		(end 69.43 84.38)
		(width 0.125)
		(layer "F.Cu")
		(net 242)
	)
	(via
		(at 69.43 84.38)
		(size 0.45)
		(drill 0.1)
		(layers "F.Cu" "B.Cu")
		(net 242)
	)
	(segment
		(start 69.43 84.38)
		(end 68.67 84.38)
		(width 0.155)
		(layer "B.Cu")
		(net 242)
	)
	(segment
		(start 68.395 84.655)
		(end 68.395 85.05)
		(width 0.155)
		(layer "B.Cu")
		(net 242)
	)
	(segment
		(start 68.67 84.38)
		(end 68.395 84.655)
		(width 0.155)
		(layer "B.Cu")
		(net 242)
	)
	(segment
		(start 66 85.17)
		(end 67.46 85.17)
		(width 0.125)
		(layer "F.Cu")
		(net 243)
	)
	(segment
		(start 67.46 85.17)
		(end 67.79 85.5)
		(width 0.125)
		(layer "F.Cu")
		(net 243)
	)
	(via
		(at 66 85.17)
		(size 0.45)
		(drill 0.1)
		(layers "F.Cu" "B.Cu")
		(net 243)
	)
	(segment
		(start 66.12 85.05)
		(end 67.805 85.05)
		(width 0.125)
		(layer "B.Cu")
		(net 243)
	)
	(segment
		(start 66 85.17)
		(end 66.12 85.05)
		(width 0.125)
		(layer "B.Cu")
		(net 243)
	)
	(via
		(at 127.935 89.315)
		(size 0.45)
		(drill 0.1)
		(layers "F.Cu" "B.Cu")
		(net 244)
	)
	(via
		(at 119.35 86.255)
		(size 0.45)
		(drill 0.1)
		(layers "F.Cu" "B.Cu")
		(net 244)
	)
	(segment
		(start 128.22 89.03)
		(end 128.96 89.03)
		(width 0.125)
		(layer "In1.Cu")
		(net 244)
	)
	(segment
		(start 122.52 83.85)
		(end 121.375 83.85)
		(width 0.125)
		(layer "In1.Cu")
		(net 244)
	)
	(segment
		(start 127.935 89.315)
		(end 128.22 89.03)
		(width 0.125)
		(layer "In1.Cu")
		(net 244)
	)
	(segment
		(start 128.96 89.03)
		(end 129.805 88.185)
		(width 0.125)
		(layer "In1.Cu")
		(net 244)
	)
	(segment
		(start 127.615 85.475)
		(end 126.145 84.005)
		(width 0.125)
		(layer "In1.Cu")
		(net 244)
	)
	(segment
		(start 120.095 86.255)
		(end 119.35 86.255)
		(width 0.125)
		(layer "In1.Cu")
		(net 244)
	)
	(segment
		(start 120.48 84.745)
		(end 120.48 85.87)
		(width 0.125)
		(layer "In1.Cu")
		(net 244)
	)
	(segment
		(start 129.805 86.195)
		(end 129.085 85.475)
		(width 0.125)
		(layer "In1.Cu")
		(net 244)
	)
	(segment
		(start 126.145 84.005)
		(end 122.675 84.005)
		(width 0.125)
		(layer "In1.Cu")
		(net 244)
	)
	(segment
		(start 129.805 88.185)
		(end 129.805 86.195)
		(width 0.125)
		(layer "In1.Cu")
		(net 244)
	)
	(segment
		(start 121.375 83.85)
		(end 120.48 84.745)
		(width 0.125)
		(layer "In1.Cu")
		(net 244)
	)
	(segment
		(start 122.675 84.005)
		(end 122.52 83.85)
		(width 0.125)
		(layer "In1.Cu")
		(net 244)
	)
	(segment
		(start 120.48 85.87)
		(end 120.095 86.255)
		(width 0.125)
		(layer "In1.Cu")
		(net 244)
	)
	(segment
		(start 129.085 85.475)
		(end 127.615 85.475)
		(width 0.125)
		(layer "In1.Cu")
		(net 244)
	)
	(segment
		(start 119.348 86.253)
		(end 119.35 86.255)
		(width 0.125)
		(layer "B.Cu")
		(net 244)
	)
	(segment
		(start 129.4392 88.8208)
		(end 129.18 89.08)
		(width 0.125)
		(layer "B.Cu")
		(net 244)
	)
	(segment
		(start 129.18 89.08)
		(end 128.17 89.08)
		(width 0.125)
		(layer "B.Cu")
		(net 244)
	)
	(segment
		(start 130.085 88.8208)
		(end 129.4392 88.8208)
		(width 0.125)
		(layer "B.Cu")
		(net 244)
	)
	(segment
		(start 128.17 89.08)
		(end 127.935 89.315)
		(width 0.125)
		(layer "B.Cu")
		(net 244)
	)
	(segment
		(start 116.818 86.253)
		(end 119.348 86.253)
		(width 0.125)
		(layer "B.Cu")
		(net 244)
	)
	(via
		(at 127.77 88.755)
		(size 0.45)
		(drill 0.1)
		(layers "F.Cu" "B.Cu")
		(net 245)
	)
	(via
		(at 118.275 85.475)
		(size 0.45)
		(drill 0.1)
		(layers "F.Cu" "B.Cu")
		(net 245)
	)
	(segment
		(start 128.85 88.755)
		(end 129.54 88.065)
		(width 0.125)
		(layer "In1.Cu")
		(net 245)
	)
	(segment
		(start 118.27 85.475)
		(end 118.275 85.475)
		(width 0.125)
		(layer "In1.Cu")
		(net 245)
	)
	(segment
		(start 121.47 84.13)
		(end 120.755 84.845)
		(width 0.125)
		(layer "In1.Cu")
		(net 245)
	)
	(segment
		(start 126.02 84.28)
		(end 122.545 84.28)
		(width 0.125)
		(layer "In1.Cu")
		(net 245)
	)
	(segment
		(start 127.495 85.755)
		(end 126.02 84.28)
		(width 0.125)
		(layer "In1.Cu")
		(net 245)
	)
	(segment
		(start 122.395 84.13)
		(end 121.47 84.13)
		(width 0.125)
		(layer "In1.Cu")
		(net 245)
	)
	(segment
		(start 120.755 86.07)
		(end 120.145 86.68)
		(width 0.125)
		(layer "In1.Cu")
		(net 245)
	)
	(segment
		(start 118.275 85.805)
		(end 118.275 85.475)
		(width 0.125)
		(layer "In1.Cu")
		(net 245)
	)
	(segment
		(start 122.545 84.28)
		(end 122.395 84.13)
		(width 0.125)
		(layer "In1.Cu")
		(net 245)
	)
	(segment
		(start 129.54 86.34)
		(end 128.955 85.755)
		(width 0.125)
		(layer "In1.Cu")
		(net 245)
	)
	(segment
		(start 127.77 88.755)
		(end 128.85 88.755)
		(width 0.125)
		(layer "In1.Cu")
		(net 245)
	)
	(segment
		(start 128.955 85.755)
		(end 127.495 85.755)
		(width 0.125)
		(layer "In1.Cu")
		(net 245)
	)
	(segment
		(start 120.755 84.845)
		(end 120.755 86.07)
		(width 0.125)
		(layer "In1.Cu")
		(net 245)
	)
	(segment
		(start 120.145 86.68)
		(end 119.15 86.68)
		(width 0.125)
		(layer "In1.Cu")
		(net 245)
	)
	(segment
		(start 119.15 86.68)
		(end 118.275 85.805)
		(width 0.125)
		(layer "In1.Cu")
		(net 245)
	)
	(segment
		(start 129.54 88.065)
		(end 129.54 86.34)
		(width 0.125)
		(layer "In1.Cu")
		(net 245)
	)
	(segment
		(start 117.997 85.753)
		(end 118.275 85.475)
		(width 0.125)
		(layer "B.Cu")
		(net 245)
	)
	(segment
		(start 129.1 88.755)
		(end 130.085 87.77)
		(width 0.125)
		(layer "B.Cu")
		(net 245)
	)
	(segment
		(start 116.818 85.753)
		(end 117.997 85.753)
		(width 0.125)
		(layer "B.Cu")
		(net 245)
	)
	(segment
		(start 127.77 88.755)
		(end 129.1 88.755)
		(width 0.125)
		(layer "B.Cu")
		(net 245)
	)
	(via
		(at 118.3 84.785)
		(size 0.45)
		(drill 0.1)
		(layers "F.Cu" "B.Cu")
		(net 246)
	)
	(via
		(at 127.885 88.185)
		(size 0.45)
		(drill 0.1)
		(layers "F.Cu" "B.Cu")
		(net 246)
	)
	(segment
		(start 129.265 86.465)
		(end 128.81 86.01)
		(width 0.125)
		(layer "In1.Cu")
		(net 246)
	)
	(segment
		(start 122.265 84.41)
		(end 121.58 84.41)
		(width 0.125)
		(layer "In1.Cu")
		(net 246)
	)
	(segment
		(start 117.875 85.21)
		(end 118.3 84.785)
		(width 0.125)
		(layer "In1.Cu")
		(net 246)
	)
	(segment
		(start 127.885 88.185)
		(end 128.205 88.505)
		(width 0.125)
		(layer "In1.Cu")
		(net 246)
	)
	(segment
		(start 127.255 86.01)
		(end 125.795 84.55)
		(width 0.125)
		(layer "In1.Cu")
		(net 246)
	)
	(segment
		(start 128.695 88.505)
		(end 129.265 87.935)
		(width 0.125)
		(layer "In1.Cu")
		(net 246)
	)
	(segment
		(start 118.905 86.97)
		(end 117.8 85.865)
		(width 0.125)
		(layer "In1.Cu")
		(net 246)
	)
	(segment
		(start 120.265 86.97)
		(end 118.905 86.97)
		(width 0.125)
		(layer "In1.Cu")
		(net 246)
	)
	(segment
		(start 125.795 84.55)
		(end 122.405 84.55)
		(width 0.125)
		(layer "In1.Cu")
		(net 246)
	)
	(segment
		(start 121.045 86.19)
		(end 120.265 86.97)
		(width 0.125)
		(layer "In1.Cu")
		(net 246)
	)
	(segment
		(start 128.205 88.505)
		(end 128.695 88.505)
		(width 0.125)
		(layer "In1.Cu")
		(net 246)
	)
	(segment
		(start 122.405 84.55)
		(end 122.265 84.41)
		(width 0.125)
		(layer "In1.Cu")
		(net 246)
	)
	(segment
		(start 121.045 84.945)
		(end 121.045 86.19)
		(width 0.125)
		(layer "In1.Cu")
		(net 246)
	)
	(segment
		(start 117.875 85.215)
		(end 117.875 85.21)
		(width 0.125)
		(layer "In1.Cu")
		(net 246)
	)
	(segment
		(start 117.8 85.29)
		(end 117.875 85.215)
		(width 0.125)
		(layer "In1.Cu")
		(net 246)
	)
	(segment
		(start 121.58 84.41)
		(end 121.045 84.945)
		(width 0.125)
		(layer "In1.Cu")
		(net 246)
	)
	(segment
		(start 117.8 85.865)
		(end 117.8 85.29)
		(width 0.125)
		(layer "In1.Cu")
		(net 246)
	)
	(segment
		(start 128.81 86.01)
		(end 127.255 86.01)
		(width 0.125)
		(layer "In1.Cu")
		(net 246)
	)
	(segment
		(start 129.265 87.935)
		(end 129.265 86.465)
		(width 0.125)
		(layer "In1.Cu")
		(net 246)
	)
	(segment
		(start 129.39 87.365001)
		(end 130.085 86.670001)
		(width 0.125)
		(layer "B.Cu")
		(net 246)
	)
	(segment
		(start 127.885 88.185)
		(end 128.18 88.48)
		(width 0.125)
		(layer "B.Cu")
		(net 246)
	)
	(segment
		(start 129.39 88.035)
		(end 129.39 87.365001)
		(width 0.125)
		(layer "B.Cu")
		(net 246)
	)
	(segment
		(start 117.833 85.252)
		(end 118.3 84.785)
		(width 0.125)
		(layer "B.Cu")
		(net 246)
	)
	(segment
		(start 128.18 88.48)
		(end 128.945 88.48)
		(width 0.125)
		(layer "B.Cu")
		(net 246)
	)
	(segment
		(start 128.945 88.48)
		(end 129.39 88.035)
		(width 0.125)
		(layer "B.Cu")
		(net 246)
	)
	(segment
		(start 116.818 85.252)
		(end 117.833 85.252)
		(width 0.125)
		(layer "B.Cu")
		(net 246)
	)
	(segment
		(start 112.92 86.75)
		(end 115.92 83.75)
		(width 0.15)
		(layer "B.Cu")
		(net 247)
	)
	(segment
		(start 115.92 83.75)
		(end 116.775 83.75)
		(width 0.15)
		(layer "B.Cu")
		(net 247)
	)
	(segment
		(start 110.98 88.69)
		(end 110.98 87.76)
		(width 0.15)
		(layer "B.Cu")
		(net 247)
	)
	(segment
		(start 110.7 88.97)
		(end 110.98 88.69)
		(width 0.15)
		(layer "B.Cu")
		(net 247)
	)
	(segment
		(start 111.9 86.75)
		(end 112.92 86.75)
		(width 0.15)
		(layer "B.Cu")
		(net 247)
	)
	(segment
		(start 106.935 90.305)
		(end 107.66 89.58)
		(width 0.15)
		(layer "B.Cu")
		(net 247)
	)
	(segment
		(start 106.4 90.305)
		(end 106.935 90.305)
		(width 0.15)
		(layer "B.Cu")
		(net 247)
	)
	(segment
		(start 111.6 87.535)
		(end 111.6 87.05)
		(width 0.15)
		(layer "B.Cu")
		(net 247)
	)
	(segment
		(start 108.93 89.58)
		(end 109.54 88.97)
		(width 0.15)
		(layer "B.Cu")
		(net 247)
	)
	(segment
		(start 107.66 89.58)
		(end 108.93 89.58)
		(width 0.15)
		(layer "B.Cu")
		(net 247)
	)
	(segment
		(start 111.6 87.05)
		(end 111.9 86.75)
		(width 0.15)
		(layer "B.Cu")
		(net 247)
	)
	(segment
		(start 110.2 88.97)
		(end 110.7 88.97)
		(width 0.15)
		(layer "B.Cu")
		(net 247)
	)
	(segment
		(start 111.205 87.535)
		(end 111.6 87.535)
		(width 0.15)
		(layer "B.Cu")
		(net 247)
	)
	(segment
		(start 110.98 87.76)
		(end 111.205 87.535)
		(width 0.15)
		(layer "B.Cu")
		(net 247)
	)
	(segment
		(start 109.54 88.97)
		(end 110.2 88.97)
		(width 0.15)
		(layer "B.Cu")
		(net 247)
	)
	(via
		(at 108.25 86.15)
		(size 0.45)
		(drill 0.1)
		(layers "F.Cu" "B.Cu")
		(net 248)
	)
	(via
		(at 108.4 93.4)
		(size 0.45)
		(drill 0.1)
		(layers "F.Cu" "B.Cu")
		(net 248)
	)
	(segment
		(start 107.75 86.575)
		(end 107.75 88.9)
		(width 0.15)
		(layer "In5.Cu")
		(net 248)
	)
	(segment
		(start 107.3 89.35)
		(end 107.3 92.925)
		(width 0.15)
		(layer "In5.Cu")
		(net 248)
	)
	(segment
		(start 108.175 86.15)
		(end 107.75 86.575)
		(width 0.15)
		(layer "In5.Cu")
		(net 248)
	)
	(segment
		(start 107.775 93.4)
		(end 108.4 93.4)
		(width 0.15)
		(layer "In5.Cu")
		(net 248)
	)
	(segment
		(start 107.75 88.9)
		(end 107.3 89.35)
		(width 0.15)
		(layer "In5.Cu")
		(net 248)
	)
	(segment
		(start 108.25 86.15)
		(end 108.175 86.15)
		(width 0.15)
		(layer "In5.Cu")
		(net 248)
	)
	(segment
		(start 107.3 92.925)
		(end 107.775 93.4)
		(width 0.15)
		(layer "In5.Cu")
		(net 248)
	)
	(segment
		(start 116.775 83.25)
		(end 115.44 83.25)
		(width 0.15)
		(layer "B.Cu")
		(net 248)
	)
	(segment
		(start 109.485 86.585)
		(end 109.485 86.955)
		(width 0.15)
		(layer "B.Cu")
		(net 248)
	)
	(segment
		(start 112.89 85.8)
		(end 111.6 85.8)
		(width 0.15)
		(layer "B.Cu")
		(net 248)
	)
	(segment
		(start 109.485 86.955)
		(end 109.6 87.07)
		(width 0.15)
		(layer "B.Cu")
		(net 248)
	)
	(segment
		(start 107.97 92.97)
		(end 108.4 93.4)
		(width 0.15)
		(layer "B.Cu")
		(net 248)
	)
	(segment
		(start 109.485 85.42)
		(end 109.485 86.585)
		(width 0.15)
		(layer "B.Cu")
		(net 248)
	)
	(segment
		(start 108.685 86.585)
		(end 109.485 86.585)
		(width 0.15)
		(layer "B.Cu")
		(net 248)
	)
	(segment
		(start 108.25 86.15)
		(end 108.685 86.585)
		(width 0.15)
		(layer "B.Cu")
		(net 248)
	)
	(segment
		(start 115.44 83.25)
		(end 112.89 85.8)
		(width 0.15)
		(layer "B.Cu")
		(net 248)
	)
	(segment
		(start 109.6 87.07)
		(end 110.2 87.07)
		(width 0.15)
		(layer "B.Cu")
		(net 248)
	)
	(segment
		(start 107.8 92.97)
		(end 106.535 92.97)
		(width 0.15)
		(layer "B.Cu")
		(net 248)
	)
	(segment
		(start 111.6 85.8)
		(end 110.33 87.07)
		(width 0.15)
		(layer "B.Cu")
		(net 248)
	)
	(via
		(at 109.6 89.7)
		(size 0.45)
		(drill 0.1)
		(layers "F.Cu" "B.Cu")
		(net 249)
	)
	(via
		(at 108.4 84)
		(size 0.45)
		(drill 0.1)
		(layers "F.Cu" "B.Cu")
		(net 249)
	)
	(segment
		(start 108.725 86.375)
		(end 108.725 85.925)
		(width 0.15)
		(layer "In5.Cu")
		(net 249)
	)
	(segment
		(start 108.725 85.925)
		(end 108.4 85.6)
		(width 0.15)
		(layer "In5.Cu")
		(net 249)
	)
	(segment
		(start 108.125 87.975)
		(end 108.125 86.975)
		(width 0.15)
		(layer "In5.Cu")
		(net 249)
	)
	(segment
		(start 108.75 88.2)
		(end 108.35 88.2)
		(width 0.15)
		(layer "In5.Cu")
		(net 249)
	)
	(segment
		(start 108.125 86.975)
		(end 108.725 86.375)
		(width 0.15)
		(layer "In5.Cu")
		(net 249)
	)
	(segment
		(start 109.6 89.7)
		(end 109.15 89.7)
		(width 0.15)
		(layer "In5.Cu")
		(net 249)
	)
	(segment
		(start 108.4 85.6)
		(end 108.4 84)
		(width 0.15)
		(layer "In5.Cu")
		(net 249)
	)
	(segment
		(start 109.025 89.575)
		(end 109.025 88.475)
		(width 0.15)
		(layer "In5.Cu")
		(net 249)
	)
	(segment
		(start 109.025 88.475)
		(end 108.75 88.2)
		(width 0.15)
		(layer "In5.Cu")
		(net 249)
	)
	(segment
		(start 109.15 89.7)
		(end 109.025 89.575)
		(width 0.15)
		(layer "In5.Cu")
		(net 249)
	)
	(segment
		(start 108.35 88.2)
		(end 108.125 87.975)
		(width 0.15)
		(layer "In5.Cu")
		(net 249)
	)
	(segment
		(start 109.6 90.1)
		(end 108.63 91.07)
		(width 0.15)
		(layer "B.Cu")
		(net 249)
	)
	(segment
		(start 115.25 82.75)
		(end 116.775 82.75)
		(width 0.15)
		(layer "B.Cu")
		(net 249)
	)
	(segment
		(start 110.3 85.4)
		(end 112.6 85.4)
		(width 0.15)
		(layer "B.Cu")
		(net 249)
	)
	(segment
		(start 108.4 84)
		(end 108.9 84)
		(width 0.15)
		(layer "B.Cu")
		(net 249)
	)
	(segment
		(start 109.6 89.7)
		(end 109.6 90.1)
		(width 0.15)
		(layer "B.Cu")
		(net 249)
	)
	(segment
		(start 108.63 91.07)
		(end 107.8 91.07)
		(width 0.15)
		(layer "B.Cu")
		(net 249)
	)
	(segment
		(start 109.765 89.535)
		(end 111.6 89.535)
		(width 0.15)
		(layer "B.Cu")
		(net 249)
	)
	(segment
		(start 109.6 89.7)
		(end 109.765 89.535)
		(width 0.15)
		(layer "B.Cu")
		(net 249)
	)
	(segment
		(start 112.6 85.4)
		(end 115.25 82.75)
		(width 0.15)
		(layer "B.Cu")
		(net 249)
	)
	(segment
		(start 108.9 84)
		(end 110.3 85.4)
		(width 0.15)
		(layer "B.Cu")
		(net 249)
	)
	(segment
		(start 113.95 79.4)
		(end 112.985 80.365)
		(width 0.15)
		(layer "B.Cu")
		(net 250)
	)
	(segment
		(start 116.775 79.25)
		(end 115.85 79.25)
		(width 0.15)
		(layer "B.Cu")
		(net 250)
	)
	(segment
		(start 115.85 79.25)
		(end 115.7 79.4)
		(width 0.15)
		(layer "B.Cu")
		(net 250)
	)
	(segment
		(start 115.7 79.4)
		(end 113.95 79.4)
		(width 0.15)
		(layer "B.Cu")
		(net 250)
	)
	(segment
		(start 130.95 107.65)
		(end 131.315 107.65)
		(width 0.15)
		(layer "F.Cu")
		(net 251)
	)
	(segment
		(start 138.225 107.6)
		(end 137.8 107.175)
		(width 0.15)
		(layer "F.Cu")
		(net 251)
	)
	(segment
		(start 130.5 108.1)
		(end 130.95 107.65)
		(width 0.15)
		(layer "F.Cu")
		(net 251)
	)
	(segment
		(start 110.8 102.165)
		(end 110.8 102.05)
		(width 0.15)
		(layer "F.Cu")
		(net 251)
	)
	(segment
		(start 129.8 110.3)
		(end 130.5 109.6)
		(width 0.15)
		(layer "F.Cu")
		(net 251)
	)
	(segment
		(start 134.55 107.175)
		(end 134.075 107.65)
		(width 0.15)
		(layer "F.Cu")
		(net 251)
	)
	(segment
		(start 132.085 107.65)
		(end 131.315 107.65)
		(width 0.15)
		(layer "F.Cu")
		(net 251)
	)
	(segment
		(start 77.597323 72.005136)
		(end 77.597323 73.352677)
		(width 0.15)
		(layer "F.Cu")
		(net 251)
	)
	(segment
		(start 137.8 107.175)
		(end 134.55 107.175)
		(width 0.15)
		(layer "F.Cu")
		(net 251)
	)
	(segment
		(start 76.05 73.75)
		(end 73 76.8)
		(width 0.15)
		(layer "F.Cu")
		(net 251)
	)
	(segment
		(start 77.2 73.75)
		(end 76.05 73.75)
		(width 0.15)
		(layer "F.Cu")
		(net 251)
	)
	(segment
		(start 130.5 109.6)
		(end 130.5 108.1)
		(width 0.15)
		(layer "F.Cu")
		(net 251)
	)
	(segment
		(start 113.25 100.44)
		(end 113.89 99.8)
		(width 0.13)
		(layer "F.Cu")
		(net 251)
	)
	(segment
		(start 110.8 102.05)
		(end 109.706235 100.956235)
		(width 0.15)
		(layer "F.Cu")
		(net 251)
	)
	(segment
		(start 73 76.8)
		(end 72.85 76.8)
		(width 0.15)
		(layer "F.Cu")
		(net 251)
	)
	(segment
		(start 77.597323 73.352677)
		(end 77.2 73.75)
		(width 0.15)
		(layer "F.Cu")
		(net 251)
	)
	(segment
		(start 109.706235 100.956235)
		(end 108.856235 100.956235)
		(width 0.15)
		(layer "F.Cu")
		(net 251)
	)
	(segment
		(start 138.615 107.6)
		(end 138.225 107.6)
		(width 0.15)
		(layer "F.Cu")
		(net 251)
	)
	(segment
		(start 134.075 107.65)
		(end 132.085 107.65)
		(width 0.15)
		(layer "F.Cu")
		(net 251)
	)
	(segment
		(start 113.25 101.0125)
		(end 113.25 100.44)
		(width 0.13)
		(layer "F.Cu")
		(net 251)
	)
	(segment
		(start 129.8 111)
		(end 129.8 110.3)
		(width 0.15)
		(layer "F.Cu")
		(net 251)
	)
	(via
		(at 113.25 101.0125)
		(size 0.45)
		(drill 0.1)
		(layers "F.Cu" "B.Cu")
		(net 251)
	)
	(via
		(at 85.95 120.85)
		(size 0.45)
		(drill 0.1)
		(layers "F.Cu" "B.Cu")
		(net 251)
	)
	(via
		(at 129.8 111)
		(size 0.45)
		(drill 0.1)
		(layers "F.Cu" "B.Cu")
		(net 251)
	)
	(via
		(at 60.53286 99.304272)
		(size 0.45)
		(drill 0.1)
		(layers "F.Cu" "B.Cu")
		(net 251)
	)
	(via
		(at 70.446398 104.224676)
		(size 0.45)
		(drill 0.1)
		(layers "F.Cu" "B.Cu")
		(net 251)
	)
	(via
		(at 72.85 76.8)
		(size 0.45)
		(drill 0.1)
		(layers "F.Cu" "B.Cu")
		(net 251)
	)
	(via
		(at 61.9 77.5)
		(size 0.45)
		(drill 0.1)
		(layers "F.Cu" "B.Cu")
		(net 251)
	)
	(via
		(at 108.856235 100.956235)
		(size 0.45)
		(drill 0.1)
		(layers "F.Cu" "B.Cu")
		(net 251)
	)
	(segment
		(start 56.293908 97.725)
		(end 55.065 96.496092)
		(width 0.125)
		(layer "In3.Cu")
		(net 251)
	)
	(segment
		(start 83.85 120.85)
		(end 85.95 120.85)
		(width 0.125)
		(layer "In3.Cu")
		(net 251)
	)
	(segment
		(start 61.4 79.201041)
		(end 62.35052 78.250521)
		(width 0.125)
		(layer "In3.Cu")
		(net 251)
	)
	(segment
		(start 122.1 123.2)
		(end 108.2 123.2)
		(width 0.125)
		(layer "In3.Cu")
		(net 251)
	)
	(segment
		(start 86.1 120.7)
		(end 85.95 120.85)
		(width 0.125)
		(layer "In3.Cu")
		(net 251)
	)
	(segment
		(start 60.53286 99.304272)
		(end 60.384272 99.304272)
		(width 0.125)
		(layer "In3.Cu")
		(net 251)
	)
	(segment
		(start 65.75 113.65)
		(end 65.75 121.45)
		(width 0.125)
		(layer "In3.Cu")
		(net 251)
	)
	(segment
		(start 62.1 110)
		(end 65.75 113.65)
		(width 0.125)
		(layer "In3.Cu")
		(net 251)
	)
	(segment
		(start 124.7 122)
		(end 123.3 122)
		(width 0.125)
		(layer "In3.Cu")
		(net 251)
	)
	(segment
		(start 67 122.7)
		(end 82 122.7)
		(width 0.125)
		(layer "In3.Cu")
		(net 251)
	)
	(segment
		(start 128.4 112.4)
		(end 128.4 118.3)
		(width 0.125)
		(layer "In3.Cu")
		(net 251)
	)
	(segment
		(start 123.3 122)
		(end 122.1 123.2)
		(width 0.125)
		(layer "In3.Cu")
		(net 251)
	)
	(segment
		(start 59.75 98.13)
		(end 59.345 97.725)
		(width 0.125)
		(layer "In3.Cu")
		(net 251)
	)
	(segment
		(start 65.75 121.45)
		(end 67 122.7)
		(width 0.125)
		(layer "In3.Cu")
		(net 251)
	)
	(segment
		(start 59.345 97.725)
		(end 56.293908 97.725)
		(width 0.125)
		(layer "In3.Cu")
		(net 251)
	)
	(segment
		(start 129.8 111)
		(end 128.4 112.4)
		(width 0.125)
		(layer "In3.Cu")
		(net 251)
	)
	(segment
		(start 82 122.7)
		(end 83.85 120.85)
		(width 0.125)
		(layer "In3.Cu")
		(net 251)
	)
	(segment
		(start 61.4 92.7)
		(end 61.4 79.201041)
		(width 0.125)
		(layer "In3.Cu")
		(net 251)
	)
	(segment
		(start 60.758588 99.53)
		(end 61.57 99.53)
		(width 0.125)
		(layer "In3.Cu")
		(net 251)
	)
	(segment
		(start 60.384272 99.304272)
		(end 59.75 98.67)
		(width 0.125)
		(layer "In3.Cu")
		(net 251)
	)
	(segment
		(start 108.2 123.2)
		(end 105.7 120.7)
		(width 0.125)
		(layer "In3.Cu")
		(net 251)
	)
	(segment
		(start 55.8475 94.0175)
		(end 60.0825 94.0175)
		(width 0.125)
		(layer "In3.Cu")
		(net 251)
	)
	(segment
		(start 105.7 120.7)
		(end 86.1 120.7)
		(width 0.125)
		(layer "In3.Cu")
		(net 251)
	)
	(segment
		(start 55.065 96.496092)
		(end 55.065 94.8)
		(width 0.125)
		(layer "In3.Cu")
		(net 251)
	)
	(segment
		(start 60.53286 99.304272)
		(end 60.758588 99.53)
		(width 0.125)
		(layer "In3.Cu")
		(net 251)
	)
	(segment
		(start 61.57 99.53)
		(end 62.1 100.06)
		(width 0.125)
		(layer "In3.Cu")
		(net 251)
	)
	(segment
		(start 62.35052 78.250521)
		(end 62.35052 77.949479)
		(width 0.125)
		(layer "In3.Cu")
		(net 251)
	)
	(segment
		(start 61.901041 77.5)
		(end 61.9 77.5)
		(width 0.125)
		(layer "In3.Cu")
		(net 251)
	)
	(segment
		(start 55.065 94.8)
		(end 55.8475 94.0175)
		(width 0.125)
		(layer "In3.Cu")
		(net 251)
	)
	(segment
		(start 59.75 98.67)
		(end 59.75 98.13)
		(width 0.125)
		(layer "In3.Cu")
		(net 251)
	)
	(segment
		(start 60.0825 94.0175)
		(end 61.4 92.7)
		(width 0.125)
		(layer "In3.Cu")
		(net 251)
	)
	(segment
		(start 62.35052 77.949479)
		(end 61.901041 77.5)
		(width 0.125)
		(layer "In3.Cu")
		(net 251)
	)
	(segment
		(start 62.1 100.06)
		(end 62.1 110)
		(width 0.125)
		(layer "In3.Cu")
		(net 251)
	)
	(arc
		(start 128.4 118.3)
		(mid 127.316295 120.916295)
		(end 124.7 122)
		(width 0.125)
		(layer "In3.Cu")
		(net 251)
	)
	(segment
		(start 64.625 75.4)
		(end 71.45 75.4)
		(width 0.15)
		(layer "In5.Cu")
		(net 251)
	)
	(segment
		(start 60.98 99.77)
		(end 68.77 99.77)
		(width 0.125)
		(layer "In5.Cu")
		(net 251)
	)
	(segment
		(start 68.77 99.77)
		(end 69.9 100.9)
		(width 0.125)
		(layer "In5.Cu")
		(net 251)
	)
	(segment
		(start 69.9 104)
		(end 70.124676 104.224676)
		(width 0.125)
		(layer "In5.Cu")
		(net 251)
	)
	(segment
		(start 60.53286 99.32286)
		(end 60.98 99.77)
		(width 0.125)
		(layer "In5.Cu")
		(net 251)
	)
	(segment
		(start 70.124676 104.224676)
		(end 70.446398 104.224676)
		(width 0.125)
		(layer "In5.Cu")
		(net 251)
	)
	(segment
		(start 60.53286 99.304272)
		(end 60.53286 99.32286)
		(width 0.125)
		(layer "In5.Cu")
		(net 251)
	)
	(segment
		(start 62.525 77.5)
		(end 64.625 75.4)
		(width 0.15)
		(layer "In5.Cu")
		(net 251)
	)
	(segment
		(start 71.45 75.4)
		(end 72.85 76.8)
		(width 0.15)
		(layer "In5.Cu")
		(net 251)
	)
	(segment
		(start 69.9 100.9)
		(end 69.9 104)
		(width 0.125)
		(layer "In5.Cu")
		(net 251)
	)
	(segment
		(start 61.9 77.5)
		(end 62.525 77.5)
		(width 0.15)
		(layer "In5.Cu")
		(net 251)
	)
	(segment
		(start 60.328588 99.1)
		(end 60.14 99.1)
		(width 0.125)
		(layer "B.Cu")
		(net 251)
	)
	(segment
		(start 113.25 101.0125)
		(end 113.25 101.6)
		(width 0.125)
		(layer "B.Cu")
		(net 251)
	)
	(segment
		(start 85.412 121.388)
		(end 85.95 120.85)
		(width 0.15)
		(layer "B.Cu")
		(net 251)
	)
	(segment
		(start 72.9 104.4)
		(end 73.4 104.9)
		(width 0.125)
		(layer "B.Cu")
		(net 251)
	)
	(segment
		(start 113.2375 101)
		(end 109.7 101)
		(width 0.125)
		(layer "B.Cu")
		(net 251)
	)
	(segment
		(start 73.4 105.635)
		(end 72.835 106.2)
		(width 0.125)
		(layer "B.Cu")
		(net 251)
	)
	(segment
		(start 87.2 113.285)
		(end 87.2 119.85)
		(width 0.15)
		(layer "B.Cu")
		(net 251)
	)
	(segment
		(start 70.621722 104.4)
		(end 72.9 104.4)
		(width 0.125)
		(layer "B.Cu")
		(net 251)
	)
	(segment
		(start 85.112 121.388)
		(end 85.412 121.388)
		(width 0.15)
		(layer "B.Cu")
		(net 251)
	)
	(segment
		(start 73.4 104.9)
		(end 73.4 105.635)
		(width 0.125)
		(layer "B.Cu")
		(net 251)
	)
	(segment
		(start 113.25 101.0125)
		(end 113.2375 101)
		(width 0.125)
		(layer "B.Cu")
		(net 251)
	)
	(segment
		(start 85.412 121.78)
		(end 85.412 121.388)
		(width 0.15)
		(layer "B.Cu")
		(net 251)
	)
	(segment
		(start 116.1 107.9)
		(end 128.7 107.9)
		(width 0.125)
		(layer "B.Cu")
		(net 251)
	)
	(segment
		(start 60.53286 99.304272)
		(end 60.328588 99.1)
		(width 0.125)
		(layer "B.Cu")
		(net 251)
	)
	(segment
		(start 113.25 101.6)
		(end 113.5 101.85)
		(width 0.125)
		(layer "B.Cu")
		(net 251)
	)
	(segment
		(start 129.8 109)
		(end 129.8 111)
		(width 0.125)
		(layer "B.Cu")
		(net 251)
	)
	(segment
		(start 86.2 120.85)
		(end 85.95 120.85)
		(width 0.15)
		(layer "B.Cu")
		(net 251)
	)
	(segment
		(start 109.55 100.85)
		(end 108.96247 100.85)
		(width 0.125)
		(layer "B.Cu")
		(net 251)
	)
	(segment
		(start 85.01 121.49)
		(end 85.112 121.388)
		(width 0.15)
		(layer "B.Cu")
		(net 251)
	)
	(segment
		(start 70.446398 104.224676)
		(end 70.621722 104.4)
		(width 0.125)
		(layer "B.Cu")
		(net 251)
	)
	(segment
		(start 87 113.085)
		(end 87.2 113.285)
		(width 0.15)
		(layer "B.Cu")
		(net 251)
	)
	(segment
		(start 109.7 101)
		(end 109.55 100.85)
		(width 0.125)
		(layer "B.Cu")
		(net 251)
	)
	(segment
		(start 87.2 119.85)
		(end 86.2 120.85)
		(width 0.15)
		(layer "B.Cu")
		(net 251)
	)
	(segment
		(start 115.5 102.15)
		(end 115.5 107.3)
		(width 0.125)
		(layer "B.Cu")
		(net 251)
	)
	(segment
		(start 85.01 121.78)
		(end 85.01 121.49)
		(width 0.15)
		(layer "B.Cu")
		(net 251)
	)
	(segment
		(start 115.5 107.3)
		(end 116.1 107.9)
		(width 0.125)
		(layer "B.Cu")
		(net 251)
	)
	(segment
		(start 113.5 101.85)
		(end 115.2 101.85)
		(width 0.125)
		(layer "B.Cu")
		(net 251)
	)
	(segment
		(start 115.2 101.85)
		(end 115.5 102.15)
		(width 0.125)
		(layer "B.Cu")
		(net 251)
	)
	(segment
		(start 128.7 107.9)
		(end 129.8 109)
		(width 0.125)
		(layer "B.Cu")
		(net 251)
	)
	(segment
		(start 108.96247 100.85)
		(end 108.856235 100.956235)
		(width 0.125)
		(layer "B.Cu")
		(net 251)
	)
	(segment
		(start 134.1 108.15)
		(end 134.7 107.55)
		(width 0.15)
		(layer "F.Cu")
		(net 252)
	)
	(segment
		(start 109.463959 102.165)
		(end 108.431235 101.132276)
		(width 0.15)
		(layer "F.Cu")
		(net 252)
	)
	(segment
		(start 130.8 109.85)
		(end 130.8 108.3)
		(width 0.15)
		(layer "F.Cu")
		(net 252)
	)
	(segment
		(start 77.3 74.05)
		(end 78.097323 73.252677)
		(width 0.15)
		(layer "F.Cu")
		(net 252)
	)
	(segment
		(start 130.8 108.3)
		(end 130.95 108.15)
		(width 0.15)
		(layer "F.Cu")
		(net 252)
	)
	(segment
		(start 108.431235 101.132276)
		(end 108.431235 100.568765)
		(width 0.15)
		(layer "F.Cu")
		(net 252)
	)
	(segment
		(start 134.7 107.55)
		(end 137.565 107.55)
		(width 0.15)
		(layer "F.Cu")
		(net 252)
	)
	(segment
		(start 108.431235 100.568765)
		(end 108.45 100.55)
		(width 0.15)
		(layer "F.Cu")
		(net 252)
	)
	(segment
		(start 132.085 108.15)
		(end 131.315 108.15)
		(width 0.15)
		(layer "F.Cu")
		(net 252)
	)
	(segment
		(start 76.15 74.05)
		(end 77.3 74.05)
		(width 0.15)
		(layer "F.Cu")
		(net 252)
	)
	(segment
		(start 130.3 110.5)
		(end 130.3 110.35)
		(width 0.15)
		(layer "F.Cu")
		(net 252)
	)
	(segment
		(start 109.8 102.165)
		(end 109.463959 102.165)
		(width 0.15)
		(layer "F.Cu")
		(net 252)
	)
	(segment
		(start 73 77.45)
		(end 73.275 77.175)
		(width 0.15)
		(layer "F.Cu")
		(net 252)
	)
	(segment
		(start 113.7 101.02)
		(end 113.92 100.8)
		(width 0.13)
		(layer "F.Cu")
		(net 252)
	)
	(segment
		(start 73.275 77.175)
		(end 73.275 76.925)
		(width 0.15)
		(layer "F.Cu")
		(net 252)
	)
	(segment
		(start 73.275 76.925)
		(end 76.15 74.05)
		(width 0.15)
		(layer "F.Cu")
		(net 252)
	)
	(segment
		(start 132.085 108.15)
		(end 134.1 108.15)
		(width 0.15)
		(layer "F.Cu")
		(net 252)
	)
	(segment
		(start 137.565 107.55)
		(end 138.615 108.6)
		(width 0.15)
		(layer "F.Cu")
		(net 252)
	)
	(segment
		(start 130.3 110.35)
		(end 130.8 109.85)
		(width 0.15)
		(layer "F.Cu")
		(net 252)
	)
	(segment
		(start 130.95 108.15)
		(end 131.315 108.15)
		(width 0.15)
		(layer "F.Cu")
		(net 252)
	)
	(segment
		(start 78.097323 73.252677)
		(end 78.097323 72.005136)
		(width 0.15)
		(layer "F.Cu")
		(net 252)
	)
	(segment
		(start 113.7 101.4375)
		(end 113.7 101.02)
		(width 0.13)
		(layer "F.Cu")
		(net 252)
	)
	(via
		(at 108.45 100.55)
		(size 0.45)
		(drill 0.1)
		(layers "F.Cu" "B.Cu")
		(net 252)
	)
	(via
		(at 70.4 104.816328)
		(size 0.45)
		(drill 0.1)
		(layers "F.Cu" "B.Cu")
		(net 252)
	)
	(via
		(at 61.9 78.1)
		(size 0.45)
		(drill 0.1)
		(layers "F.Cu" "B.Cu")
		(net 252)
	)
	(via
		(at 113.7 101.4375)
		(size 0.45)
		(drill 0.1)
		(layers "F.Cu" "B.Cu")
		(net 252)
	)
	(via
		(at 73 77.45)
		(size 0.45)
		(drill 0.1)
		(layers "F.Cu" "B.Cu")
		(net 252)
	)
	(via
		(at 60.43 99.87)
		(size 0.45)
		(drill 0.1)
		(layers "F.Cu" "B.Cu")
		(net 252)
	)
	(via
		(at 130.3 110.5)
		(size 0.45)
		(drill 0.1)
		(layers "F.Cu" "B.Cu")
		(net 252)
	)
	(via
		(at 86.37 121.4)
		(size 0.45)
		(drill 0.1)
		(layers "F.Cu" "B.Cu")
		(net 252)
	)
	(segment
		(start 82.1 123)
		(end 83.7 121.4)
		(width 0.125)
		(layer "In3.Cu")
		(net 252)
	)
	(segment
		(start 65.45 113.75)
		(end 65.45 121.55)
		(width 0.125)
		(layer "In3.Cu")
		(net 252)
	)
	(segment
		(start 128.7 118.4)
		(end 128.7 112.7)
		(width 0.125)
		(layer "In3.Cu")
		(net 252)
	)
	(segment
		(start 122.3 123.5)
		(end 123.5 122.3)
		(width 0.125)
		(layer "In3.Cu")
		(net 252)
	)
	(segment
		(start 61.05 78.95)
		(end 61.05 92.5)
		(width 0.125)
		(layer "In3.Cu")
		(net 252)
	)
	(segment
		(start 108.1 123.5)
		(end 122.3 123.5)
		(width 0.125)
		(layer "In3.Cu")
		(net 252)
	)
	(segment
		(start 130.3 111.1)
		(end 130.3 110.5)
		(width 0.125)
		(layer "In3.Cu")
		(net 252)
	)
	(segment
		(start 56.18 98)
		(end 59.2 98)
		(width 0.125)
		(layer "In3.Cu")
		(net 252)
	)
	(segment
		(start 65.45 121.55)
		(end 66.9 123)
		(width 0.125)
		(layer "In3.Cu")
		(net 252)
	)
	(segment
		(start 61.49 99.87)
		(end 61.8 100.18)
		(width 0.125)
		(layer "In3.Cu")
		(net 252)
	)
	(segment
		(start 66.9 123)
		(end 82.1 123)
		(width 0.125)
		(layer "In3.Cu")
		(net 252)
	)
	(segment
		(start 83.7 121.4)
		(end 86.37 121.4)
		(width 0.125)
		(layer "In3.Cu")
		(net 252)
	)
	(segment
		(start 128.7 112.7)
		(end 130.3 111.1)
		(width 0.125)
		(layer "In3.Cu")
		(net 252)
	)
	(segment
		(start 61.8 110.1)
		(end 65.45 113.75)
		(width 0.125)
		(layer "In3.Cu")
		(net 252)
	)
	(segment
		(start 55.89 93.6)
		(end 54.79 94.7)
		(width 0.125)
		(layer "In3.Cu")
		(net 252)
	)
	(segment
		(start 86.37 121.4)
		(end 86.77 121)
		(width 0.125)
		(layer "In3.Cu")
		(net 252)
	)
	(segment
		(start 60.45 99.87)
		(end 61.49 99.87)
		(width 0.125)
		(layer "In3.Cu")
		(net 252)
	)
	(segment
		(start 59.45 98.87)
		(end 60.45 99.87)
		(width 0.125)
		(layer "In3.Cu")
		(net 252)
	)
	(segment
		(start 54.79 96.61)
		(end 56.18 98)
		(width 0.125)
		(layer "In3.Cu")
		(net 252)
	)
	(segment
		(start 59.45 98.25)
		(end 59.45 98.87)
		(width 0.125)
		(layer "In3.Cu")
		(net 252)
	)
	(segment
		(start 54.79 94.7)
		(end 54.79 96.61)
		(width 0.125)
		(layer "In3.Cu")
		(net 252)
	)
	(segment
		(start 123.5 122.3)
		(end 124.8 122.3)
		(width 0.125)
		(layer "In3.Cu")
		(net 252)
	)
	(segment
		(start 61.8 100.18)
		(end 61.8 110.1)
		(width 0.125)
		(layer "In3.Cu")
		(net 252)
	)
	(segment
		(start 61.9 78.1)
		(end 61.05 78.95)
		(width 0.125)
		(layer "In3.Cu")
		(net 252)
	)
	(segment
		(start 59.2 98)
		(end 59.45 98.25)
		(width 0.125)
		(layer "In3.Cu")
		(net 252)
	)
	(segment
		(start 86.77 121)
		(end 105.6 121)
		(width 0.125)
		(layer "In3.Cu")
		(net 252)
	)
	(segment
		(start 61.05 92.5)
		(end 59.95 93.6)
		(width 0.125)
		(layer "In3.Cu")
		(net 252)
	)
	(segment
		(start 59.95 93.6)
		(end 55.89 93.6)
		(width 0.125)
		(layer "In3.Cu")
		(net 252)
	)
	(segment
		(start 105.6 121)
		(end 108.1 123.5)
		(width 0.125)
		(layer "In3.Cu")
		(net 252)
	)
	(arc
		(start 124.8 122.3)
		(mid 127.557716 121.157716)
		(end 128.7 118.4)
		(width 0.125)
		(layer "In3.Cu")
		(net 252)
	)
	(segment
		(start 68.63 100.03)
		(end 69.5 100.9)
		(width 0.125)
		(layer "In5.Cu")
		(net 252)
	)
	(segment
		(start 69.5 100.9)
		(end 69.5 104.4)
		(width 0.125)
		(layer "In5.Cu")
		(net 252)
	)
	(segment
		(start 60.43 99.87)
		(end 60.43 99.98)
		(width 0.125)
		(layer "In5.Cu")
		(net 252)
	)
	(segment
		(start 69.916328 104.816328)
		(end 70.4 104.816328)
		(width 0.125)
		(layer "In5.Cu")
		(net 252)
	)
	(segment
		(start 71.3 75.7)
		(end 72.4 76.8)
		(width 0.15)
		(layer "In5.Cu")
		(net 252)
	)
	(segment
		(start 72.85 77.45)
		(end 73 77.45)
		(width 0.15)
		(layer "In5.Cu")
		(net 252)
	)
	(segment
		(start 62.525 78.1)
		(end 64.925 75.7)
		(width 0.15)
		(layer "In5.Cu")
		(net 252)
	)
	(segment
		(start 60.48 100.03)
		(end 68.63 100.03)
		(width 0.125)
		(layer "In5.Cu")
		(net 252)
	)
	(segment
		(start 69.5 104.4)
		(end 69.916328 104.816328)
		(width 0.125)
		(layer "In5.Cu")
		(net 252)
	)
	(segment
		(start 72.4 77)
		(end 72.85 77.45)
		(width 0.15)
		(layer "In5.Cu")
		(net 252)
	)
	(segment
		(start 64.925 75.7)
		(end 71.3 75.7)
		(width 0.15)
		(layer "In5.Cu")
		(net 252)
	)
	(segment
		(start 72.4 76.8)
		(end 72.4 77)
		(width 0.15)
		(layer "In5.Cu")
		(net 252)
	)
	(segment
		(start 60.43 99.98)
		(end 60.48 100.03)
		(width 0.125)
		(layer "In5.Cu")
		(net 252)
	)
	(segment
		(start 61.9 78.1)
		(end 62.525 78.1)
		(width 0.15)
		(layer "In5.Cu")
		(net 252)
	)
	(segment
		(start 72.285 104.65)
		(end 72.835 105.2)
		(width 0.125)
		(layer "B.Cu")
		(net 252)
	)
	(segment
		(start 108.456265 100.543735)
		(end 108.45 100.55)
		(width 0.125)
		(layer "B.Cu")
		(net 252)
	)
	(segment
		(start 85.92 121.4)
		(end 86.37 121.4)
		(width 0.15)
		(layer "B.Cu")
		(net 252)
	)
	(segment
		(start 115.8 107.1)
		(end 116.3 107.6)
		(width 0.125)
		(layer "B.Cu")
		(net 252)
	)
	(segment
		(start 59.38 99.87)
		(end 59.14 99.63)
		(width 0.125)
		(layer "B.Cu")
		(net 252)
	)
	(segment
		(start 70.4 104.816328)
		(end 70.566328 104.65)
		(width 0.125)
		(layer "B.Cu")
		(net 252)
	)
	(segment
		(start 87.5 119.95)
		(end 87.5 113.585)
		(width 0.15)
		(layer "B.Cu")
		(net 252)
	)
	(segment
		(start 115.2375 101.4375)
		(end 115.8 102)
		(width 0.125)
		(layer "B.Cu")
		(net 252)
	)
	(segment
		(start 113.7 101.4375)
		(end 115.2375 101.4375)
		(width 0.125)
		(layer "B.Cu")
		(net 252)
	)
	(segment
		(start 70.566328 104.65)
		(end 72.285 104.65)
		(width 0.125)
		(layer "B.Cu")
		(net 252)
	)
	(segment
		(start 116.3 107.6)
		(end 128.9 107.6)
		(width 0.125)
		(layer "B.Cu")
		(net 252)
	)
	(segment
		(start 85.81 121.51)
		(end 85.92 121.4)
		(width 0.15)
		(layer "B.Cu")
		(net 252)
	)
	(segment
		(start 86.37 121.4)
		(end 86.37 121.08)
		(width 0.15)
		(layer "B.Cu")
		(net 252)
	)
	(segment
		(start 86.37 121.08)
		(end 87.5 119.95)
		(width 0.15)
		(layer "B.Cu")
		(net 252)
	)
	(segment
		(start 87.5 113.585)
		(end 88 113.085)
		(width 0.15)
		(layer "B.Cu")
		(net 252)
	)
	(segment
		(start 128.9 107.6)
		(end 130.3 109)
		(width 0.125)
		(layer "B.Cu")
		(net 252)
	)
	(segment
		(start 113.7 100.879136)
		(end 113.420864 100.6)
		(width 0.125)
		(layer "B.Cu")
		(net 252)
	)
	(segment
		(start 130.3 109)
		(end 130.3 110.5)
		(width 0.125)
		(layer "B.Cu")
		(net 252)
	)
	(segment
		(start 109.668735 100.543735)
		(end 108.456265 100.543735)
		(width 0.125)
		(layer "B.Cu")
		(net 252)
	)
	(segment
		(start 113.420864 100.6)
		(end 109.725 100.6)
		(width 0.125)
		(layer "B.Cu")
		(net 252)
	)
	(segment
		(start 85.81 121.78)
		(end 85.81 121.51)
		(width 0.15)
		(layer "B.Cu")
		(net 252)
	)
	(segment
		(start 59.14 99.63)
		(end 59.14 99.1)
		(width 0.125)
		(layer "B.Cu")
		(net 252)
	)
	(segment
		(start 109.725 100.6)
		(end 109.668735 100.543735)
		(width 0.125)
		(layer "B.Cu")
		(net 252)
	)
	(segment
		(start 60.43 99.87)
		(end 59.38 99.87)
		(width 0.125)
		(layer "B.Cu")
		(net 252)
	)
	(segment
		(start 115.8 102)
		(end 115.8 107.1)
		(width 0.125)
		(layer "B.Cu")
		(net 252)
	)
	(segment
		(start 113.7 101.4375)
		(end 113.7 100.879136)
		(width 0.125)
		(layer "B.Cu")
		(net 252)
	)
	(segment
		(start 82.77 113.38)
		(end 82.77 114.127)
		(width 0.15)
		(layer "F.Cu")
		(net 253)
	)
	(segment
		(start 82.77 111.86215)
		(end 82.77 113.38)
		(width 0.125)
		(layer "F.Cu")
		(net 253)
	)
	(segment
		(start 82.25785 111.35)
		(end 82.77 111.86215)
		(width 0.125)
		(layer "F.Cu")
		(net 253)
	)
	(segment
		(start 80.42 111.35)
		(end 82.25785 111.35)
		(width 0.125)
		(layer "F.Cu")
		(net 253)
	)
	(via
		(at 82.77 113.38)
		(size 0.45)
		(drill 0.1)
		(layers "F.Cu" "B.Cu")
		(net 253)
	)
	(via
		(at 80.42 111.35)
		(size 0.45)
		(drill 0.1)
		(layers "F.Cu" "B.Cu")
		(net 253)
	)
	(segment
		(start 67.7 99.25)
		(end 67.7 99.75)
		(width 0.125)
		(layer "B.Cu")
		(net 253)
	)
	(segment
		(start 80.66 104.13)
		(end 75.58 99.05)
		(width 0.125)
		(layer "B.Cu")
		(net 253)
	)
	(segment
		(start 83.81 118.54)
		(end 83.81 121.81)
		(width 0.125)
		(layer "B.Cu")
		(net 253)
	)
	(segment
		(start 83.96 118.39)
		(end 83.81 118.54)
		(width 0.125)
		(layer "B.Cu")
		(net 253)
	)
	(segment
		(start 80.66 111.11)
		(end 80.66 104.13)
		(width 0.125)
		(layer "B.Cu")
		(net 253)
	)
	(segment
		(start 75.58 99.05)
		(end 67.9 99.05)
		(width 0.125)
		(layer "B.Cu")
		(net 253)
	)
	(segment
		(start 67.9 99.05)
		(end 67.7 99.25)
		(width 0.125)
		(layer "B.Cu")
		(net 253)
	)
	(segment
		(start 80.42 111.35)
		(end 80.66 111.11)
		(width 0.125)
		(layer "B.Cu")
		(net 253)
	)
	(segment
		(start 82.77 113.44)
		(end 82.77 116.22)
		(width 0.125)
		(layer "B.Cu")
		(net 253)
	)
	(segment
		(start 82.77 116.22)
		(end 83.96 117.41)
		(width 0.125)
		(layer "B.Cu")
		(net 253)
	)
	(segment
		(start 83.96 117.41)
		(end 83.96 118.39)
		(width 0.125)
		(layer "B.Cu")
		(net 253)
	)
	(segment
		(start 83.11 117.42)
		(end 81.772 117.42)
		(width 0.15)
		(layer "F.Cu")
		(net 254)
	)
	(segment
		(start 81.772 117.42)
		(end 81.772 116.676)
		(width 0.15)
		(layer "F.Cu")
		(net 254)
	)
	(via
		(at 83.11 117.42)
		(size 0.45)
		(drill 0.1)
		(layers "F.Cu" "B.Cu")
		(net 254)
	)
	(via
		(at 81.772 117.42)
		(size 0.45)
		(drill 0.1)
		(layers "F.Cu" "B.Cu")
		(net 254)
	)
	(segment
		(start 80.97 104.055)
		(end 75.715 98.8)
		(width 0.125)
		(layer "B.Cu")
		(net 254)
	)
	(segment
		(start 83.11 117.42)
		(end 83.01 117.52)
		(width 0.125)
		(layer "B.Cu")
		(net 254)
	)
	(segment
		(start 67.75 98.8)
		(end 67.3 99.25)
		(width 0.125)
		(layer "B.Cu")
		(net 254)
	)
	(segment
		(start 67.3 99.25)
		(end 67.3 99.75)
		(width 0.125)
		(layer "B.Cu")
		(net 254)
	)
	(segment
		(start 81.3 116.95)
		(end 81.3 114.31)
		(width 0.125)
		(layer "B.Cu")
		(net 254)
	)
	(segment
		(start 83.01 117.52)
		(end 83.01 121.81)
		(width 0.125)
		(layer "B.Cu")
		(net 254)
	)
	(segment
		(start 81.772 117.42)
		(end 81.77 117.42)
		(width 0.125)
		(layer "B.Cu")
		(net 254)
	)
	(segment
		(start 81.77 117.42)
		(end 81.3 116.95)
		(width 0.125)
		(layer "B.Cu")
		(net 254)
	)
	(segment
		(start 80.97 113.98)
		(end 80.97 104.055)
		(width 0.125)
		(layer "B.Cu")
		(net 254)
	)
	(segment
		(start 75.715 98.8)
		(end 67.75 98.8)
		(width 0.125)
		(layer "B.Cu")
		(net 254)
	)
	(segment
		(start 81.3 114.31)
		(end 80.97 113.98)
		(width 0.125)
		(layer "B.Cu")
		(net 254)
	)
	(segment
		(start 82.27 114.127)
		(end 82.27 112.8)
		(width 0.15)
		(layer "F.Cu")
		(net 255)
	)
	(segment
		(start 82.27 112.8)
		(end 81.18 112.8)
		(width 0.125)
		(layer "F.Cu")
		(net 255)
	)
	(via
		(at 82.27 112.8)
		(size 0.45)
		(drill 0.1)
		(layers "F.Cu" "B.Cu")
		(net 255)
	)
	(segment
		(start 76.02 98.3)
		(end 81.5 103.78)
		(width 0.125)
		(layer "B.Cu")
		(net 255)
	)
	(segment
		(start 81.5 103.78)
		(end 81.5 109.59)
		(width 0.125)
		(layer "B.Cu")
		(net 255)
	)
	(segment
		(start 82.27 116.6)
		(end 82.612 116.942)
		(width 0.125)
		(layer "B.Cu")
		(net 255)
	)
	(segment
		(start 82.612 116.942)
		(end 82.612 121.81)
		(width 0.125)
		(layer "B.Cu")
		(net 255)
	)
	(segment
		(start 66.5 99.75)
		(end 66.5 99.25)
		(width 0.125)
		(layer "B.Cu")
		(net 255)
	)
	(segment
		(start 81.5 109.59)
		(end 82.27 110.36)
		(width 0.125)
		(layer "B.Cu")
		(net 255)
	)
	(segment
		(start 82.27 110.36)
		(end 82.27 116.6)
		(width 0.125)
		(layer "B.Cu")
		(net 255)
	)
	(segment
		(start 67.45 98.3)
		(end 76.02 98.3)
		(width 0.125)
		(layer "B.Cu")
		(net 255)
	)
	(segment
		(start 66.5 99.25)
		(end 67.45 98.3)
		(width 0.125)
		(layer "B.Cu")
		(net 255)
	)
	(segment
		(start 81.272 117.622)
		(end 81.272 116.676)
		(width 0.15)
		(layer "F.Cu")
		(net 256)
	)
	(segment
		(start 82.15 118.1)
		(end 83.4775 118.1)
		(width 0.15)
		(layer "F.Cu")
		(net 256)
	)
	(segment
		(start 81.75 118.1)
		(end 81.272 117.622)
		(width 0.15)
		(layer "F.Cu")
		(net 256)
	)
	(segment
		(start 82.15 118.1)
		(end 81.75 118.1)
		(width 0.15)
		(layer "F.Cu")
		(net 256)
	)
	(via
		(at 82.15 118.1)
		(size 0.45)
		(drill 0.1)
		(layers "F.Cu" "B.Cu")
		(net 256)
	)
	(via
		(at 83.4775 118.1)
		(size 0.45)
		(drill 0.1)
		(layers "F.Cu" "B.Cu")
		(net 256)
	)
	(segment
		(start 81.79 116.77)
		(end 81.79 114.15)
		(width 0.125)
		(layer "B.Cu")
		(net 256)
	)
	(segment
		(start 83.412 118.1655)
		(end 83.412 121.81)
		(width 0.125)
		(layer "B.Cu")
		(net 256)
	)
	(segment
		(start 81.25 103.945)
		(end 75.855 98.55)
		(width 0.125)
		(layer "B.Cu")
		(net 256)
	)
	(segment
		(start 82.24 117.22)
		(end 81.79 116.77)
		(width 0.125)
		(layer "B.Cu")
		(net 256)
	)
	(segment
		(start 67.6 98.55)
		(end 66.9 99.25)
		(width 0.125)
		(layer "B.Cu")
		(net 256)
	)
	(segment
		(start 83.4775 118.1)
		(end 83.412 118.1655)
		(width 0.125)
		(layer "B.Cu")
		(net 256)
	)
	(segment
		(start 75.855 98.55)
		(end 67.6 98.55)
		(width 0.125)
		(layer "B.Cu")
		(net 256)
	)
	(segment
		(start 82.15 118.1)
		(end 82.24 118.01)
		(width 0.125)
		(layer "B.Cu")
		(net 256)
	)
	(segment
		(start 66.9 99.25)
		(end 66.9 99.75)
		(width 0.125)
		(layer "B.Cu")
		(net 256)
	)
	(segment
		(start 81.79 114.15)
		(end 81.25 113.61)
		(width 0.125)
		(layer "B.Cu")
		(net 256)
	)
	(segment
		(start 81.25 113.61)
		(end 81.25 103.945)
		(width 0.125)
		(layer "B.Cu")
		(net 256)
	)
	(segment
		(start 82.24 118.01)
		(end 82.24 117.22)
		(width 0.125)
		(layer "B.Cu")
		(net 256)
	)
	(segment
		(start 73.9505 109.738074)
		(end 73.9505 110.131969)
		(width 0.155)
		(layer "F.Cu")
		(net 257)
	)
	(segment
		(start 74.2005 108.817969)
		(end 74.2005 109.488074)
		(width 0.155)
		(layer "F.Cu")
		(net 257)
	)
	(segment
		(start 73.9505 110.131969)
		(end 73.6 110.482469)
		(width 0.155)
		(layer "F.Cu")
		(net 257)
	)
	(segment
		(start 74.15 108.767469)
		(end 74.2005 108.817969)
		(width 0.155)
		(layer "F.Cu")
		(net 257)
	)
	(segment
		(start 74.2005 109.488074)
		(end 73.9505 109.738074)
		(width 0.155)
		(layer "F.Cu")
		(net 257)
	)
	(segment
		(start 72.60492 117.56)
		(end 72.49992 117.665)
		(width 0.165)
		(layer "F.Cu")
		(net 258)
	)
	(segment
		(start 72.5 116.297501)
		(end 72.605 116.402501)
		(width 0.165)
		(layer "F.Cu")
		(net 258)
	)
	(segment
		(start 72.5 114.702499)
		(end 72.6005 114.601999)
		(width 0.155)
		(layer "F.Cu")
		(net 258)
	)
	(segment
		(start 72.60492 117.167365)
		(end 72.60492 117.56)
		(width 0.165)
		(layer "F.Cu")
		(net 258)
	)
	(segment
		(start 72.6005 113.663074)
		(end 73.9505 112.313074)
		(width 0.155)
		(layer "F.Cu")
		(net 258)
	)
	(segment
		(start 73.9505 112.313074)
		(end 73.9505 111.802969)
		(width 0.155)
		(layer "F.Cu")
		(net 258)
	)
	(segment
		(start 72.6005 114.601999)
		(end 72.6005 113.663074)
		(width 0.155)
		(layer "F.Cu")
		(net 258)
	)
	(segment
		(start 73.9505 111.802969)
		(end 73.6 111.452469)
		(width 0.155)
		(layer "F.Cu")
		(net 258)
	)
	(segment
		(start 72.5 115.115)
		(end 72.5 114.702499)
		(width 0.155)
		(layer "F.Cu")
		(net 258)
	)
	(segment
		(start 72.605 117.167285)
		(end 72.60492 117.167365)
		(width 0.165)
		(layer "F.Cu")
		(net 258)
	)
	(segment
		(start 72.5 115.885)
		(end 72.5 116.297501)
		(width 0.165)
		(layer "F.Cu")
		(net 258)
	)
	(segment
		(start 72.5 115.115)
		(end 72.5 115.885)
		(width 0.165)
		(layer "F.Cu")
		(net 258)
	)
	(segment
		(start 72.605 116.402501)
		(end 72.605 117.167285)
		(width 0.165)
		(layer "F.Cu")
		(net 258)
	)
	(segment
		(start 76.2495 110.131969)
		(end 76.6 110.482469)
		(width 0.155)
		(layer "F.Cu")
		(net 259)
	)
	(segment
		(start 76.2495 109.938074)
		(end 76.2495 110.131969)
		(width 0.155)
		(layer "F.Cu")
		(net 259)
	)
	(segment
		(start 75.75 108.767469)
		(end 75.6995 108.817969)
		(width 0.155)
		(layer "F.Cu")
		(net 259)
	)
	(segment
		(start 75.6995 108.817969)
		(end 75.6995 109.388074)
		(width 0.155)
		(layer "F.Cu")
		(net 259)
	)
	(segment
		(start 75.6995 109.388074)
		(end 76.2495 109.938074)
		(width 0.155)
		(layer "F.Cu")
		(net 259)
	)
	(segment
		(start 78.8995 114.601999)
		(end 79 114.702499)
		(width 0.155)
		(layer "F.Cu")
		(net 260)
	)
	(segment
		(start 78.8995 113.063074)
		(end 78.8995 114.601999)
		(width 0.155)
		(layer "F.Cu")
		(net 260)
	)
	(segment
		(start 77.5295 121.161926)
		(end 77.5295 121.3925)
		(width 0.155)
		(layer "F.Cu")
		(net 260)
	)
	(segment
		(start 76.2495 112.113074)
		(end 76.461926 112.3255)
		(width 0.155)
		(layer "F.Cu")
		(net 260)
	)
	(segment
		(start 77.5295 121.3925)
		(end 77.677 121.54)
		(width 0.155)
		(layer "F.Cu")
		(net 260)
	)
	(segment
		(start 76.2495 111.802969)
		(end 76.2495 112.113074)
		(width 0.155)
		(layer "F.Cu")
		(net 260)
	)
	(segment
		(start 78.1295 120.031926)
		(end 78.1295 120.561926)
		(width 0.155)
		(layer "F.Cu")
		(net 260)
	)
	(segment
		(start 79 114.702499)
		(end 79 115.115)
		(width 0.155)
		(layer "F.Cu")
		(net 260)
	)
	(segment
		(start 79 115.885)
		(end 79 116.297501)
		(width 0.155)
		(layer "F.Cu")
		(net 260)
	)
	(segment
		(start 78.1295 120.561926)
		(end 77.5295 121.161926)
		(width 0.155)
		(layer "F.Cu")
		(net 260)
	)
	(segment
		(start 78.8995 119.261926)
		(end 78.1295 120.031926)
		(width 0.155)
		(layer "F.Cu")
		(net 260)
	)
	(segment
		(start 79 115.115)
		(end 79 115.885)
		(width 0.165)
		(layer "F.Cu")
		(net 260)
	)
	(segment
		(start 76.461926 112.3255)
		(end 78.161926 112.3255)
		(width 0.155)
		(layer "F.Cu")
		(net 260)
	)
	(segment
		(start 78.8995 116.398001)
		(end 78.8995 119.261926)
		(width 0.155)
		(layer "F.Cu")
		(net 260)
	)
	(segment
		(start 78.161926 112.3255)
		(end 78.8995 113.063074)
		(width 0.155)
		(layer "F.Cu")
		(net 260)
	)
	(segment
		(start 76.6 111.452469)
		(end 76.2495 111.802969)
		(width 0.155)
		(layer "F.Cu")
		(net 260)
	)
	(segment
		(start 79 116.297501)
		(end 78.8995 116.398001)
		(width 0.155)
		(layer "F.Cu")
		(net 260)
	)
	(via
		(at 77.677 121.54)
		(size 0.45)
		(drill 0.1)
		(layers "F.Cu" "B.Cu")
		(net 260)
	)
	(segment
		(start 76.89942 120.477994)
		(end 77.5295 121.108074)
		(width 0.155)
		(layer "B.Cu")
		(net 260)
	)
	(segment
		(start 77.5295 121.3925)
		(end 77.677 121.54)
		(width 0.155)
		(layer "B.Cu")
		(net 260)
	)
	(segment
		(start 77.5295 121.108074)
		(end 77.5295 121.3925)
		(width 0.155)
		(layer "B.Cu")
		(net 260)
	)
	(segment
		(start 77.14992 120.065)
		(end 76.89942 120.3155)
		(width 0.155)
		(layer "B.Cu")
		(net 260)
	)
	(segment
		(start 76.89942 120.3155)
		(end 76.89942 120.477994)
		(width 0.155)
		(layer "B.Cu")
		(net 260)
	)
	(segment
		(start 73.5 118.85)
		(end 73.5 118.73)
		(width 0.15)
		(layer "F.Cu")
		(net 261)
	)
	(segment
		(start 75.94992 119.365)
		(end 75.94992 119.10008)
		(width 0.15)
		(layer "F.Cu")
		(net 261)
	)
	(segment
		(start 69.435 120.665)
		(end 68.85 121.25)
		(width 0.2)
		(layer "F.Cu")
		(net 261)
	)
	(segment
		(start 73.54992 119.365)
		(end 73.54992 118.89992)
		(width 0.15)
		(layer "F.Cu")
		(net 261)
	)
	(segment
		(start 73.54992 118.89992)
		(end 73.5 118.85)
		(width 0.15)
		(layer "F.Cu")
		(net 261)
	)
	(segment
		(start 76 119.05)
		(end 76 118.115)
		(width 0.15)
		(layer "F.Cu")
		(net 261)
	)
	(segment
		(start 68.85 121.25)
		(end 68.85 124.315)
		(width 0.2)
		(layer "F.Cu")
		(net 261)
	)
	(segment
		(start 75.94992 119.10008)
		(end 76 119.05)
		(width 0.15)
		(layer "F.Cu")
		(net 261)
	)
	(via
		(at 68 115.75)
		(size 0.45)
		(drill 0.1)
		(layers "F.Cu" "B.Cu")
		(free yes)
		(net 261)
	)
	(via
		(at 68.6 115.2)
		(size 0.45)
		(drill 0.1)
		(layers "F.Cu" "B.Cu")
		(free yes)
		(net 261)
	)
	(via
		(at 69.2 115.2)
		(size 0.45)
		(drill 0.1)
		(layers "F.Cu" "B.Cu")
		(free yes)
		(net 261)
	)
	(via
		(at 69.2 115.75)
		(size 0.45)
		(drill 0.1)
		(layers "F.Cu" "B.Cu")
		(free yes)
		(net 261)
	)
	(via
		(at 68.6 115.75)
		(size 0.45)
		(drill 0.1)
		(layers "F.Cu" "B.Cu")
		(free yes)
		(net 261)
	)
	(via
		(at 69.435 120.665)
		(size 0.45)
		(drill 0.1)
		(layers "F.Cu" "B.Cu")
		(net 261)
	)
	(via
		(at 68 115.2)
		(size 0.45)
		(drill 0.1)
		(layers "F.Cu" "B.Cu")
		(free yes)
		(net 261)
	)
	(segment
		(start 68.86 119.03)
		(end 68.86 116.01)
		(width 0.2)
		(layer "B.Cu")
		(net 261)
	)
	(segment
		(start 67.9 107.415)
		(end 68.2 107.715)
		(width 0.5)
		(layer "B.Cu")
		(net 261)
	)
	(segment
		(start 69.435 120.665)
		(end 69.435 119.605)
		(width 0.2)
		(layer "B.Cu")
		(net 261)
	)
	(segment
		(start 68.86 116.01)
		(end 68.6 115.75)
		(width 0.2)
		(layer "B.Cu")
		(net 261)
	)
	(segment
		(start 69.435 119.605)
		(end 68.86 119.03)
		(width 0.2)
		(layer "B.Cu")
		(net 261)
	)
	(segment
		(start 67.9 106.45)
		(end 67.9 107.415)
		(width 0.5)
		(layer "B.Cu")
		(net 261)
	)
	(segment
		(start 117.1505 110.9145)
		(end 116.8 111.265)
		(width 0.155)
		(layer "F.Cu")
		(net 262)
	)
	(segment
		(start 114.332907 107.909553)
		(end 114.366773 107.875686)
		(width 0.155)
		(layer "F.Cu")
		(net 262)
	)
	(segment
		(start 114.61426 107.875687)
		(end 114.61426 107.875686)
		(width 0.155)
		(layer "F.Cu")
		(net 262)
	)
	(segment
		(start 114.085421 107.909553)
		(end 114.08542 107.909553)
		(width 0.155)
		(layer "F.Cu")
		(net 262)
	)
	(segment
		(start 114.61426 107.875686)
		(end 117.1505 110.411926)
		(width 0.155)
		(layer "F.Cu")
		(net 262)
	)
	(segment
		(start 114.332907 107.909552)
		(end 114.332907 107.909553)
		(width 0.155)
		(layer "F.Cu")
		(net 262)
	)
	(segment
		(start 114.119287 107.6282)
		(end 114.08542 107.662066)
		(width 0.155)
		(layer "F.Cu")
		(net 262)
	)
	(segment
		(start 114.119286 107.6282)
		(end 114.119287 107.6282)
		(width 0.155)
		(layer "F.Cu")
		(net 262)
	)
	(segment
		(start 117.1505 110.411926)
		(end 117.1505 110.9145)
		(width 0.155)
		(layer "F.Cu")
		(net 262)
	)
	(segment
		(start 113.433074 106.6945)
		(end 114.119287 107.380713)
		(width 0.155)
		(layer "F.Cu")
		(net 262)
	)
	(segment
		(start 110.464939 106.745)
		(end 110.515439 106.6945)
		(width 0.155)
		(layer "F.Cu")
		(net 262)
	)
	(segment
		(start 110.515439 106.6945)
		(end 113.433074 106.6945)
		(width 0.155)
		(layer "F.Cu")
		(net 262)
	)
	(segment
		(start 110.089938 106.745)
		(end 110.464939 106.745)
		(width 0.155)
		(layer "F.Cu")
		(net 262)
	)
	(arc
		(start 114.08542 107.662066)
		(mid 114.034164 107.78581)
		(end 114.085421 107.909553)
		(width 0.155)
		(layer "F.Cu")
		(net 262)
	)
	(arc
		(start 114.119287 107.380713)
		(mid 114.170543 107.504457)
		(end 114.119286 107.6282)
		(width 0.155)
		(layer "F.Cu")
		(net 262)
	)
	(arc
		(start 114.366773 107.875686)
		(mid 114.490517 107.82443)
		(end 114.61426 107.875687)
		(width 0.155)
		(layer "F.Cu")
		(net 262)
	)
	(arc
		(start 114.08542 107.909553)
		(mid 114.209164 107.960809)
		(end 114.332907 107.909552)
		(width 0.155)
		(layer "F.Cu")
		(net 262)
	)
	(segment
		(start 115.5495 120.708074)
		(end 115.771926 120.9305)
		(width 0.155)
		(layer "F.Cu")
		(net 263)
	)
	(segment
		(start 116.4705 120.018074)
		(end 117.1485 119.340074)
		(width 0.155)
		(layer "F.Cu")
		(net 263)
	)
	(segment
		(start 116.9485 118.1)
		(end 116.929146 118.1)
		(width 0.155)
		(layer "F.Cu")
		(net 263)
	)
	(segment
		(start 117.1505 112.5855)
		(end 116.8 112.235)
		(width 0.155)
		(layer "F.Cu")
		(net 263)
	)
	(segment
		(start 116.9485 118.9)
		(end 116.92911 118.9)
		(width 0.155)
		(layer "F.Cu")
		(net 263)
	)
	(segment
		(start 115.8 120.15)
		(end 115.5495 120.4005)
		(width 0.155)
		(layer "F.Cu")
		(net 263)
	)
	(segment
		(start 117.1505 115.401999)
		(end 117.1505 112.5855)
		(width 0.155)
		(layer "F.Cu")
		(net 263)
	)
	(segment
		(start 117.1485 117.07875)
		(end 117.048 116.97825)
		(width 0.155)
		(layer "F.Cu")
		(net 263)
	)
	(segment
		(start 116.058074 120.9305)
		(end 116.4705 120.518074)
		(width 0.155)
		(layer "F.Cu")
		(net 263)
	)
	(segment
		(start 116.92911 118.5)
		(end 116.9485 118.5)
		(width 0.155)
		(layer "F.Cu")
		(net 263)
	)
	(segment
		(start 117.05 115.502499)
		(end 117.1505 115.401999)
		(width 0.155)
		(layer "F.Cu")
		(net 263)
	)
	(segment
		(start 116.4705 120.518074)
		(end 116.4705 120.018074)
		(width 0.155)
		(layer "F.Cu")
		(net 263)
	)
	(segment
		(start 115.771926 120.9305)
		(end 116.058074 120.9305)
		(width 0.155)
		(layer "F.Cu")
		(net 263)
	)
	(segment
		(start 115.5495 120.4005)
		(end 115.5495 120.708074)
		(width 0.155)
		(layer "F.Cu")
		(net 263)
	)
	(segment
		(start 117.05 115.915)
		(end 117.05 115.502499)
		(width 0.155)
		(layer "F.Cu")
		(net 263)
	)
	(segment
		(start 116.929146 117.7)
		(end 116.9485 117.7)
		(width 0.155)
		(layer "F.Cu")
		(net 263)
	)
	(segment
		(start 117.1485 119.340074)
		(end 117.1485 119.1)
		(width 0.155)
		(layer "F.Cu")
		(net 263)
	)
	(segment
		(start 117.05 116.563749)
		(end 117.05 115.793749)
		(width 0.155)
		(layer "F.Cu")
		(net 263)
	)
	(segment
		(start 117.048 116.97825)
		(end 117.048 116.565749)
		(width 0.155)
		(layer "F.Cu")
		(net 263)
	)
	(segment
		(start 117.1485 117.5)
		(end 117.1485 117.07875)
		(width 0.155)
		(layer "F.Cu")
		(net 263)
	)
	(arc
		(start 116.72911 118.7)
		(mid 116.787689 118.558579)
		(end 116.92911 118.5)
		(width 0.155)
		(layer "F.Cu")
		(net 263)
	)
	(arc
		(start 116.9485 118.5)
		(mid 117.089921 118.441421)
		(end 117.1485 118.3)
		(width 0.155)
		(layer "F.Cu")
		(net 263)
	)
	(arc
		(start 116.929146 118.1)
		(mid 116.787725 118.041421)
		(end 116.729146 117.9)
		(width 0.155)
		(layer "F.Cu")
		(net 263)
	)
	(arc
		(start 117.1485 118.3)
		(mid 117.089921 118.158579)
		(end 116.9485 118.1)
		(width 0.155)
		(layer "F.Cu")
		(net 263)
	)
	(arc
		(start 117.1485 119.1)
		(mid 117.089921 118.958579)
		(end 116.9485 118.9)
		(width 0.155)
		(layer "F.Cu")
		(net 263)
	)
	(arc
		(start 116.729146 117.9)
		(mid 116.787725 117.758579)
		(end 116.929146 117.7)
		(width 0.155)
		(layer "F.Cu")
		(net 263)
	)
	(arc
		(start 116.92911 118.9)
		(mid 116.787689 118.841421)
		(end 116.72911 118.7)
		(width 0.155)
		(layer "F.Cu")
		(net 263)
	)
	(arc
		(start 116.9485 117.7)
		(mid 117.089921 117.641421)
		(end 117.1485 117.5)
		(width 0.155)
		(layer "F.Cu")
		(net 263)
	)
	(segment
		(start 111.1505 110.9145)
		(end 110.8 111.265)
		(width 0.155)
		(layer "F.Cu")
		(net 264)
	)
	(segment
		(start 111.1505 110.3395)
		(end 111.1505 110.9145)
		(width 0.155)
		(layer "F.Cu")
		(net 264)
	)
	(segment
		(start 111.1505 109.211926)
		(end 111.1505 109.4895)
		(width 0.155)
		(layer "F.Cu")
		(net 264)
	)
	(segment
		(start 111.1505 110.2895)
		(end 111.1505 110.3395)
		(width 0.155)
		(layer "F.Cu")
		(net 264)
	)
	(segment
		(start 110.114948 108.345)
		(end 110.283574 108.345)
		(width 0.155)
		(layer "F.Cu")
		(net 264)
	)
	(segment
		(start 110.9505 109.6895)
		(end 110.878198 109.6895)
		(width 0.155)
		(layer "F.Cu")
		(net 264)
	)
	(segment
		(start 110.283574 108.345)
		(end 111.1505 109.211926)
		(width 0.155)
		(layer "F.Cu")
		(net 264)
	)
	(segment
		(start 110.878198 110.0895)
		(end 110.9505 110.0895)
		(width 0.155)
		(layer "F.Cu")
		(net 264)
	)
	(arc
		(start 110.678198 109.8895)
		(mid 110.736777 110.030921)
		(end 110.878198 110.0895)
		(width 0.155)
		(layer "F.Cu")
		(net 264)
	)
	(arc
		(start 111.1505 109.4895)
		(mid 111.091921 109.630921)
		(end 110.9505 109.6895)
		(width 0.155)
		(layer "F.Cu")
		(net 264)
	)
	(arc
		(start 110.878198 109.6895)
		(mid 110.736777 109.748079)
		(end 110.678198 109.8895)
		(width 0.155)
		(layer "F.Cu")
		(net 264)
	)
	(arc
		(start 110.9505 110.0895)
		(mid 111.091921 110.148079)
		(end 111.1505 110.2895)
		(width 0.155)
		(layer "F.Cu")
		(net 264)
	)
	(segment
		(start 111.05 115.502499)
		(end 111.1505 115.401999)
		(width 0.155)
		(layer "F.Cu")
		(net 265)
	)
	(segment
		(start 111.05 116.438749)
		(end 111.1505 116.338249)
		(width 0.155)
		(layer "F.Cu")
		(net 265)
	)
	(segment
		(start 111.1505 115.401999)
		(end 111.1505 112.5855)
		(width 0.155)
		(layer "F.Cu")
		(net 265)
	)
	(segment
		(start 111.05 116.20625)
		(end 111.05 115.793749)
		(width 0.155)
		(layer "F.Cu")
		(net 265)
	)
	(segment
		(start 111.1505 116.338249)
		(end 111.1505 116.30675)
		(width 0.155)
		(layer "F.Cu")
		(net 265)
	)
	(segment
		(start 111.1505 116.30675)
		(end 111.05 116.20625)
		(width 0.155)
		(layer "F.Cu")
		(net 265)
	)
	(segment
		(start 111.15 117.37)
		(end 111.05 117.27)
		(width 0.155)
		(layer "F.Cu")
		(net 265)
	)
	(segment
		(start 111.05 115.915)
		(end 111.05 115.502499)
		(width 0.155)
		(layer "F.Cu")
		(net 265)
	)
	(segment
		(start 111.05 117.27)
		(end 111.05 116.685)
		(width 0.155)
		(layer "F.Cu")
		(net 265)
	)
	(segment
		(start 111.15 118.2)
		(end 111.15 117.37)
		(width 0.155)
		(layer "F.Cu")
		(net 265)
	)
	(segment
		(start 111.1505 112.5855)
		(end 110.8 112.235)
		(width 0.155)
		(layer "F.Cu")
		(net 265)
	)
	(segment
		(start 110.345 107.945)
		(end 110.089938 107.945)
		(width 0.155)
		(layer "F.Cu")
		(net 266)
	)
	(segment
		(start 111.8 111.265)
		(end 111.4495 110.9145)
		(width 0.155)
		(layer "F.Cu")
		(net 266)
	)
	(segment
		(start 111.4495 109.0495)
		(end 110.345 107.945)
		(width 0.155)
		(layer "F.Cu")
		(net 266)
	)
	(segment
		(start 111.4495 110.9145)
		(end 111.4495 109.0495)
		(width 0.155)
		(layer "F.Cu")
		(net 266)
	)
	(segment
		(start 111.65 117.37)
		(end 111.55 117.27)
		(width 0.155)
		(layer "F.Cu")
		(net 267)
	)
	(segment
		(start 111.65 118.2)
		(end 111.65 117.37)
		(width 0.155)
		(layer "F.Cu")
		(net 267)
	)
	(segment
		(start 111.4495 115.401999)
		(end 111.4495 112.5855)
		(width 0.155)
		(layer "F.Cu")
		(net 267)
	)
	(segment
		(start 111.55 116.20625)
		(end 111.55 115.793749)
		(width 0.155)
		(layer "F.Cu")
		(net 267)
	)
	(segment
		(start 111.4495 116.30675)
		(end 111.55 116.20625)
		(width 0.155)
		(layer "F.Cu")
		(net 267)
	)
	(segment
		(start 111.55 117.27)
		(end 111.55 116.685)
		(width 0.155)
		(layer "F.Cu")
		(net 267)
	)
	(segment
		(start 111.55 115.502499)
		(end 111.4495 115.401999)
		(width 0.155)
		(layer "F.Cu")
		(net 267)
	)
	(segment
		(start 111.55 115.915)
		(end 111.55 115.502499)
		(width 0.155)
		(layer "F.Cu")
		(net 267)
	)
	(segment
		(start 111.4495 116.338249)
		(end 111.4495 116.30675)
		(width 0.155)
		(layer "F.Cu")
		(net 267)
	)
	(segment
		(start 111.4495 112.5855)
		(end 111.8 112.235)
		(width 0.155)
		(layer "F.Cu")
		(net 267)
	)
	(segment
		(start 111.55 116.438749)
		(end 111.4495 116.338249)
		(width 0.155)
		(layer "F.Cu")
		(net 267)
	)
	(segment
		(start 113.556926 106.3955)
		(end 117.4495 110.288074)
		(width 0.155)
		(layer "F.Cu")
		(net 268)
	)
	(segment
		(start 110.089938 106.345)
		(end 110.464939 106.345)
		(width 0.155)
		(layer "F.Cu")
		(net 268)
	)
	(segment
		(start 117.4495 110.288074)
		(end 117.4495 110.9145)
		(width 0.155)
		(layer "F.Cu")
		(net 268)
	)
	(segment
		(start 110.515439 106.3955)
		(end 113.556926 106.3955)
		(width 0.155)
		(layer "F.Cu")
		(net 268)
	)
	(segment
		(start 110.464939 106.345)
		(end 110.515439 106.3955)
		(width 0.155)
		(layer "F.Cu")
		(net 268)
	)
	(segment
		(start 117.4495 110.9145)
		(end 117.8 111.265)
		(width 0.155)
		(layer "F.Cu")
		(net 268)
	)
	(segment
		(start 115.2505 120.4005)
		(end 115.2505 120.831926)
		(width 0.155)
		(layer "F.Cu")
		(net 269)
	)
	(segment
		(start 116.7695 120.641926)
		(end 116.7695 120.141926)
		(width 0.155)
		(layer "F.Cu")
		(net 269)
	)
	(segment
		(start 116.7695 120.141926)
		(end 117.4475 119.463926)
		(width 0.155)
		(layer "F.Cu")
		(net 269)
	)
	(segment
		(start 117.4495 112.5855)
		(end 117.4495 115.401999)
		(width 0.155)
		(layer "F.Cu")
		(net 269)
	)
	(segment
		(start 115.648074 121.2295)
		(end 116.181926 121.2295)
		(width 0.155)
		(layer "F.Cu")
		(net 269)
	)
	(segment
		(start 115.2505 120.831926)
		(end 115.648074 121.2295)
		(width 0.155)
		(layer "F.Cu")
		(net 269)
	)
	(segment
		(start 115 120.15)
		(end 115.2505 120.4005)
		(width 0.155)
		(layer "F.Cu")
		(net 269)
	)
	(segment
		(start 117.4475 117.07875)
		(end 117.548 116.97825)
		(width 0.155)
		(layer "F.Cu")
		(net 269)
	)
	(segment
		(start 117.8 112.235)
		(end 117.4495 112.5855)
		(width 0.155)
		(layer "F.Cu")
		(net 269)
	)
	(segment
		(start 117.55 115.502499)
		(end 117.55 115.915)
		(width 0.155)
		(layer "F.Cu")
		(net 269)
	)
	(segment
		(start 117.548 116.97825)
		(end 117.548 116.565749)
		(width 0.155)
		(layer "F.Cu")
		(net 269)
	)
	(segment
		(start 117.4495 115.401999)
		(end 117.55 115.502499)
		(width 0.155)
		(layer "F.Cu")
		(net 269)
	)
	(segment
		(start 116.181926 121.2295)
		(end 116.7695 120.641926)
		(width 0.155)
		(layer "F.Cu")
		(net 269)
	)
	(segment
		(start 117.4475 119.463926)
		(end 117.4475 117.07875)
		(width 0.155)
		(layer "F.Cu")
		(net 269)
	)
	(segment
		(start 117.55 116.563749)
		(end 117.55 115.793749)
		(width 0.155)
		(layer "F.Cu")
		(net 269)
	)
	(segment
		(start 106.175 122.85)
		(end 103.65 122.85)
		(width 0.2)
		(layer "F.Cu")
		(net 270)
	)
	(segment
		(start 98.135 127.405)
		(end 98.135 126.305)
		(width 0.15)
		(layer "F.Cu")
		(net 270)
	)
	(segment
		(start 98.135 126.305)
		(end 100.44 124)
		(width 0.15)
		(layer "F.Cu")
		(net 270)
	)
	(segment
		(start 100.44 124)
		(end 100.44 122.68)
		(width 0.15)
		(layer "F.Cu")
		(net 270)
	)
	(segment
		(start 100.44 122.68)
		(end 101.2 121.92)
		(width 0.15)
		(layer "F.Cu")
		(net 270)
	)
	(segment
		(start 107.64 124.315)
		(end 106.175 122.85)
		(width 0.2)
		(layer "F.Cu")
		(net 270)
	)
	(via
		(at 103.15 122.05)
		(size 0.45)
		(drill 0.1)
		(layers "F.Cu" "B.Cu")
		(free yes)
		(net 270)
	)
	(via
		(at 101.9 121.6)
		(size 0.45)
		(drill 0.1)
		(layers "F.Cu" "B.Cu")
		(free yes)
		(net 270)
	)
	(via
		(at 102.65 122.05)
		(size 0.45)
		(drill 0.1)
		(layers "F.Cu" "B.Cu")
		(free yes)
		(net 270)
	)
	(via
		(at 102.9 121.6)
		(size 0.45)
		(drill 0.1)
		(layers "F.Cu" "B.Cu")
		(free yes)
		(net 270)
	)
	(via
		(at 102.4 121.6)
		(size 0.45)
		(drill 0.1)
		(layers "F.Cu" "B.Cu")
		(free yes)
		(net 270)
	)
	(via
		(at 102.15 122.05)
		(size 0.45)
		(drill 0.1)
		(layers "F.Cu" "B.Cu")
		(free yes)
		(net 270)
	)
	(via
		(at 98.135 127.405)
		(size 0.45)
		(drill 0.1)
		(layers "F.Cu" "B.Cu")
		(net 270)
	)
	(segment
		(start 89.94 126.25)
		(end 90.55 126.86)
		(width 0.15)
		(layer "B.Cu")
		(net 270)
	)
	(segment
		(start 68.895 124.035)
		(end 69.04 124.18)
		(width 0.15)
		(layer "B.Cu")
		(net 270)
	)
	(segment
		(start 90.55 126.86)
		(end 91.095 127.405)
		(width 0.15)
		(layer "B.Cu")
		(net 270)
	)
	(segment
		(start 68.835 126.845)
		(end 69.435 127.445)
		(width 0.15)
		(layer "B.Cu")
		(net 270)
	)
	(segment
		(start 68.165 118.57)
		(end 68.165 118.98)
		(width 0.15)
		(layer "B.Cu")
		(net 270)
	)
	(segment
		(start 91.095 127.405)
		(end 98.135 127.405)
		(width 0.15)
		(layer "B.Cu")
		(net 270)
	)
	(segment
		(start 69.435 127.445)
		(end 69.945 127.955)
		(width 0.15)
		(layer "B.Cu")
		(net 270)
	)
	(segment
		(start 67.4 126.38)
		(end 67.73 126.71)
		(width 0.15)
		(layer "B.Cu")
		(net 270)
	)
	(segment
		(start 73.65 127.955)
		(end 86.11 127.955)
		(width 0.15)
		(layer "B.Cu")
		(net 270)
	)
	(segment
		(start 86.11 127.955)
		(end 87.725 126.34)
		(width 0.15)
		(layer "B.Cu")
		(net 270)
	)
	(segment
		(start 67.4 125.98)
		(end 67.4 126.38)
		(width 0.15)
		(layer "B.Cu")
		(net 270)
	)
	(segment
		(start 69.945 127.955)
		(end 73.65 127.955)
		(width 0.15)
		(layer "B.Cu")
		(net 270)
	)
	(segment
		(start 68.635 123.775)
		(end 68.895 124.035)
		(width 0.15)
		(layer "B.Cu")
		(net 270)
	)
	(segment
		(start 89.32 126.25)
		(end 89.94 126.25)
		(width 0.15)
		(layer "B.Cu")
		(net 270)
	)
	(segment
		(start 67.62 125.42)
		(end 67.4 125.64)
		(width 0.15)
		(layer "B.Cu")
		(net 270)
	)
	(segment
		(start 67.725 125.315)
		(end 67.62 125.42)
		(width 0.15)
		(layer "B.Cu")
		(net 270)
	)
	(segment
		(start 87.725 126.34)
		(end 87.815 126.25)
		(width 0.15)
		(layer "B.Cu")
		(net 270)
	)
	(segment
		(start 68.265 125.315)
		(end 67.725 125.315)
		(width 0.15)
		(layer "B.Cu")
		(net 270)
	)
	(segment
		(start 69.04 124.98)
		(end 68.84 125.18)
		(width 0.15)
		(layer "B.Cu")
		(net 270)
	)
	(segment
		(start 68.71 126.845)
		(end 68.835 126.845)
		(width 0.15)
		(layer "B.Cu")
		(net 270)
	)
	(segment
		(start 68.905 119.72)
		(end 68.905 120.44)
		(width 0.15)
		(layer "B.Cu")
		(net 270)
	)
	(segment
		(start 67.73 126.71)
		(end 67.865 126.845)
		(width 0.15)
		(layer "B.Cu")
		(net 270)
	)
	(segment
		(start 67.865 126.845)
		(end 68.71 126.845)
		(width 0.15)
		(layer "B.Cu")
		(net 270)
	)
	(segment
		(start 68.705 125.315)
		(end 68.265 125.315)
		(width 0.15)
		(layer "B.Cu")
		(net 270)
	)
	(segment
		(start 67.4 125.64)
		(end 67.4 125.98)
		(width 0.15)
		(layer "B.Cu")
		(net 270)
	)
	(segment
		(start 67.76 120.845)
		(end 67.48 121.125)
		(width 0.15)
		(layer "B.Cu")
		(net 270)
	)
	(segment
		(start 87.815 126.25)
		(end 89.32 126.25)
		(width 0.15)
		(layer "B.Cu")
		(net 270)
	)
	(segment
		(start 68.165 118.98)
		(end 68.905 119.72)
		(width 0.15)
		(layer "B.Cu")
		(net 270)
	)
	(segment
		(start 68.84 125.18)
		(end 68.705 125.315)
		(width 0.15)
		(layer "B.Cu")
		(net 270)
	)
	(segment
		(start 109.1 112.485)
		(end 109.1 117)
		(width 0.15)
		(layer "B.Cu")
		(net 270)
	)
	(segment
		(start 67.48 121.125)
		(end 67.48 121.91)
		(width 0.15)
		(layer "B.Cu")
		(net 270)
	)
	(segment
		(start 67.66 123.775)
		(end 68.635 123.775)
		(width 0.15)
		(layer "B.Cu")
		(net 270)
	)
	(segment
		(start 103.25 113.985)
		(end 103.25 116.95)
		(width 0.2)
		(layer "B.Cu")
		(net 270)
	)
	(segment
		(start 67.48 121.91)
		(end 67.48 123.595)
		(width 0.15)
		(layer "B.Cu")
		(net 270)
	)
	(segment
		(start 69.04 124.88)
		(end 69.04 124.98)
		(width 0.15)
		(layer "B.Cu")
		(net 270)
	)
	(segment
		(start 68.905 120.44)
		(end 68.5 120.845)
		(width 0.15)
		(layer "B.Cu")
		(net 270)
	)
	(segment
		(start 67.48 123.595)
		(end 67.66 123.775)
		(width 0.15)
		(layer "B.Cu")
		(net 270)
	)
	(segment
		(start 68.5 120.845)
		(end 67.76 120.845)
		(width 0.15)
		(layer "B.Cu")
		(net 270)
	)
	(segment
		(start 69.04 124.18)
		(end 69.04 124.88)
		(width 0.15)
		(layer "B.Cu")
		(net 270)
	)
	(via
		(at 46 126)
		(size 0.45)
		(drill 0.1)
		(layers "F.Cu" "B.Cu")
		(net 271)
	)
	(via
		(at 55 115.112)
		(size 0.45)
		(drill 0.1)
		(layers "F.Cu" "B.Cu")
		(net 271)
	)
	(segment
		(start 47 126)
		(end 46 126)
		(width 0.15)
		(layer "In3.Cu")
		(net 271)
	)
	(segment
		(start 49.5 115.8)
		(end 48.29 117.01)
		(width 0.15)
		(layer "In3.Cu")
		(net 271)
	)
	(segment
		(start 55 115.112)
		(end 54.312 115.8)
		(width 0.15)
		(layer "In3.Cu")
		(net 271)
	)
	(segment
		(start 54.312 115.8)
		(end 49.5 115.8)
		(width 0.15)
		(layer "In3.Cu")
		(net 271)
	)
	(segment
		(start 47.625 122.134669)
		(end 47.625 125.375)
		(width 0.15)
		(layer "In3.Cu")
		(net 271)
	)
	(segment
		(start 47.625 125.375)
		(end 47 126)
		(width 0.15)
		(layer "In3.Cu")
		(net 271)
	)
	(segment
		(start 48.29 121.469669)
		(end 47.625 122.134669)
		(width 0.15)
		(layer "In3.Cu")
		(net 271)
	)
	(segment
		(start 48.29 117.01)
		(end 48.29 121.469669)
		(width 0.15)
		(layer "In3.Cu")
		(net 271)
	)
	(segment
		(start 46.4 126.95)
		(end 46.4 126.4)
		(width 0.155)
		(layer "B.Cu")
		(net 271)
	)
	(segment
		(start 55 115.112)
		(end 54.437 115.112)
		(width 0.15)
		(layer "B.Cu")
		(net 271)
	)
	(segment
		(start 46.4 126.4)
		(end 46 126)
		(width 0.155)
		(layer "B.Cu")
		(net 271)
	)
	(via
		(at 45.3 126)
		(size 0.45)
		(drill 0.1)
		(layers "F.Cu" "B.Cu")
		(net 272)
	)
	(via
		(at 47.865 119.68)
		(size 0.45)
		(drill 0.1)
		(layers "F.Cu" "B.Cu")
		(net 272)
	)
	(via
		(at 50.75 112.95)
		(size 0.45)
		(drill 0.1)
		(layers "F.Cu" "B.Cu")
		(net 272)
	)
	(segment
		(start 47.565 119.98)
		(end 47.3 119.98)
		(width 0.155)
		(layer "In3.Cu")
		(net 272)
	)
	(segment
		(start 47.3 119.67)
		(end 47.3 119.46)
		(width 0.155)
		(layer "In3.Cu")
		(net 272)
	)
	(segment
		(start 47.3 119.98)
		(end 47.3 119.84)
		(width 0.155)
		(layer "In3.Cu")
		(net 272)
	)
	(segment
		(start 47.3 125.2)
		(end 47.3 119.98)
		(width 0.155)
		(layer "In3.Cu")
		(net 272)
	)
	(segment
		(start 47.865 119.68)
		(end 47.565 119.98)
		(width 0.155)
		(layer "In3.Cu")
		(net 272)
	)
	(segment
		(start 50.75 114.15)
		(end 47.3 117.6)
		(width 0.155)
		(layer "In3.Cu")
		(net 272)
	)
	(segment
		(start 45.8 125.5)
		(end 47 125.5)
		(width 0.155)
		(layer "In3.Cu")
		(net 272)
	)
	(segment
		(start 47.3 119.57)
		(end 47.3 119.46)
		(width 0.155)
		(layer "In3.Cu")
		(net 272)
	)
	(segment
		(start 47.3 119.84)
		(end 47.3 119.67)
		(width 0.155)
		(layer "In3.Cu")
		(net 272)
	)
	(segment
		(start 47.3 119.77)
		(end 47.3 119.84)
		(width 0.155)
		(layer "In3.Cu")
		(net 272)
	)
	(segment
		(start 47 125.5)
		(end 47.3 125.2)
		(width 0.155)
		(layer "In3.Cu")
		(net 272)
	)
	(segment
		(start 50.75 112.95)
		(end 50.75 114.15)
		(width 0.155)
		(layer "In3.Cu")
		(net 272)
	)
	(segment
		(start 47.3 117.6)
		(end 47.3 119.46)
		(width 0.155)
		(layer "In3.Cu")
		(net 272)
	)
	(segment
		(start 45.3 126)
		(end 45.8 125.5)
		(width 0.155)
		(layer "In3.Cu")
		(net 272)
	)
	(segment
		(start 50.75 112.95)
		(end 50.775 112.925)
		(width 0.2)
		(layer "B.Cu")
		(net 272)
	)
	(segment
		(start 48.47 119.18)
		(end 48.83 118.82)
		(width 0.155)
		(layer "B.Cu")
		(net 272)
	)
	(segment
		(start 44.9 126.95)
		(end 44.9 126.4)
		(width 0.155)
		(layer "B.Cu")
		(net 272)
	)
	(segment
		(start 44.9 126.4)
		(end 45.3 126)
		(width 0.155)
		(layer "B.Cu")
		(net 272)
	)
	(segment
		(start 50.775 112.925)
		(end 51.6 112.925)
		(width 0.2)
		(layer "B.Cu")
		(net 272)
	)
	(segment
		(start 47.865 119.68)
		(end 48.26 119.68)
		(width 0.155)
		(layer "B.Cu")
		(net 272)
	)
	(segment
		(start 49.1 118.55)
		(end 48.83 118.82)
		(width 0.15)
		(layer "B.Cu")
		(net 272)
	)
	(segment
		(start 48.47 119.47)
		(end 48.47 119.18)
		(width 0.155)
		(layer "B.Cu")
		(net 272)
	)
	(segment
		(start 48.26 119.68)
		(end 48.47 119.47)
		(width 0.155)
		(layer "B.Cu")
		(net 272)
	)
	(segment
		(start 49.15 118.55)
		(end 49.1 118.55)
		(width 0.15)
		(layer "B.Cu")
		(net 272)
	)
	(via
		(at 60.85 102.6775)
		(size 0.45)
		(drill 0.1)
		(layers "F.Cu" "B.Cu")
		(net 273)
	)
	(via
		(at 55.45 116.8)
		(size 0.45)
		(drill 0.1)
		(layers "F.Cu" "B.Cu")
		(net 273)
	)
	(segment
		(start 57.3 104.24)
		(end 57.3 114.7)
		(width 0.125)
		(layer "In5.Cu")
		(net 273)
	)
	(segment
		(start 55.4 116.75)
		(end 55.45 116.8)
		(width 0.125)
		(layer "In5.Cu")
		(net 273)
	)
	(segment
		(start 60.7 102.8275)
		(end 60.7 103.15)
		(width 0.125)
		(layer "In5.Cu")
		(net 273)
	)
	(segment
		(start 60.16 103.69)
		(end 57.85 103.69)
		(width 0.125)
		(layer "In5.Cu")
		(net 273)
	)
	(segment
		(start 55.4 116.6)
		(end 55.4 116.75)
		(width 0.125)
		(layer "In5.Cu")
		(net 273)
	)
	(segment
		(start 60.7 103.15)
		(end 60.16 103.69)
		(width 0.125)
		(layer "In5.Cu")
		(net 273)
	)
	(segment
		(start 60.85 102.6775)
		(end 60.7 102.8275)
		(width 0.125)
		(layer "In5.Cu")
		(net 273)
	)
	(segment
		(start 57.3 114.7)
		(end 55.4 116.6)
		(width 0.125)
		(layer "In5.Cu")
		(net 273)
	)
	(segment
		(start 57.85 103.69)
		(end 57.3 104.24)
		(width 0.125)
		(layer "In5.Cu")
		(net 273)
	)
	(segment
		(start 55.45 117.565)
		(end 54.4 118.615)
		(width 0.15)
		(layer "B.Cu")
		(net 273)
	)
	(segment
		(start 61.4725 102.6775)
		(end 62.05 102.1)
		(width 0.125)
		(layer "B.Cu")
		(net 273)
	)
	(segment
		(start 54.4 119.8)
		(end 54.4 119.385)
		(width 0.15)
		(layer "B.Cu")
		(net 273)
	)
	(segment
		(start 62.05 102.1)
		(end 62.95 102.1)
		(width 0.125)
		(layer "B.Cu")
		(net 273)
	)
	(segment
		(start 60.85 102.6775)
		(end 61.4725 102.6775)
		(width 0.125)
		(layer "B.Cu")
		(net 273)
	)
	(segment
		(start 54.85 120.25)
		(end 54.4 119.8)
		(width 0.15)
		(layer "B.Cu")
		(net 273)
	)
	(segment
		(start 55.45 116.8)
		(end 55.45 117.565)
		(width 0.15)
		(layer "B.Cu")
		(net 273)
	)
	(segment
		(start 54.85 121.11)
		(end 54.85 120.25)
		(width 0.15)
		(layer "B.Cu")
		(net 273)
	)
	(segment
		(start 54.4 119.385)
		(end 54.4 118.615)
		(width 0.15)
		(layer "B.Cu")
		(net 273)
	)
	(segment
		(start 110.597323 72.005136)
		(end 110.597323 72.730136)
		(width 0.125)
		(layer "F.Cu")
		(net 274)
	)
	(segment
		(start 110.472323 73.784455)
		(end 109.995 74.261778)
		(width 0.125)
		(layer "F.Cu")
		(net 274)
	)
	(segment
		(start 109.995 76.888223)
		(end 110.433483 77.326706)
		(width 0.125)
		(layer "F.Cu")
		(net 274)
	)
	(segment
		(start 109.995 74.261778)
		(end 109.995 76.888223)
		(width 0.125)
		(layer "F.Cu")
		(net 274)
	)
	(segment
		(start 110.597323 72.730136)
		(end 110.472323 72.855136)
		(width 0.125)
		(layer "F.Cu")
		(net 274)
	)
	(segment
		(start 110.472323 72.855136)
		(end 110.472323 73.784455)
		(width 0.125)
		(layer "F.Cu")
		(net 274)
	)
	(segment
		(start 110.433483 77.326706)
		(end 110.663294 77.326706)
		(width 0.125)
		(layer "F.Cu")
		(net 274)
	)
	(via
		(at 110.663294 77.326706)
		(size 0.45)
		(drill 0.1)
		(layers "F.Cu" "B.Cu")
		(net 274)
	)
	(segment
		(start 111.375 79.531778)
		(end 111.375 78.268223)
		(width 0.125)
		(layer "B.Cu")
		(net 274)
	)
	(segment
		(start 108.755 81.681778)
		(end 108.755 80.691778)
		(width 0.125)
		(layer "B.Cu")
		(net 274)
	)
	(segment
		(start 111.375 78.268223)
		(end 110.663294 77.556517)
		(width 0.125)
		(layer "B.Cu")
		(net 274)
	)
	(segment
		(start 103.215 91.201778)
		(end 103.215 87.221778)
		(width 0.125)
		(layer "B.Cu")
		(net 274)
	)
	(segment
		(start 110.663294 77.556517)
		(end 110.663294 77.326706)
		(width 0.125)
		(layer "B.Cu")
		(net 274)
	)
	(segment
		(start 96.385 94.55)
		(end 99.866778 94.55)
		(width 0.125)
		(layer "B.Cu")
		(net 274)
	)
	(segment
		(start 96.035 94.9)
		(end 96.385 94.55)
		(width 0.125)
		(layer "B.Cu")
		(net 274)
	)
	(segment
		(start 108.755 80.691778)
		(end 109.171778 80.275)
		(width 0.125)
		(layer "B.Cu")
		(net 274)
	)
	(segment
		(start 99.866778 94.55)
		(end 103.215 91.201778)
		(width 0.125)
		(layer "B.Cu")
		(net 274)
	)
	(segment
		(start 103.215 87.221778)
		(end 108.755 81.681778)
		(width 0.125)
		(layer "B.Cu")
		(net 274)
	)
	(segment
		(start 109.171778 80.275)
		(end 110.631778 80.275)
		(width 0.125)
		(layer "B.Cu")
		(net 274)
	)
	(segment
		(start 110.631778 80.275)
		(end 111.375 79.531778)
		(width 0.125)
		(layer "B.Cu")
		(net 274)
	)
	(segment
		(start 53.35 122.35)
		(end 53.35 120.75)
		(width 0.155)
		(layer "B.Cu")
		(net 275)
	)
	(segment
		(start 53.6 122.6)
		(end 53.35 122.35)
		(width 0.155)
		(layer "B.Cu")
		(net 275)
	)
	(segment
		(start 54.35 122.25)
		(end 54 122.6)
		(width 0.155)
		(layer "B.Cu")
		(net 275)
	)
	(segment
		(start 54 122.6)
		(end 53.6 122.6)
		(width 0.155)
		(layer "B.Cu")
		(net 275)
	)
	(segment
		(start 52.9 118.202499)
		(end 53.2505 117.851999)
		(width 0.155)
		(layer "B.Cu")
		(net 275)
	)
	(segment
		(start 53.2505 117.851999)
		(end 53.2505 117.6355)
		(width 0.155)
		(layer "B.Cu")
		(net 275)
	)
	(segment
		(start 52.9 120.3)
		(end 52.9 119.385)
		(width 0.155)
		(layer "B.Cu")
		(net 275)
	)
	(segment
		(start 52.9 119.385)
		(end 52.9 118.615)
		(width 0.155)
		(layer "B.Cu")
		(net 275)
	)
	(segment
		(start 53.2505 117.6355)
		(end 52.9 117.285)
		(width 0.155)
		(layer "B.Cu")
		(net 275)
	)
	(segment
		(start 53.35 120.75)
		(end 52.9 120.3)
		(width 0.155)
		(layer "B.Cu")
		(net 275)
	)
	(segment
		(start 52.9 117.285)
		(end 51.9 117.285)
		(width 0.155)
		(layer "B.Cu")
		(net 275)
	)
	(segment
		(start 52.9 118.615)
		(end 52.9 118.202499)
		(width 0.155)
		(layer "B.Cu")
		(net 275)
	)
	(segment
		(start 54.35 121.11)
		(end 54.35 122.25)
		(width 0.155)
		(layer "B.Cu")
		(net 275)
	)
	(via
		(at 51.35 118)
		(size 0.45)
		(drill 0.1)
		(layers "F.Cu" "B.Cu")
		(net 276)
	)
	(via
		(at 60.75 101.3125)
		(size 0.45)
		(drill 0.1)
		(layers "F.Cu" "B.Cu")
		(net 276)
	)
	(segment
		(start 59.98 103.36)
		(end 57.78 103.36)
		(width 0.125)
		(layer "In5.Cu")
		(net 276)
	)
	(segment
		(start 52.75 116.6)
		(end 51.35 118)
		(width 0.125)
		(layer "In5.Cu")
		(net 276)
	)
	(segment
		(start 60.75 101.3125)
		(end 60.4 101.6625)
		(width 0.125)
		(layer "In5.Cu")
		(net 276)
	)
	(segment
		(start 57.78 103.36)
		(end 52.75 108.39)
		(width 0.125)
		(layer "In5.Cu")
		(net 276)
	)
	(segment
		(start 52.75 108.39)
		(end 52.75 116.6)
		(width 0.125)
		(layer "In5.Cu")
		(net 276)
	)
	(segment
		(start 60.4 102.94)
		(end 59.98 103.36)
		(width 0.125)
		(layer "In5.Cu")
		(net 276)
	)
	(segment
		(start 60.4 101.6625)
		(end 60.4 102.94)
		(width 0.125)
		(layer "In5.Cu")
		(net 276)
	)
	(segment
		(start 52.4 118.298959)
		(end 52.4 118.2)
		(width 0.15)
		(layer "B.Cu")
		(net 276)
	)
	(segment
		(start 52.2 118)
		(end 51.55 118)
		(width 0.15)
		(layer "B.Cu")
		(net 276)
	)
	(segment
		(start 52.4 118.298959)
		(end 52.4 118.615)
		(width 0.15)
		(layer "B.Cu")
		(net 276)
	)
	(segment
		(start 52.4 118.2)
		(end 52.2 118)
		(width 0.15)
		(layer "B.Cu")
		(net 276)
	)
	(segment
		(start 51.85 120.55)
		(end 52.4 120)
		(width 0.15)
		(layer "B.Cu")
		(net 276)
	)
	(segment
		(start 52.4 118.615)
		(end 52.4 119.385)
		(width 0.15)
		(layer "B.Cu")
		(net 276)
	)
	(segment
		(start 51.85 121.11)
		(end 51.85 120.55)
		(width 0.15)
		(layer "B.Cu")
		(net 276)
	)
	(segment
		(start 60.75 101.3125)
		(end 60.7625 101.3)
		(width 0.15)
		(layer "B.Cu")
		(net 276)
	)
	(segment
		(start 60.7625 101.3)
		(end 62.95 101.3)
		(width 0.15)
		(layer "B.Cu")
		(net 276)
	)
	(segment
		(start 52.4 120)
		(end 52.4 119.385)
		(width 0.15)
		(layer "B.Cu")
		(net 276)
	)
	(segment
		(start 51.55 118)
		(end 51.35 118)
		(width 0.15)
		(layer "B.Cu")
		(net 276)
	)
	(segment
		(start 74 113.521323)
		(end 74 115.115)
		(width 0.15)
		(layer "F.Cu")
		(net 277)
	)
	(segment
		(start 74.072001 113.449322)
		(end 74 113.521323)
		(width 0.15)
		(layer "F.Cu")
		(net 277)
	)
	(segment
		(start 74 115.885)
		(end 74 115.115)
		(width 0.15)
		(layer "F.Cu")
		(net 277)
	)
	(segment
		(start 74 115.885)
		(end 74 118.11493)
		(width 0.15)
		(layer "F.Cu")
		(net 277)
	)
	(via
		(at 74.072001 113.449322)
		(size 0.45)
		(drill 0.1)
		(layers "F.Cu" "B.Cu")
		(net 277)
	)
	(via
		(at 70.5 101.1)
		(size 0.45)
		(drill 0.1)
		(layers "F.Cu" "B.Cu")
		(net 277)
	)
	(segment
		(start 72 108.7)
		(end 72 104.85)
		(width 0.125)
		(layer "In3.Cu")
		(net 277)
	)
	(segment
		(start 71.5 104.35)
		(end 71.5 102.25)
		(width 0.125)
		(layer "In3.Cu")
		(net 277)
	)
	(segment
		(start 73.186339 109.886339)
		(end 72 108.7)
		(width 0.125)
		(layer "In3.Cu")
		(net 277)
	)
	(segment
		(start 71 101.1)
		(end 70.5 101.1)
		(width 0.125)
		(layer "In3.Cu")
		(net 277)
	)
	(segment
		(start 71.5 102.25)
		(end 71.15 101.9)
		(width 0.125)
		(layer "In3.Cu")
		(net 277)
	)
	(segment
		(start 73.186339 112.563661)
		(end 73.186339 109.886339)
		(width 0.125)
		(layer "In3.Cu")
		(net 277)
	)
	(segment
		(start 72 104.85)
		(end 71.5 104.35)
		(width 0.125)
		(layer "In3.Cu")
		(net 277)
	)
	(segment
		(start 71.15 101.9)
		(end 71.15 101.25)
		(width 0.125)
		(layer "In3.Cu")
		(net 277)
	)
	(segment
		(start 71.15 101.25)
		(end 71 101.1)
		(width 0.125)
		(layer "In3.Cu")
		(net 277)
	)
	(segment
		(start 74.072001 113.449322)
		(end 73.186339 112.563661)
		(width 0.125)
		(layer "In3.Cu")
		(net 277)
	)
	(segment
		(start 69.65 101.3)
		(end 70.3 101.3)
		(width 0.15)
		(layer "B.Cu")
		(net 277)
	)
	(segment
		(start 70.3 101.3)
		(end 70.5 101.1)
		(width 0.15)
		(layer "B.Cu")
		(net 277)
	)
	(segment
		(start 76 115.115)
		(end 76 114.6)
		(width 0.15)
		(layer "F.Cu")
		(net 278)
	)
	(segment
		(start 76 116.45)
		(end 76 115.885)
		(width 0.15)
		(layer "F.Cu")
		(net 278)
	)
	(segment
		(start 75.9 116.55)
		(end 76 116.45)
		(width 0.15)
		(layer "F.Cu")
		(net 278)
	)
	(segment
		(start 76 115.885)
		(end 76 115.115)
		(width 0.15)
		(layer "F.Cu")
		(net 278)
	)
	(segment
		(start 75.9 116.7)
		(end 75.9 116.55)
		(width 0.15)
		(layer "F.Cu")
		(net 278)
	)
	(via
		(at 70.425 102.225)
		(size 0.45)
		(drill 0.1)
		(layers "F.Cu" "B.Cu")
		(net 278)
	)
	(via
		(at 75.9 116.7)
		(size 0.45)
		(drill 0.1)
		(layers "F.Cu" "B.Cu")
		(net 278)
	)
	(via
		(at 76 114.6)
		(size 0.45)
		(drill 0.1)
		(layers "F.Cu" "B.Cu")
		(net 278)
	)
	(segment
		(start 72.9 110.05)
		(end 72.9 113.05)
		(width 0.15)
		(layer "In3.Cu")
		(net 278)
	)
	(segment
		(start 72.9 113.05)
		(end 74 114.15)
		(width 0.15)
		(layer "In3.Cu")
		(net 278)
	)
	(segment
		(start 71.2 102.5)
		(end 71.2 104.45)
		(width 0.15)
		(layer "In3.Cu")
		(net 278)
	)
	(segment
		(start 70.925 102.225)
		(end 71.2 102.5)
		(width 0.15)
		(layer "In3.Cu")
		(net 278)
	)
	(segment
		(start 70.425 102.225)
		(end 70.925 102.225)
		(width 0.15)
		(layer "In3.Cu")
		(net 278)
	)
	(segment
		(start 74 114.15)
		(end 75.55 114.15)
		(width 0.15)
		(layer "In3.Cu")
		(net 278)
	)
	(segment
		(start 75.55 114.15)
		(end 76 114.6)
		(width 0.15)
		(layer "In3.Cu")
		(net 278)
	)
	(segment
		(start 71.7 108.85)
		(end 72.9 110.05)
		(width 0.15)
		(layer "In3.Cu")
		(net 278)
	)
	(segment
		(start 71.7 104.95)
		(end 71.7 108.85)
		(width 0.15)
		(layer "In3.Cu")
		(net 278)
	)
	(segment
		(start 71.2 104.45)
		(end 71.7 104.95)
		(width 0.15)
		(layer "In3.Cu")
		(net 278)
	)
	(segment
		(start 77.4 120.9)
		(end 76 120.9)
		(width 0.15)
		(layer "In5.Cu")
		(net 278)
	)
	(segment
		(start 76 120.9)
		(end 75.54992 120.44992)
		(width 0.15)
		(layer "In5.Cu")
		(net 278)
	)
	(segment
		(start 75.9 116.7)
		(end 77.8 118.6)
		(width 0.15)
		(layer "In5.Cu")
		(net 278)
	)
	(segment
		(start 75.54992 120.44992)
		(end 75.54992 120.065)
		(width 0.15)
		(layer "In5.Cu")
		(net 278)
	)
	(segment
		(start 78.3 119.05)
		(end 78.3 120)
		(width 0.15)
		(layer "In5.Cu")
		(net 278)
	)
	(segment
		(start 78.3 120)
		(end 77.4 120.9)
		(width 0.15)
		(layer "In5.Cu")
		(net 278)
	)
	(segment
		(start 77.8 118.6)
		(end 77.85 118.6)
		(width 0.15)
		(layer "In5.Cu")
		(net 278)
	)
	(segment
		(start 77.85 118.6)
		(end 78.3 119.05)
		(width 0.15)
		(layer "In5.Cu")
		(net 278)
	)
	(segment
		(start 70.425 102.225)
		(end 70.3 102.1)
		(width 0.15)
		(layer "B.Cu")
		(net 278)
	)
	(segment
		(start 70.3 102.1)
		(end 69.65 102.1)
		(width 0.15)
		(layer "B.Cu")
		(net 278)
	)
	(via
		(at 59.585 75.735)
		(size 0.45)
		(drill 0.1)
		(layers "F.Cu" "B.Cu")
		(net 279)
	)
	(via
		(at 58.4 110.53)
		(size 0.45)
		(drill 0.1)
		(layers "F.Cu" "B.Cu")
		(net 279)
	)
	(segment
		(start 57.86 77.26)
		(end 52.2625 82.8575)
		(width 0.125)
		(layer "In3.Cu")
		(net 279)
	)
	(segment
		(start 52.2625 82.8575)
		(end 52.2625 97.0725)
		(width 0.125)
		(layer "In3.Cu")
		(net 279)
	)
	(segment
		(start 52.8 97.61)
		(end 52.8 109)
		(width 0.125)
		(layer "In3.Cu")
		(net 279)
	)
	(segment
		(start 57.17 109.3)
		(end 58.4 110.53)
		(width 0.125)
		(layer "In3.Cu")
		(net 279)
	)
	(segment
		(start 58.63 77.26)
		(end 57.86 77.26)
		(width 0.125)
		(layer "In3.Cu")
		(net 279)
	)
	(segment
		(start 59.585 75.735)
		(end 59.585 76.305)
		(width 0.125)
		(layer "In3.Cu")
		(net 279)
	)
	(segment
		(start 53.1 109.3)
		(end 57.17 109.3)
		(width 0.125)
		(layer "In3.Cu")
		(net 279)
	)
	(segment
		(start 59.585 76.305)
		(end 58.63 77.26)
		(width 0.125)
		(layer "In3.Cu")
		(net 279)
	)
	(segment
		(start 52.2625 97.0725)
		(end 52.8 97.61)
		(width 0.125)
		(layer "In3.Cu")
		(net 279)
	)
	(segment
		(start 52.8 109)
		(end 53.1 109.3)
		(width 0.125)
		(layer "In3.Cu")
		(net 279)
	)
	(segment
		(start 59.83 75.49)
		(end 59.83 74.89)
		(width 0.15)
		(layer "B.Cu")
		(net 279)
	)
	(segment
		(start 60.35 74.37)
		(end 60.35 73.6)
		(width 0.15)
		(layer "B.Cu")
		(net 279)
	)
	(segment
		(start 59.585 75.735)
		(end 59.83 75.49)
		(width 0.15)
		(layer "B.Cu")
		(net 279)
	)
	(segment
		(start 58.4 110.53)
		(end 58.32 110.45)
		(width 0.15)
		(layer "B.Cu")
		(net 279)
	)
	(segment
		(start 58.32 110.45)
		(end 57.935 110.45)
		(width 0.15)
		(layer "B.Cu")
		(net 279)
	)
	(segment
		(start 59.83 74.89)
		(end 60.35 74.37)
		(width 0.15)
		(layer "B.Cu")
		(net 279)
	)
	(segment
		(start 89 112.115)
		(end 90 112.115)
		(width 0.125)
		(layer "B.Cu")
		(net 281)
	)
	(segment
		(start 89.25 111.5)
		(end 89.25 110.9)
		(width 0.15)
		(layer "B.Cu")
		(net 281)
	)
	(segment
		(start 89 111.75)
		(end 89.25 111.5)
		(width 0.15)
		(layer "B.Cu")
		(net 281)
	)
	(segment
		(start 89 112.115)
		(end 89 111.75)
		(width 0.15)
		(layer "B.Cu")
		(net 281)
	)
	(segment
		(start 112.55 117.15)
		(end 112.55 116.685)
		(width 0.13)
		(layer "F.Cu")
		(net 282)
	)
	(segment
		(start 112.65001 118.2)
		(end 112.65001 117.25001)
		(width 0.13)
		(layer "F.Cu")
		(net 282)
	)
	(segment
		(start 112.55 115.793749)
		(end 112.55 116.563749)
		(width 0.13)
		(layer "F.Cu")
		(net 282)
	)
	(segment
		(start 112.55 114.95)
		(end 112.55 115.915)
		(width 0.13)
		(layer "F.Cu")
		(net 282)
	)
	(segment
		(start 112.6 114.9)
		(end 112.55 114.95)
		(width 0.13)
		(layer "F.Cu")
		(net 282)
	)
	(segment
		(start 112.65001 117.25001)
		(end 112.55 117.15)
		(width 0.13)
		(layer "F.Cu")
		(net 282)
	)
	(segment
		(start 106.745 105.145)
		(end 106.7 105.1)
		(width 0.13)
		(layer "F.Cu")
		(net 282)
	)
	(segment
		(start 107.689938 105.145)
		(end 106.745 105.145)
		(width 0.13)
		(layer "F.Cu")
		(net 282)
	)
	(via
		(at 106.7 105.1)
		(size 0.45)
		(drill 0.1)
		(layers "F.Cu" "B.Cu")
		(net 282)
	)
	(via
		(at 112.6 114.9)
		(size 0.45)
		(drill 0.1)
		(layers "F.Cu" "B.Cu")
		(net 282)
	)
	(segment
		(start 106.7 105.1)
		(end 107.8 105.1)
		(width 0.13)
		(layer "B.Cu")
		(net 282)
	)
	(segment
		(start 109.8 113.8)
		(end 110.9 114.9)
		(width 0.13)
		(layer "B.Cu")
		(net 282)
	)
	(segment
		(start 107.8 105.1)
		(end 109.8 107.1)
		(width 0.13)
		(layer "B.Cu")
		(net 282)
	)
	(segment
		(start 110.9 114.9)
		(end 112.6 114.9)
		(width 0.13)
		(layer "B.Cu")
		(net 282)
	)
	(segment
		(start 109.8 107.1)
		(end 109.8 113.8)
		(width 0.13)
		(layer "B.Cu")
		(net 282)
	)
	(segment
		(start 114.55 115.915)
		(end 114.55 115.05)
		(width 0.13)
		(layer "F.Cu")
		(net 283)
	)
	(segment
		(start 114.55 117.15)
		(end 114.5 117.2)
		(width 0.13)
		(layer "F.Cu")
		(net 283)
	)
	(segment
		(start 106.68 104.48)
		(end 106.945 104.745)
		(width 0.13)
		(layer "F.Cu")
		(net 283)
	)
	(segment
		(start 114.55 116.563749)
		(end 114.55 115.793749)
		(width 0.13)
		(layer "F.Cu")
		(net 283)
	)
	(segment
		(start 106.945 104.745)
		(end 107.659948 104.745)
		(width 0.13)
		(layer "F.Cu")
		(net 283)
	)
	(segment
		(start 114.55 115.05)
		(end 114.5 115)
		(width 0.13)
		(layer "F.Cu")
		(net 283)
	)
	(segment
		(start 114.55 116.685)
		(end 114.55 117.15)
		(width 0.13)
		(layer "F.Cu")
		(net 283)
	)
	(via
		(at 106.68 104.48)
		(size 0.45)
		(drill 0.1)
		(layers "F.Cu" "B.Cu")
		(net 283)
	)
	(via
		(at 114.5 117.2)
		(size 0.45)
		(drill 0.1)
		(layers "F.Cu" "B.Cu")
		(net 283)
	)
	(via
		(at 114.5 115)
		(size 0.45)
		(drill 0.1)
		(layers "F.Cu" "B.Cu")
		(net 283)
	)
	(segment
		(start 116.1 121.1)
		(end 116.7 120.5)
		(width 0.13)
		(layer "In3.Cu")
		(net 283)
	)
	(segment
		(start 117.1 119.1)
		(end 116.4 118.4)
		(width 0.13)
		(layer "In3.Cu")
		(net 283)
	)
	(segment
		(start 114.5 118)
		(end 114.5 117.2)
		(width 0.13)
		(layer "In3.Cu")
		(net 283)
	)
	(segment
		(start 114.9 118.4)
		(end 114.5 118)
		(width 0.13)
		(layer "In3.Cu")
		(net 283)
	)
	(segment
		(start 114.2 120.6)
		(end 114.7 121.1)
		(width 0.13)
		(layer "In3.Cu")
		(net 283)
	)
	(segment
		(start 116.7 120.5)
		(end 116.7 120)
		(width 0.13)
		(layer "In3.Cu")
		(net 283)
	)
	(segment
		(start 117.1 119.6)
		(end 117.1 119.1)
		(width 0.13)
		(layer "In3.Cu")
		(net 283)
	)
	(segment
		(start 116.4 118.4)
		(end 114.9 118.4)
		(width 0.13)
		(layer "In3.Cu")
		(net 283)
	)
	(segment
		(start 116.7 120)
		(end 117.1 119.6)
		(width 0.13)
		(layer "In3.Cu")
		(net 283)
	)
	(segment
		(start 114.2 120.15)
		(end 114.2 120.6)
		(width 0.13)
		(layer "In3.Cu")
		(net 283)
	)
	(segment
		(start 114.7 121.1)
		(end 116.1 121.1)
		(width 0.13)
		(layer "In3.Cu")
		(net 283)
	)
	(segment
		(start 114.5 115)
		(end 113.95 114.45)
		(width 0.13)
		(layer "B.Cu")
		(net 283)
	)
	(segment
		(start 113.95 114.45)
		(end 110.95 114.45)
		(width 0.13)
		(layer "B.Cu")
		(net 283)
	)
	(segment
		(start 107.58 104.48)
		(end 106.68 104.48)
		(width 0.13)
		(layer "B.Cu")
		(net 283)
	)
	(segment
		(start 110.95 114.45)
		(end 110.1 113.6)
		(width 0.13)
		(layer "B.Cu")
		(net 283)
	)
	(segment
		(start 110.1 113.6)
		(end 110.1 107)
		(width 0.13)
		(layer "B.Cu")
		(net 283)
	)
	(segment
		(start 110.1 107)
		(end 107.58 104.48)
		(width 0.13)
		(layer "B.Cu")
		(net 283)
	)
	(segment
		(start 106.178015 116.818677)
		(end 106.178015 117.022785)
		(width 0.15)
		(layer "F.Cu")
		(net 284)
	)
	(segment
		(start 105.225 118.975)
		(end 105.225 117.725)
		(width 0.15)
		(layer "F.Cu")
		(net 284)
	)
	(segment
		(start 108.9 103.2)
		(end 109.289938 103.589938)
		(width 0.15)
		(layer "F.Cu")
		(net 284)
	)
	(segment
		(start 105.075 117.625)
		(end 104.8 117.625)
		(width 0.15)
		(layer "F.Cu")
		(net 284)
	)
	(segment
		(start 104.6 117.425)
		(end 104.6 116.885)
		(width 0.15)
		(layer "F.Cu")
		(net 284)
	)
	(segment
		(start 106.05 119.35)
		(end 105.6 119.35)
		(width 0.15)
		(layer "F.Cu")
		(net 284)
	)
	(segment
		(start 106.178015 117.022785)
		(end 105.95 117.2508)
		(width 0.15)
		(layer "F.Cu")
		(net 284)
	)
	(segment
		(start 104.8 117.625)
		(end 104.6 117.425)
		(width 0.15)
		(layer "F.Cu")
		(net 284)
	)
	(segment
		(start 105.5758 117.625)
		(end 105.95 117.2508)
		(width 0.15)
		(layer "F.Cu")
		(net 284)
	)
	(segment
		(start 105.325 117.625)
		(end 105.225 117.625)
		(width 0.15)
		(layer "F.Cu")
		(net 284)
	)
	(segment
		(start 105.225 117.625)
		(end 105.075 117.625)
		(width 0.15)
		(layer "F.Cu")
		(net 284)
	)
	(segment
		(start 105.225 117.725)
		(end 105.325 117.625)
		(width 0.15)
		(layer "F.Cu")
		(net 284)
	)
	(segment
		(start 105.225 117.725)
		(end 105.225 117.625)
		(width 0.15)
		(layer "F.Cu")
		(net 284)
	)
	(segment
		(start 105.225 117.725)
		(end 105.125 117.625)
		(width 0.15)
		(layer "F.Cu")
		(net 284)
	)
	(segment
		(start 105.125 117.625)
		(end 105.075 117.625)
		(width 0.15)
		(layer "F.Cu")
		(net 284)
	)
	(segment
		(start 105.6 119.35)
		(end 105.225 118.975)
		(width 0.15)
		(layer "F.Cu")
		(net 284)
	)
	(segment
		(start 109.289938 103.589938)
		(end 109.289938 104.345)
		(width 0.15)
		(layer "F.Cu")
		(net 284)
	)
	(segment
		(start 105.325 117.625)
		(end 105.5758 117.625)
		(width 0.15)
		(layer "F.Cu")
		(net 284)
	)
	(segment
		(start 104.6 116.885)
		(end 104.2 116.485)
		(width 0.15)
		(layer "F.Cu")
		(net 284)
	)
	(via
		(at 106.178015 116.818677)
		(size 0.45)
		(drill 0.1)
		(layers "F.Cu" "B.Cu")
		(net 284)
	)
	(via
		(at 108.9 103.2)
		(size 0.45)
		(drill 0.1)
		(layers "F.Cu" "B.Cu")
		(net 284)
	)
	(segment
		(start 107.443762 115.435)
		(end 108.065 115.435)
		(width 0.125)
		(layer "B.Cu")
		(net 284)
	)
	(segment
		(start 105.7 104.1)
		(end 105.7 105.5)
		(width 0.125)
		(layer "B.Cu")
		(net 284)
	)
	(segment
		(start 108.4875 102.7875)
		(end 107.0125 102.7875)
		(width 0.125)
		(layer "B.Cu")
		(net 284)
	)
	(segment
		(start 108.9 103.2)
		(end 108.4875 102.7875)
		(width 0.125)
		(layer "B.Cu")
		(net 284)
	)
	(segment
		(start 107.4 115.391238)
		(end 107.4 112.6)
		(width 0.125)
		(layer "B.Cu")
		(net 284)
	)
	(segment
		(start 107.4 107.2)
		(end 107.4 112.2)
		(width 0.125)
		(layer "B.Cu")
		(net 284)
	)
	(segment
		(start 106.178015 116.676985)
		(end 107.4 115.455)
		(width 0.125)
		(layer "B.Cu")
		(net 284)
	)
	(segment
		(start 107.35 105.9)
		(end 107.6 106.15)
		(width 0.125)
		(layer "B.Cu")
		(net 284)
	)
	(segment
		(start 107.4 115.455)
		(end 107.4 115.391238)
		(width 0.125)
		(layer "B.Cu")
		(net 284)
	)
	(segment
		(start 106.1 105.9)
		(end 107.35 105.9)
		(width 0.125)
		(layer "B.Cu")
		(net 284)
	)
	(segment
		(start 107.0125 102.7875)
		(end 105.7 104.1)
		(width 0.125)
		(layer "B.Cu")
		(net 284)
	)
	(segment
		(start 108.1 112.485)
		(end 107.515 112.485)
		(width 0.15)
		(layer "B.Cu")
		(net 284)
	)
	(segment
		(start 105.7 105.5)
		(end 106.1 105.9)
		(width 0.125)
		(layer "B.Cu")
		(net 284)
	)
	(segment
		(start 107.4 112.2)
		(end 107.4 112.6)
		(width 0.125)
		(layer "B.Cu")
		(net 284)
	)
	(segment
		(start 107.4 112.37)
		(end 107.515 112.485)
		(width 0.125)
		(layer "B.Cu")
		(net 284)
	)
	(segment
		(start 107.4 115.391238)
		(end 107.443762 115.435)
		(width 0.125)
		(layer "B.Cu")
		(net 284)
	)
	(segment
		(start 107.6 106.15)
		(end 107.6 107)
		(width 0.125)
		(layer "B.Cu")
		(net 284)
	)
	(segment
		(start 107.6 107)
		(end 107.4 107.2)
		(width 0.125)
		(layer "B.Cu")
		(net 284)
	)
	(segment
		(start 106.178015 116.818677)
		(end 106.178015 116.676985)
		(width 0.125)
		(layer "B.Cu")
		(net 284)
	)
	(segment
		(start 107.4 112.2)
		(end 107.4 112.37)
		(width 0.125)
		(layer "B.Cu")
		(net 284)
	)
	(segment
		(start 107.4 112.6)
		(end 107.515 112.485)
		(width 0.125)
		(layer "B.Cu")
		(net 284)
	)
	(segment
		(start 71.015 100.65)
		(end 71.315 100.95)
		(width 0.15)
		(layer "B.Cu")
		(net 285)
	)
	(segment
		(start 70.3 100.65)
		(end 71.015 100.65)
		(width 0.15)
		(layer "B.Cu")
		(net 285)
	)
	(segment
		(start 70.05 100.9)
		(end 70.3 100.65)
		(width 0.15)
		(layer "B.Cu")
		(net 285)
	)
	(segment
		(start 69.65 100.9)
		(end 70.05 100.9)
		(width 0.15)
		(layer "B.Cu")
		(net 285)
	)
	(segment
		(start 66.68 109.23)
		(end 66.68 107.02)
		(width 0.15)
		(layer "B.Cu")
		(net 286)
	)
	(segment
		(start 66.68 107.02)
		(end 66.9 106.8)
		(width 0.15)
		(layer "B.Cu")
		(net 286)
	)
	(segment
		(start 66.9 106.8)
		(end 66.9 106.45)
		(width 0.15)
		(layer "B.Cu")
		(net 286)
	)
	(segment
		(start 68.2 109.765)
		(end 67.2 109.765)
		(width 0.15)
		(layer "B.Cu")
		(net 286)
	)
	(segment
		(start 67.2 109.75)
		(end 66.68 109.23)
		(width 0.15)
		(layer "B.Cu")
		(net 286)
	)
	(segment
		(start 64.925 107.375)
		(end 64.925 109.79)
		(width 0.15)
		(layer "B.Cu")
		(net 287)
	)
	(segment
		(start 65.3 107)
		(end 64.925 107.375)
		(width 0.15)
		(layer "B.Cu")
		(net 287)
	)
	(segment
		(start 64.925 109.79)
		(end 65.925 109.79)
		(width 0.15)
		(layer "B.Cu")
		(net 287)
	)
	(segment
		(start 65.3 106.45)
		(end 65.3 107)
		(width 0.15)
		(layer "B.Cu")
		(net 287)
	)
	(segment
		(start 71.432221 105.467469)
		(end 71.2 105.235248)
		(width 0.15)
		(layer "F.Cu")
		(net 293)
	)
	(segment
		(start 71.85 105.467469)
		(end 71.432221 105.467469)
		(width 0.15)
		(layer "F.Cu")
		(net 293)
	)
	(via
		(at 60.3968 105.1213)
		(size 0.45)
		(drill 0.1)
		(layers "F.Cu" "B.Cu")
		(net 293)
	)
	(via
		(at 71.2 105.235248)
		(size 0.45)
		(drill 0.1)
		(layers "F.Cu" "B.Cu")
		(net 293)
	)
	(segment
		(start 71.2 105.235248)
		(end 69.764752 105.235248)
		(width 0.125)
		(layer "In5.Cu")
		(net 293)
	)
	(segment
		(start 69 106)
		(end 61.2755 106)
		(width 0.125)
		(layer "In5.Cu")
		(net 293)
	)
	(segment
		(start 69.764752 105.235248)
		(end 69 106)
		(width 0.125)
		(layer "In5.Cu")
		(net 293)
	)
	(segment
		(start 61.2755 106)
		(end 60.3968 105.1213)
		(width 0.125)
		(layer "In5.Cu")
		(net 293)
	)
	(segment
		(start 71.2 105.235248)
		(end 71.814752 105.235248)
		(width 0.15)
		(layer "B.Cu")
		(net 293)
	)
	(segment
		(start 60.8468 105.1032)
		(end 60.85 105.1)
		(width 0.15)
		(layer "B.Cu")
		(net 293)
	)
	(segment
		(start 60.3968 105.1213)
		(end 60.4149 105.1032)
		(width 0.15)
		(layer "B.Cu")
		(net 293)
	)
	(segment
		(start 60.4149 105.1032)
		(end 60.8468 105.1032)
		(width 0.15)
		(layer "B.Cu")
		(net 293)
	)
	(segment
		(start 71.814752 105.235248)
		(end 71.85 105.2)
		(width 0.15)
		(layer "B.Cu")
		(net 293)
	)
	(segment
		(start 62.95 104.5)
		(end 62.4 104.5)
		(width 0.15)
		(layer "B.Cu")
		(net 294)
	)
	(segment
		(start 62.1904 104.2904)
		(end 61.3207 104.2904)
		(width 0.15)
		(layer "B.Cu")
		(net 294)
	)
	(segment
		(start 62.4 104.5)
		(end 62.1904 104.2904)
		(width 0.15)
		(layer "B.Cu")
		(net 294)
	)
	(segment
		(start 71.267469 105.867469)
		(end 71.85 105.867469)
		(width 0.15)
		(layer "F.Cu")
		(net 295)
	)
	(segment
		(start 70.593765 105.688)
		(end 71.088 105.688)
		(width 0.15)
		(layer "F.Cu")
		(net 295)
	)
	(segment
		(start 71.088 105.688)
		(end 71.267469 105.867469)
		(width 0.15)
		(layer "F.Cu")
		(net 295)
	)
	(via
		(at 70.593765 105.688)
		(size 0.45)
		(drill 0.1)
		(layers "F.Cu" "B.Cu")
		(net 295)
	)
	(via
		(at 59.909263 105.425206)
		(size 0.45)
		(drill 0.1)
		(layers "F.Cu" "B.Cu")
		(net 295)
	)
	(segment
		(start 60.809057 106.325)
		(end 59.909263 105.425206)
		(width 0.125)
		(layer "In5.Cu")
		(net 295)
	)
	(segment
		(start 69.912 105.688)
		(end 69.275 106.325)
		(width 0.125)
		(layer "In5.Cu")
		(net 295)
	)
	(segment
		(start 69.275 106.325)
		(end 60.809057 106.325)
		(width 0.125)
		(layer "In5.Cu")
		(net 295)
	)
	(segment
		(start 70.593765 105.688)
		(end 69.912 105.688)
		(width 0.125)
		(layer "In5.Cu")
		(net 295)
	)
	(segment
		(start 70.593765 105.688)
		(end 71.353 105.688)
		(width 0.15)
		(layer "B.Cu")
		(net 295)
	)
	(segment
		(start 60.85 104.7)
		(end 60.8468 104.6968)
		(width 0.15)
		(layer "B.Cu")
		(net 295)
	)
	(segment
		(start 71.353 105.688)
		(end 71.865 106.2)
		(width 0.15)
		(layer "B.Cu")
		(net 295)
	)
	(segment
		(start 60.2032 104.6968)
		(end 59.909263 104.990737)
		(width 0.15)
		(layer "B.Cu")
		(net 295)
	)
	(segment
		(start 59.909263 104.990737)
		(end 59.909263 105.425206)
		(width 0.15)
		(layer "B.Cu")
		(net 295)
	)
	(segment
		(start 60.8468 104.6968)
		(end 60.2032 104.6968)
		(width 0.15)
		(layer "B.Cu")
		(net 295)
	)
	(segment
		(start 62.95 105.3)
		(end 62.2 105.3)
		(width 0.15)
		(layer "B.Cu")
		(net 296)
	)
	(segment
		(start 62.0032 105.1032)
		(end 61.3207 105.1032)
		(width 0.15)
		(layer "B.Cu")
		(net 296)
	)
	(segment
		(start 62.2 105.3)
		(end 62.0032 105.1032)
		(width 0.15)
		(layer "B.Cu")
		(net 296)
	)
	(segment
		(start 71 106.2)
		(end 71.067469 106.267469)
		(width 0.15)
		(layer "F.Cu")
		(net 297)
	)
	(segment
		(start 71.067469 106.267469)
		(end 71.85 106.267469)
		(width 0.15)
		(layer "F.Cu")
		(net 297)
	)
	(via
		(at 59.432818 105.746225)
		(size 0.45)
		(drill 0.1)
		(layers "F.Cu" "B.Cu")
		(net 297)
	)
	(via
		(at 71 106.2)
		(size 0.45)
		(drill 0.1)
		(layers "F.Cu" "B.Cu")
		(net 297)
	)
	(segment
		(start 69.4 106.6)
		(end 60.286593 106.6)
		(width 0.125)
		(layer "In5.Cu")
		(net 297)
	)
	(segment
		(start 70.9125 106.1125)
		(end 69.8875 106.1125)
		(width 0.125)
		(layer "In5.Cu")
		(net 297)
	)
	(segment
		(start 60.286593 106.6)
		(end 59.432818 105.746225)
		(width 0.125)
		(layer "In5.Cu")
		(net 297)
	)
	(segment
		(start 69.8875 106.1125)
		(end 69.4 106.6)
		(width 0.125)
		(layer "In5.Cu")
		(net 297)
	)
	(segment
		(start 71 106.2)
		(end 70.9125 106.1125)
		(width 0.125)
		(layer "In5.Cu")
		(net 297)
	)
	(segment
		(start 59.432818 104.932818)
		(end 59.432818 105.746225)
		(width 0.15)
		(layer "B.Cu")
		(net 297)
	)
	(segment
		(start 60.075236 104.2904)
		(end 59.432818 104.932818)
		(width 0.15)
		(layer "B.Cu")
		(net 297)
	)
	(segment
		(start 60.85 104.3)
		(end 60.8404 104.2904)
		(width 0.15)
		(layer "B.Cu")
		(net 297)
	)
	(segment
		(start 60.8404 104.2904)
		(end 60.075236 104.2904)
		(width 0.15)
		(layer "B.Cu")
		(net 297)
	)
	(segment
		(start 61.9968 104.6968)
		(end 62.2 104.9)
		(width 0.15)
		(layer "B.Cu")
		(net 298)
	)
	(segment
		(start 61.3207 104.6968)
		(end 61.9968 104.6968)
		(width 0.15)
		(layer "B.Cu")
		(net 298)
	)
	(segment
		(start 62.2 104.9)
		(end 62.95 104.9)
		(width 0.15)
		(layer "B.Cu")
		(net 298)
	)
	(segment
		(start 61.685921 103.364079)
		(end 62.15 102.9)
		(width 0.15)
		(layer "B.Cu")
		(net 299)
	)
	(segment
		(start 62.15 102.9)
		(end 62.95 102.9)
		(width 0.15)
		(layer "B.Cu")
		(net 299)
	)
	(segment
		(start 59.964079 103.364079)
		(end 61.685921 103.364079)
		(width 0.15)
		(layer "B.Cu")
		(net 299)
	)
	(segment
		(start 68.9 99.9)
		(end 68.9 99.75)
		(width 0.15)
		(layer "B.Cu")
		(net 300)
	)
	(segment
		(start 73.415 100.415)
		(end 72.9 99.9)
		(width 0.15)
		(layer "B.Cu")
		(net 300)
	)
	(segment
		(start 72.9 99.9)
		(end 68.9 99.9)
		(width 0.15)
		(layer "B.Cu")
		(net 300)
	)
	(segment
		(start 73.415 101)
		(end 73.415 100.415)
		(width 0.15)
		(layer "B.Cu")
		(net 300)
	)
	(segment
		(start 72.8 101.335)
		(end 73.415 101.95)
		(width 0.15)
		(layer "B.Cu")
		(net 301)
	)
	(segment
		(start 69.65 100.5)
		(end 69.875 100.275)
		(width 0.15)
		(layer "B.Cu")
		(net 301)
	)
	(segment
		(start 72.8 100.4)
		(end 72.8 101.335)
		(width 0.15)
		(layer "B.Cu")
		(net 301)
	)
	(segment
		(start 72.675 100.275)
		(end 72.8 100.4)
		(width 0.15)
		(layer "B.Cu")
		(net 301)
	)
	(segment
		(start 69.875 100.275)
		(end 72.675 100.275)
		(width 0.15)
		(layer "B.Cu")
		(net 301)
	)
	(segment
		(start 51.16859 110.52859)
		(end 50.5525 109.9125)
		(width 0.125)
		(layer "F.Cu")
		(net 302)
	)
	(segment
		(start 50.5525 109.9125)
		(end 49.10318 109.9125)
		(width 0.125)
		(layer "F.Cu")
		(net 302)
	)
	(segment
		(start 49.10318 109.9125)
		(end 48.322644 110.693036)
		(width 0.125)
		(layer "F.Cu")
		(net 302)
	)
	(segment
		(start 51.16859 110.534383)
		(end 51.16859 110.52859)
		(width 0.125)
		(layer "F.Cu")
		(net 302)
	)
	(via
		(at 48.322644 110.693036)
		(size 0.45)
		(drill 0.1)
		(layers "F.Cu" "B.Cu")
		(net 302)
	)
	(via
		(at 60.19989 100.973133)
		(size 0.45)
		(drill 0.1)
		(layers "F.Cu" "B.Cu")
		(net 302)
	)
	(via
		(at 51.16859 110.534383)
		(size 0.45)
		(drill 0.1)
		(layers "F.Cu" "B.Cu")
		(net 302)
	)
	(segment
		(start 60.19989 100.973133)
		(end 59.666867 100.973133)
		(width 0.125)
		(layer "In5.Cu")
		(net 302)
	)
	(segment
		(start 59.666867 100.973133)
		(end 57.71 102.93)
		(width 0.125)
		(layer "In5.Cu")
		(net 302)
	)
	(segment
		(start 55.827347 102.93)
		(end 51.15 107.607347)
		(width 0.125)
		(layer "In5.Cu")
		(net 302)
	)
	(segment
		(start 51.15 110.515793)
		(end 51.16859 110.534383)
		(width 0.125)
		(layer "In5.Cu")
		(net 302)
	)
	(segment
		(start 51.15 107.607347)
		(end 51.15 110.515793)
		(width 0.125)
		(layer "In5.Cu")
		(net 302)
	)
	(segment
		(start 57.71 102.93)
		(end 55.827347 102.93)
		(width 0.125)
		(layer "In5.Cu")
		(net 302)
	)
	(segment
		(start 59.69 100.9)
		(end 58.57 99.78)
		(width 0.125)
		(layer "B.Cu")
		(net 302)
	)
	(segment
		(start 48.504108 110.8745)
		(end 49.03 110.8745)
		(width 0.15)
		(layer "B.Cu")
		(net 302)
	)
	(segment
		(start 60.126757 100.9)
		(end 60.19989 100.973133)
		(width 0.125)
		(layer "B.Cu")
		(net 302)
	)
	(segment
		(start 58.57 99.78)
		(end 58.57 98.32)
		(width 0.125)
		(layer "B.Cu")
		(net 302)
	)
	(segment
		(start 58.75 98.14)
		(end 59.14 98.14)
		(width 0.125)
		(layer "B.Cu")
		(net 302)
	)
	(segment
		(start 59.69 100.9)
		(end 60.126757 100.9)
		(width 0.125)
		(layer "B.Cu")
		(net 302)
	)
	(segment
		(start 60.273023 100.9)
		(end 60.19989 100.973133)
		(width 0.125)
		(layer "B.Cu")
		(net 302)
	)
	(segment
		(start 59.14 98.14)
		(end 59.14 97.7)
		(width 0.125)
		(layer "B.Cu")
		(net 302)
	)
	(segment
		(start 59.21 97.63)
		(end 59.21 97.15)
		(width 0.125)
		(layer "B.Cu")
		(net 302)
	)
	(segment
		(start 62.95 100.9)
		(end 60.273023 100.9)
		(width 0.125)
		(layer "B.Cu")
		(net 302)
	)
	(segment
		(start 59.14 97.7)
		(end 59.21 97.63)
		(width 0.125)
		(layer "B.Cu")
		(net 302)
	)
	(segment
		(start 58.57 98.32)
		(end 58.75 98.14)
		(width 0.125)
		(layer "B.Cu")
		(net 302)
	)
	(segment
		(start 48.322644 110.693036)
		(end 48.504108 110.8745)
		(width 0.15)
		(layer "B.Cu")
		(net 302)
	)
	(segment
		(start 51.2375 111.384383)
		(end 50.615617 111.384383)
		(width 0.125)
		(layer "F.Cu")
		(net 303)
	)
	(segment
		(start 48.57 111.73)
		(end 48.35 111.95)
		(width 0.125)
		(layer "F.Cu")
		(net 303)
	)
	(segment
		(start 50.27 111.73)
		(end 48.57 111.73)
		(width 0.125)
		(layer "F.Cu")
		(net 303)
	)
	(segment
		(start 50.615617 111.384383)
		(end 50.27 111.73)
		(width 0.125)
		(layer "F.Cu")
		(net 303)
	)
	(via
		(at 51.2375 111.384383)
		(size 0.45)
		(drill 0.1)
		(layers "F.Cu" "B.Cu")
		(net 303)
	)
	(via
		(at 60.202626 100.398137)
		(size 0.45)
		(drill 0.1)
		(layers "F.Cu" "B.Cu")
		(net 303)
	)
	(via
		(at 48.35 111.95)
		(size 0.45)
		(drill 0.1)
		(layers "F.Cu" "B.Cu")
		(net 303)
	)
	(segment
		(start 50.618191 107.381809)
		(end 50.618191 110.765074)
		(width 0.125)
		(layer "In5.Cu")
		(net 303)
	)
	(segment
		(start 57.43 102.55)
		(end 55.45 102.55)
		(width 0.125)
		(layer "In5.Cu")
		(net 303)
	)
	(segment
		(start 55.45 102.55)
		(end 50.618191 107.381809)
		(width 0.125)
		(layer "In5.Cu")
		(net 303)
	)
	(segment
		(start 60.202626 100.398137)
		(end 59.581863 100.398137)
		(width 0.125)
		(layer "In5.Cu")
		(net 303)
	)
	(segment
		(start 50.618191 110.765074)
		(end 51.2375 111.384383)
		(width 0.125)
		(layer "In5.Cu")
		(net 303)
	)
	(segment
		(start 59.581863 100.398137)
		(end 57.43 102.55)
		(width 0.125)
		(layer "In5.Cu")
		(net 303)
	)
	(segment
		(start 61.275 100.5)
		(end 61.26 100.5)
		(width 0.125)
		(layer "B.Cu")
		(net 303)
	)
	(segment
		(start 60.64 98.64)
		(end 60.14 98.14)
		(width 0.125)
		(layer "B.Cu")
		(net 303)
	)
	(segment
		(start 61.16 100.49)
		(end 61.17 100.5)
		(width 0.125)
		(layer "B.Cu")
		(net 303)
	)
	(segment
		(start 61.06 100.5)
		(end 61.16 100.4)
		(width 0.125)
		(layer "B.Cu")
		(net 303)
	)
	(segment
		(start 60.304489 100.5)
		(end 61.05 100.5)
		(width 0.125)
		(layer "B.Cu")
		(net 303)
	)
	(segment
		(start 48.35 111.95)
		(end 48.5255 111.7745)
		(width 0.15)
		(layer "B.Cu")
		(net 303)
	)
	(segment
		(start 48.5255 111.7745)
		(end 49.03 111.7745)
		(width 0.15)
		(layer "B.Cu")
		(net 303)
	)
	(segment
		(start 61.16 98.64)
		(end 61.16 100.4)
		(width 0.125)
		(layer "B.Cu")
		(net 303)
	)
	(segment
		(start 61.16 98.64)
		(end 60.64 98.64)
		(width 0.125)
		(layer "B.Cu")
		(net 303)
	)
	(segment
		(start 61.16 100.4)
		(end 61.16 100.49)
		(width 0.125)
		(layer "B.Cu")
		(net 303)
	)
	(segment
		(start 61.05 100.5)
		(end 61.17 100.5)
		(width 0.125)
		(layer "B.Cu")
		(net 303)
	)
	(segment
		(start 62.95 100.5)
		(end 62.36 100.5)
		(width 0.125)
		(layer "B.Cu")
		(net 303)
	)
	(segment
		(start 61.275 100.5)
		(end 62.36 100.5)
		(width 0.125)
		(layer "B.Cu")
		(net 303)
	)
	(segment
		(start 60.202626 100.398137)
		(end 60.304489 100.5)
		(width 0.125)
		(layer "B.Cu")
		(net 303)
	)
	(segment
		(start 61.05 100.5)
		(end 61.06 100.5)
		(width 0.125)
		(layer "B.Cu")
		(net 303)
	)
	(segment
		(start 61.17 100.5)
		(end 61.275 100.5)
		(width 0.125)
		(layer "B.Cu")
		(net 303)
	)
	(segment
		(start 61.26 100.5)
		(end 61.16 100.4)
		(width 0.125)
		(layer "B.Cu")
		(net 303)
	)
	(segment
		(start 73.764499 104.4)
		(end 73.75 104.414499)
		(width 0.15)
		(layer "F.Cu")
		(net 304)
	)
	(segment
		(start 73.75 104.414499)
		(end 73.75 104.967469)
		(width 0.15)
		(layer "F.Cu")
		(net 304)
	)
	(via
		(at 73.764499 104.4)
		(size 0.45)
		(drill 0.1)
		(layers "F.Cu" "B.Cu")
		(net 304)
	)
	(segment
		(start 74 104.635501)
		(end 73.764499 104.4)
		(width 0.155)
		(layer "B.Cu")
		(net 304)
	)
	(segment
		(start 74 104.815)
		(end 74 104.635501)
		(width 0.155)
		(layer "B.Cu")
		(net 304)
	)
	(segment
		(start 73.764499 104.170501)
		(end 74.05 103.885)
		(width 0.15)
		(layer "B.Cu")
		(net 304)
	)
	(segment
		(start 73.764499 104.4)
		(end 73.764499 104.170501)
		(width 0.15)
		(layer "B.Cu")
		(net 304)
	)
	(segment
		(start 76.15 104.967469)
		(end 76.15 104.35)
		(width 0.15)
		(layer "F.Cu")
		(net 305)
	)
	(via
		(at 76.15 104.35)
		(size 0.45)
		(drill 0.1)
		(layers "F.Cu" "B.Cu")
		(net 305)
	)
	(segment
		(start 76 103.885)
		(end 76 104.2)
		(width 0.155)
		(layer "B.Cu")
		(net 305)
	)
	(segment
		(start 76 104.2)
		(end 76.15 104.35)
		(width 0.155)
		(layer "B.Cu")
		(net 305)
	)
	(segment
		(start 76 104.815)
		(end 76 104.5)
		(width 0.155)
		(layer "B.Cu")
		(net 305)
	)
	(segment
		(start 76 104.5)
		(end 76.15 104.35)
		(width 0.155)
		(layer "B.Cu")
		(net 305)
	)
	(segment
		(start 78.55 107.825497)
		(end 78.191972 107.467469)
		(width 0.15)
		(layer "F.Cu")
		(net 306)
	)
	(segment
		(start 78.191972 107.467469)
		(end 77.65 107.467469)
		(width 0.15)
		(layer "F.Cu")
		(net 306)
	)
	(via
		(at 78.55 107.825497)
		(size 0.45)
		(drill 0.1)
		(layers "F.Cu" "B.Cu")
		(net 306)
	)
	(segment
		(start 78.024503 107.3)
		(end 78.55 107.825497)
		(width 0.15)
		(layer "B.Cu")
		(net 306)
	)
	(segment
		(start 79.075497 107.3)
		(end 78.55 107.825497)
		(width 0.15)
		(layer "B.Cu")
		(net 306)
	)
	(segment
		(start 74.95 104.967469)
		(end 74.95 104.3555)
		(width 0.15)
		(layer "F.Cu")
		(net 307)
	)
	(via
		(at 74.95 104.3555)
		(size 0.45)
		(drill 0.1)
		(layers "F.Cu" "B.Cu")
		(net 307)
	)
	(segment
		(start 75 104.3055)
		(end 74.95 104.3555)
		(width 0.155)
		(layer "B.Cu")
		(net 307)
	)
	(segment
		(start 75 104.4055)
		(end 74.95 104.3555)
		(width 0.155)
		(layer "B.Cu")
		(net 307)
	)
	(segment
		(start 75 103.885)
		(end 75 104.3055)
		(width 0.155)
		(layer "B.Cu")
		(net 307)
	)
	(segment
		(start 75 104.815)
		(end 75 104.4055)
		(width 0.155)
		(layer "B.Cu")
		(net 307)
	)
	(segment
		(start 78.43962 108.4)
		(end 78.55 108.4)
		(width 0.155)
		(layer "F.Cu")
		(net 308)
	)
	(segment
		(start 77.65 107.867469)
		(end 77.907089 107.867469)
		(width 0.155)
		(layer "F.Cu")
		(net 308)
	)
	(segment
		(start 77.907089 107.867469)
		(end 78.43962 108.4)
		(width 0.155)
		(layer "F.Cu")
		(net 308)
	)
	(via
		(at 78.55 108.4)
		(size 0.45)
		(drill 0.1)
		(layers "F.Cu" "B.Cu")
		(net 308)
	)
	(segment
		(start 77.935 108.3)
		(end 78.45 108.3)
		(width 0.15)
		(layer "B.Cu")
		(net 308)
	)
	(segment
		(start 79.115 108.3)
		(end 77.935 108.3)
		(width 0.15)
		(layer "B.Cu")
		(net 308)
	)
	(segment
		(start 78.65 108.3)
		(end 78.55 108.4)
		(width 0.15)
		(layer "B.Cu")
		(net 308)
	)
	(segment
		(start 78.45 108.3)
		(end 78.55 108.4)
		(width 0.15)
		(layer "B.Cu")
		(net 308)
	)
	(segment
		(start 79.115 108.3)
		(end 78.65 108.3)
		(width 0.15)
		(layer "B.Cu")
		(net 308)
	)
	(segment
		(start 76.15 108.767469)
		(end 76.15 109.225)
		(width 0.15)
		(layer "F.Cu")
		(net 309)
	)
	(segment
		(start 76.15 109.225)
		(end 76.175 109.25)
		(width 0.15)
		(layer "F.Cu")
		(net 309)
	)
	(via
		(at 76.175 109.25)
		(size 0.45)
		(drill 0.1)
		(layers "F.Cu" "B.Cu")
		(net 309)
	)
	(segment
		(start 74.95 108.767469)
		(end 74.95 109.4)
		(width 0.15)
		(layer "F.Cu")
		(net 310)
	)
	(via
		(at 74.95 109.4)
		(size 0.45)
		(drill 0.1)
		(layers "F.Cu" "B.Cu")
		(net 310)
	)
	(segment
		(start 74.95 108.835)
		(end 75 108.785)
		(width 0.15)
		(layer "B.Cu")
		(net 310)
	)
	(segment
		(start 74.95 109.4)
		(end 74.95 108.835)
		(width 0.15)
		(layer "B.Cu")
		(net 310)
	)
	(segment
		(start 128.55 113.95)
		(end 128.55 120.45)
		(width 0.125)
		(layer "F.Cu")
		(net 311)
	)
	(segment
		(start 134.85 112.785)
		(end 129.715 112.785)
		(width 0.125)
		(layer "F.Cu")
		(net 311)
	)
	(segment
		(start 109.2 122.15)
		(end 108.4 121.35)
		(width 0.125)
		(layer "F.Cu")
		(net 311)
	)
	(segment
		(start 112.8 121.35)
		(end 112 122.15)
		(width 0.125)
		(layer "F.Cu")
		(net 311)
	)
	(segment
		(start 114.8 122.1)
		(end 114.05 121.35)
		(width 0.125)
		(layer "F.Cu")
		(net 311)
	)
	(segment
		(start 108.4 114.85)
		(end 108.65 114.6)
		(width 0.125)
		(layer "F.Cu")
		(net 311)
	)
	(segment
		(start 126.9 122.1)
		(end 114.8 122.1)
		(width 0.125)
		(layer "F.Cu")
		(net 311)
	)
	(segment
		(start 114.05 121.35)
		(end 112.8 121.35)
		(width 0.125)
		(layer "F.Cu")
		(net 311)
	)
	(segment
		(start 112 122.15)
		(end 109.2 122.15)
		(width 0.125)
		(layer "F.Cu")
		(net 311)
	)
	(segment
		(start 134.85 112.785)
		(end 134.85 113.6)
		(width 0.125)
		(layer "F.Cu")
		(net 311)
	)
	(segment
		(start 108.4 121.35)
		(end 108.4 114.85)
		(width 0.125)
		(layer "F.Cu")
		(net 311)
	)
	(segment
		(start 129.715 112.785)
		(end 128.55 113.95)
		(width 0.125)
		(layer "F.Cu")
		(net 311)
	)
	(segment
		(start 128.55 120.45)
		(end 126.9 122.1)
		(width 0.125)
		(layer "F.Cu")
		(net 311)
	)
	(via
		(at 134.85 113.6)
		(size 0.45)
		(drill 0.1)
		(layers "F.Cu" "B.Cu")
		(net 311)
	)
	(via
		(at 108.65 114.6)
		(size 0.45)
		(drill 0.1)
		(layers "F.Cu" "B.Cu")
		(net 311)
	)
	(via
		(at 92.2725 113.2)
		(size 0.45)
		(drill 0.1)
		(layers "F.Cu" "B.Cu")
		(net 311)
	)
	(segment
		(start 105.55 114.6)
		(end 108.65 114.6)
		(width 0.125)
		(layer "In3.Cu")
		(net 311)
	)
	(segment
		(start 92.275 113.2)
		(end 92.925 112.55)
		(width 0.125)
		(layer "In3.Cu")
		(net 311)
	)
	(segment
		(start 96.05 112.35)
		(end 103.3 112.35)
		(width 0.125)
		(layer "In3.Cu")
		(net 311)
	)
	(segment
		(start 95.85 112.55)
		(end 96.05 112.35)
		(width 0.125)
		(layer "In3.Cu")
		(net 311)
	)
	(segment
		(start 92.925 112.55)
		(end 95.85 112.55)
		(width 0.125)
		(layer "In3.Cu")
		(net 311)
	)
	(segment
		(start 103.3 112.35)
		(end 105.55 114.6)
		(width 0.125)
		(layer "In3.Cu")
		(net 311)
	)
	(segment
		(start 92.2725 113.2)
		(end 92.275 113.2)
		(width 0.125)
		(layer "In3.Cu")
		(net 311)
	)
	(segment
		(start 135.4 114.15)
		(end 138.15 114.15)
		(width 0.125)
		(layer "B.Cu")
		(net 311)
	)
	(segment
		(start 92.2725 113.2)
		(end 92.2 113.1275)
		(width 0.125)
		(layer "B.Cu")
		(net 311)
	)
	(segment
		(start 134.904 113.546)
		(end 134.904 112.649)
		(width 0.125)
		(layer "B.Cu")
		(net 311)
	)
	(segment
		(start 138.15 114.15)
		(end 138.484 113.816)
		(width 0.125)
		(layer "B.Cu")
		(net 311)
	)
	(segment
		(start 134.85 113.6)
		(end 135.4 114.15)
		(width 0.125)
		(layer "B.Cu")
		(net 311)
	)
	(segment
		(start 92.2 113.1275)
		(end 92.2 112.55)
		(width 0.125)
		(layer "B.Cu")
		(net 311)
	)
	(segment
		(start 138.484 113.816)
		(end 138.484 112.649)
		(width 0.125)
		(layer "B.Cu")
		(net 311)
	)
	(segment
		(start 134.85 113.6)
		(end 134.904 113.546)
		(width 0.125)
		(layer "B.Cu")
		(net 311)
	)
	(segment
		(start 53.075 115.650001)
		(end 53.075 115.05)
		(width 0.155)
		(layer "B.Cu")
		(net 312)
	)
	(segment
		(start 53.2505 115.9645)
		(end 53.2505 115.825501)
		(width 0.155)
		(layer "B.Cu")
		(net 312)
	)
	(segment
		(start 52.9 116.315)
		(end 53.2505 115.9645)
		(width 0.155)
		(layer "B.Cu")
		(net 312)
	)
	(segment
		(start 53.2505 115.825501)
		(end 53.075 115.650001)
		(width 0.155)
		(layer "B.Cu")
		(net 312)
	)
	(segment
		(start 53.725 115.650001)
		(end 53.725 115.05)
		(width 0.155)
		(layer "B.Cu")
		(net 313)
	)
	(segment
		(start 53.9 116.315)
		(end 53.5495 115.9645)
		(width 0.155)
		(layer "B.Cu")
		(net 313)
	)
	(segment
		(start 53.5495 115.825501)
		(end 53.725 115.650001)
		(width 0.155)
		(layer "B.Cu")
		(net 313)
	)
	(segment
		(start 53.5495 115.9645)
		(end 53.5495 115.825501)
		(width 0.155)
		(layer "B.Cu")
		(net 313)
	)
	(segment
		(start 111.245 105.945)
		(end 110.089938 105.945)
		(width 0.15)
		(layer "F.Cu")
		(net 314)
	)
	(segment
		(start 111.25 105.95)
		(end 111.245 105.945)
		(width 0.15)
		(layer "F.Cu")
		(net 314)
	)
	(via
		(at 111.25 105.95)
		(size 0.45)
		(drill 0.1)
		(layers "F.Cu" "B.Cu")
		(net 314)
	)
	(segment
		(start 111.25 105.95)
		(end 111.4 106.1)
		(width 0.15)
		(layer "B.Cu")
		(net 314)
	)
	(segment
		(start 111.4 106.1)
		(end 111.915 106.1)
		(width 0.15)
		(layer "B.Cu")
		(net 314)
	)
	(segment
		(start 111.915 107.1)
		(end 111.915 106.1)
		(width 0.15)
		(layer "B.Cu")
		(net 314)
	)
	(segment
		(start 105.635 105.135)
		(end 106.37 105.87)
		(width 0.15)
		(layer "F.Cu")
		(net 315)
	)
	(segment
		(start 106.37 105.87)
		(end 107.614938 105.87)
		(width 0.15)
		(layer "F.Cu")
		(net 315)
	)
	(segment
		(start 107.614938 105.87)
		(end 107.689938 105.945)
		(width 0.15)
		(layer "F.Cu")
		(net 315)
	)
	(segment
		(start 106.5 105.55)
		(end 106.25 105.3)
		(width 0.15)
		(layer "F.Cu")
		(net 316)
	)
	(segment
		(start 106.555 105.545)
		(end 106.55 105.55)
		(width 0.15)
		(layer "F.Cu")
		(net 316)
	)
	(segment
		(start 107.689938 105.545)
		(end 106.555 105.545)
		(width 0.15)
		(layer "F.Cu")
		(net 316)
	)
	(segment
		(start 106.05 104.1)
		(end 105.635 104.1)
		(width 0.15)
		(layer "F.Cu")
		(net 316)
	)
	(segment
		(start 106.25 105.3)
		(end 106.25 104.3)
		(width 0.15)
		(layer "F.Cu")
		(net 316)
	)
	(segment
		(start 106.25 104.3)
		(end 106.05 104.1)
		(width 0.15)
		(layer "F.Cu")
		(net 316)
	)
	(segment
		(start 106.55 105.55)
		(end 106.5 105.55)
		(width 0.15)
		(layer "F.Cu")
		(net 316)
	)
	(segment
		(start 110.868093 105.531907)
		(end 110.103031 105.531907)
		(width 0.15)
		(layer "F.Cu")
		(net 317)
	)
	(segment
		(start 111 105.4)
		(end 110.868093 105.531907)
		(width 0.15)
		(layer "F.Cu")
		(net 317)
	)
	(segment
		(start 110.103031 105.531907)
		(end 110.089938 105.545)
		(width 0.15)
		(layer "F.Cu")
		(net 317)
	)
	(via
		(at 111 105.4)
		(size 0.45)
		(drill 0.1)
		(layers "F.Cu" "B.Cu")
		(net 317)
	)
	(segment
		(start 111.3 105.1)
		(end 111 105.4)
		(width 0.125)
		(layer "B.Cu")
		(net 317)
	)
	(segment
		(start 111.915 105.1)
		(end 111.3 105.1)
		(width 0.125)
		(layer "B.Cu")
		(net 317)
	)
	(segment
		(start 108.489938 108.745)
		(end 108.489938 109.410062)
		(width 0.15)
		(layer "F.Cu")
		(net 318)
	)
	(segment
		(start 108.489938 109.410062)
		(end 108.175 109.725)
		(width 0.15)
		(layer "F.Cu")
		(net 318)
	)
	(segment
		(start 108.175 109.725)
		(end 108.175 110.14)
		(width 0.15)
		(layer "F.Cu")
		(net 318)
	)
	(segment
		(start 108.298959 103.8)
		(end 108.489938 103.990979)
		(width 0.15)
		(layer "F.Cu")
		(net 319)
	)
	(segment
		(start 107.3 103.6)
		(end 107.5 103.8)
		(width 0.15)
		(layer "F.Cu")
		(net 319)
	)
	(segment
		(start 107.5 103.8)
		(end 108.298959 103.8)
		(width 0.15)
		(layer "F.Cu")
		(net 319)
	)
	(segment
		(start 108.489938 103.990979)
		(end 108.489938 104.345)
		(width 0.15)
		(layer "F.Cu")
		(net 319)
	)
	(segment
		(start 107.3 103.135)
		(end 107.3 103.6)
		(width 0.15)
		(layer "F.Cu")
		(net 319)
	)
	(segment
		(start 97.15 103.341472)
		(end 97.422132 103.613604)
		(width 0.15)
		(layer "F.Cu")
		(net 320)
	)
	(segment
		(start 97.15 102.107)
		(end 97.15 103.341472)
		(width 0.15)
		(layer "F.Cu")
		(net 320)
	)
	(via
		(at 97.15 102.107)
		(size 0.45)
		(drill 0.1)
		(layers "F.Cu" "B.Cu")
		(net 320)
	)
	(segment
		(start 97.15 101.65)
		(end 96.55 101.05)
		(width 0.15)
		(layer "B.Cu")
		(net 320)
	)
	(segment
		(start 97.15 102.107)
		(end 97.15 101.65)
		(width 0.15)
		(layer "B.Cu")
		(net 320)
	)
	(segment
		(start 96.55 101.05)
		(end 95.375 101.05)
		(width 0.15)
		(layer "B.Cu")
		(net 320)
	)
	(segment
		(start 97.31 97.41)
		(end 98.25 98.35)
		(width 0.15)
		(layer "B.Cu")
		(net 320)
	)
	(segment
		(start 94.5 100.175)
		(end 94.5 98.32)
		(width 0.15)
		(layer "B.Cu")
		(net 320)
	)
	(segment
		(start 98.25 98.35)
		(end 98.65 98.35)
		(width 0.15)
		(layer "B.Cu")
		(net 320)
	)
	(segment
		(start 97.15 102.65)
		(end 96.9396 102.8604)
		(width 0.15)
		(layer "B.Cu")
		(net 320)
	)
	(segment
		(start 97.15 102.107)
		(end 97.15 102.65)
		(width 0.15)
		(layer "B.Cu")
		(net 320)
	)
	(segment
		(start 96.9396 102.8604)
		(end 96.9396 103.1693)
		(width 0.15)
		(layer "B.Cu")
		(net 320)
	)
	(segment
		(start 95.375 101.05)
		(end 94.5 100.175)
		(width 0.15)
		(layer "B.Cu")
		(net 320)
	)
	(segment
		(start 94.5 98.32)
		(end 95.41 97.41)
		(width 0.15)
		(layer "B.Cu")
		(net 320)
	)
	(segment
		(start 95.41 97.41)
		(end 97.31 97.41)
		(width 0.15)
		(layer "B.Cu")
		(net 320)
	)
	(segment
		(start 99.69 104.625)
		(end 99.3 104.625)
		(width 0.15)
		(layer "B.Cu")
		(net 321)
	)
	(segment
		(start 97.5107 104.2107)
		(end 97.29 103.99)
		(width 0.15)
		(layer "B.Cu")
		(net 321)
	)
	(segment
		(start 96.2 110.415)
		(end 96.2 103.97)
		(width 0.155)
		(layer "B.Cu")
		(net 321)
	)
	(segment
		(start 97.29 103.99)
		(end 95.73 103.99)
		(width 0.15)
		(layer "B.Cu")
		(net 321)
	)
	(segment
		(start 99.3 104.625)
		(end 98.8857 104.2107)
		(width 0.15)
		(layer "B.Cu")
		(net 321)
	)
	(segment
		(start 98.8857 104.2107)
		(end 97.5107 104.2107)
		(width 0.15)
		(layer "B.Cu")
		(net 321)
	)
	(segment
		(start 96.2 103.97)
		(end 96.13 103.9)
		(width 0.155)
		(layer "B.Cu")
		(net 321)
	)
	(via
		(at 126.04 114.14)
		(size 0.45)
		(drill 0.1)
		(layers "F.Cu" "B.Cu")
		(net 322)
	)
	(via
		(at 134.12 118.8)
		(size 0.45)
		(drill 0.1)
		(layers "F.Cu" "B.Cu")
		(net 322)
	)
	(via
		(at 88.1 106.112)
		(size 0.45)
		(drill 0.1)
		(layers "F.Cu" "B.Cu")
		(net 322)
	)
	(segment
		(start 90.87834 105)
		(end 89.92834 105.95)
		(width 0.125)
		(layer "In3.Cu")
		(net 322)
	)
	(segment
		(start 88.262 105.95)
		(end 88.1 106.112)
		(width 0.125)
		(layer "In3.Cu")
		(net 322)
	)
	(segment
		(start 100.9 105)
		(end 90.87834 105)
		(width 0.125)
		(layer "In3.Cu")
		(net 322)
	)
	(segment
		(start 126.04 114.14)
		(end 126.03 114.15)
		(width 0.125)
		(layer "In3.Cu")
		(net 322)
	)
	(segment
		(start 89.92834 105.95)
		(end 88.262 105.95)
		(width 0.125)
		(layer "In3.Cu")
		(net 322)
	)
	(segment
		(start 126.03 114.15)
		(end 107.9 114.15)
		(width 0.125)
		(layer "In3.Cu")
		(net 322)
	)
	(segment
		(start 105.25 111.5)
		(end 105.25 109.35)
		(width 0.125)
		(layer "In3.Cu")
		(net 322)
	)
	(segment
		(start 107.9 114.15)
		(end 105.25 111.5)
		(width 0.125)
		(layer "In3.Cu")
		(net 322)
	)
	(segment
		(start 105.25 109.35)
		(end 100.9 105)
		(width 0.125)
		(layer "In3.Cu")
		(net 322)
	)
	(segment
		(start 127.74 114.14)
		(end 128.2 114.6)
		(width 0.125)
		(layer "In5.Cu")
		(net 322)
	)
	(segment
		(start 128.6 118.8)
		(end 134.12 118.8)
		(width 0.125)
		(layer "In5.Cu")
		(net 322)
	)
	(segment
		(start 128.2 114.6)
		(end 128.2 118.4)
		(width 0.125)
		(layer "In5.Cu")
		(net 322)
	)
	(segment
		(start 128.2 118.4)
		(end 128.6 118.8)
		(width 0.125)
		(layer "In5.Cu")
		(net 322)
	)
	(segment
		(start 126.04 114.14)
		(end 127.74 114.14)
		(width 0.125)
		(layer "In5.Cu")
		(net 322)
	)
	(segment
		(start 138.35 114.4)
		(end 135.05 114.4)
		(width 0.125)
		(layer "B.Cu")
		(net 322)
	)
	(segment
		(start 138.7 116.15)
		(end 138.484 115.934)
		(width 0.125)
		(layer "B.Cu")
		(net 322)
	)
	(segment
		(start 138.484 114.534)
		(end 138.35 114.4)
		(width 0.125)
		(layer "B.Cu")
		(net 322)
	)
	(segment
		(start 138.75 118.95)
		(end 138.3 119.4)
		(width 0.15)
		(layer "B.Cu")
		(net 322)
	)
	(segment
		(start 135.05 114.4)
		(end 134.904 114.546)
		(width 0.125)
		(layer "B.Cu")
		(net 322)
	)
	(segment
		(start 135.2 119.4)
		(end 134.8 119)
		(width 0.15)
		(layer "B.Cu")
		(net 322)
	)
	(segment
		(start 139.13 117.55)
		(end 139.13 117.545)
		(width 0.125)
		(layer "B.Cu")
		(net 322)
	)
	(segment
		(start 138.7 117.115)
		(end 138.7 116.15)
		(width 0.125)
		(layer "B.Cu")
		(net 322)
	)
	(segment
		(start 88.103 106.115)
		(end 88.1 106.112)
		(width 0.15)
		(layer "B.Cu")
		(net 322)
	)
	(segment
		(start 139.13 117.545)
		(end 138.7 117.115)
		(width 0.125)
		(layer "B.Cu")
		(net 322)
	)
	(segment
		(start 139.13 117.55)
		(end 138.75 117.93)
		(width 0.15)
		(layer "B.Cu")
		(net 322)
	)
	(segment
		(start 134.8 119)
		(end 134.6 118.8)
		(width 0.155)
		(layer "B.Cu")
		(net 322)
	)
	(segment
		(start 138.3 119.4)
		(end 135.2 119.4)
		(width 0.15)
		(layer "B.Cu")
		(net 322)
	)
	(segment
		(start 138.484 115.934)
		(end 138.484 115.249)
		(width 0.125)
		(layer "B.Cu")
		(net 322)
	)
	(segment
		(start 88.7 106.115)
		(end 88.103 106.115)
		(width 0.15)
		(layer "B.Cu")
		(net 322)
	)
	(segment
		(start 134.12 118.8)
		(end 134.6 118.8)
		(width 0.15)
		(layer "B.Cu")
		(net 322)
	)
	(segment
		(start 138.75 117.93)
		(end 138.75 118.95)
		(width 0.15)
		(layer "B.Cu")
		(net 322)
	)
	(segment
		(start 138.484 115.249)
		(end 138.484 114.534)
		(width 0.125)
		(layer "B.Cu")
		(net 322)
	)
	(segment
		(start 89.085 106.115)
		(end 89.25 105.95)
		(width 0.15)
		(layer "B.Cu")
		(net 322)
	)
	(segment
		(start 88.7 106.115)
		(end 89.085 106.115)
		(width 0.15)
		(layer "B.Cu")
		(net 322)
	)
	(segment
		(start 89.25 105.95)
		(end 89.535 105.95)
		(width 0.15)
		(layer "B.Cu")
		(net 322)
	)
	(segment
		(start 134.904 114.546)
		(end 134.904 115.249)
		(width 0.125)
		(layer "B.Cu")
		(net 322)
	)
	(segment
		(start 96.64 102.43)
		(end 96.725 102.515)
		(width 0.15)
		(layer "F.Cu")
		(net 323)
	)
	(segment
		(start 96.725 102.515)
		(end 96.725 103.482158)
		(width 0.15)
		(layer "F.Cu")
		(net 323)
	)
	(segment
		(start 96.725 103.482158)
		(end 97.139289 103.896447)
		(width 0.15)
		(layer "F.Cu")
		(net 323)
	)
	(via
		(at 96.64 102.43)
		(size 0.45)
		(drill 0.1)
		(layers "F.Cu" "B.Cu")
		(net 323)
	)
	(segment
		(start 96.64 102.43)
		(end 96.5332 102.5368)
		(width 0.15)
		(layer "B.Cu")
		(net 323)
	)
	(segment
		(start 94.175 98.165)
		(end 95.22 97.12)
		(width 0.15)
		(layer "B.Cu")
		(net 323)
	)
	(segment
		(start 96.35 101.4)
		(end 95.225 101.4)
		(width 0.15)
		(layer "B.Cu")
		(net 323)
	)
	(segment
		(start 96.725 102.345)
		(end 96.725 101.775)
		(width 0.15)
		(layer "B.Cu")
		(net 323)
	)
	(segment
		(start 95.22 97.12)
		(end 98.37 97.12)
		(width 0.15)
		(layer "B.Cu")
		(net 323)
	)
	(segment
		(start 95.225 101.4)
		(end 94.175 100.35)
		(width 0.15)
		(layer "B.Cu")
		(net 323)
	)
	(segment
		(start 96.64 102.43)
		(end 96.725 102.345)
		(width 0.15)
		(layer "B.Cu")
		(net 323)
	)
	(segment
		(start 99.15 97.9)
		(end 99.15 98.35)
		(width 0.15)
		(layer "B.Cu")
		(net 323)
	)
	(segment
		(start 98.37 97.12)
		(end 99.15 97.9)
		(width 0.15)
		(layer "B.Cu")
		(net 323)
	)
	(segment
		(start 96.5332 102.5368)
		(end 96.5332 103.1693)
		(width 0.15)
		(layer "B.Cu")
		(net 323)
	)
	(segment
		(start 96.725 101.775)
		(end 96.35 101.4)
		(width 0.15)
		(layer "B.Cu")
		(net 323)
	)
	(segment
		(start 94.175 100.35)
		(end 94.175 98.165)
		(width 0.15)
		(layer "B.Cu")
		(net 323)
	)
	(segment
		(start 95.315089 98.597745)
		(end 95.315089 98.434911)
		(width 0.13)
		(layer "F.Cu")
		(net 324)
	)
	(segment
		(start 95.7 98.05)
		(end 96.165 98.05)
		(width 0.13)
		(layer "F.Cu")
		(net 324)
	)
	(segment
		(start 95.315089 98.434911)
		(end 95.7 98.05)
		(width 0.13)
		(layer "F.Cu")
		(net 324)
	)
	(segment
		(start 95.315089 98.597745)
		(end 95.352834 98.56)
		(width 0.15)
		(layer "F.Cu")
		(net 324)
	)
	(via
		(at 95.315089 98.597745)
		(size 0.45)
		(drill 0.1)
		(layers "F.Cu" "B.Cu")
		(net 324)
	)
	(segment
		(start 95.315089 98.034911)
		(end 95.62 97.73)
		(width 0.15)
		(layer "B.Cu")
		(net 324)
	)
	(segment
		(start 95.62 97.73)
		(end 97.22 97.73)
		(width 0.15)
		(layer "B.Cu")
		(net 324)
	)
	(segment
		(start 95.315089 98.597745)
		(end 95.315089 98.034911)
		(width 0.15)
		(layer "B.Cu")
		(net 324)
	)
	(segment
		(start 97.22 97.73)
		(end 98 98.51)
		(width 0.15)
		(layer "B.Cu")
		(net 324)
	)
	(segment
		(start 98 98.51)
		(end 98 98.99999)
		(width 0.15)
		(layer "B.Cu")
		(net 324)
	)
	(segment
		(start 97.085 98.47)
		(end 97.045 98.43)
		(width 0.15)
		(layer "B.Cu")
		(net 325)
	)
	(segment
		(start 98 100)
		(end 97.51 100)
		(width 0.15)
		(layer "B.Cu")
		(net 325)
	)
	(segment
		(start 97.51 100)
		(end 97.085 99.575)
		(width 0.15)
		(layer "B.Cu")
		(net 325)
	)
	(segment
		(start 97.085 99.575)
		(end 97.085 98.47)
		(width 0.15)
		(layer "B.Cu")
		(net 325)
	)
	(segment
		(start 64.847323 79.228336)
		(end 64.847323 80.205136)
		(width 0.15)
		(layer "F.Cu")
		(net 327)
	)
	(segment
		(start 64.559661 78.940674)
		(end 64.847323 79.228336)
		(width 0.15)
		(layer "F.Cu")
		(net 327)
	)
	(via
		(at 64.559661 78.940674)
		(size 0.45)
		(drill 0.1)
		(layers "F.Cu" "B.Cu")
		(net 327)
	)
	(segment
		(start 65.313987 79.695)
		(end 66.05 79.695)
		(width 0.15)
		(layer "B.Cu")
		(net 327)
	)
	(segment
		(start 64.559661 78.940674)
		(end 65.313987 79.695)
		(width 0.15)
		(layer "B.Cu")
		(net 327)
	)
	(segment
		(start 55 108.9)
		(end 55.7 108.2)
		(width 0.15)
		(layer "F.Cu")
		(net 328)
	)
	(segment
		(start 55.7 108.2)
		(end 56.92 108.2)
		(width 0.15)
		(layer "F.Cu")
		(net 328)
	)
	(segment
		(start 56.92 108.2)
		(end 57.15 108.43)
		(width 0.15)
		(layer "F.Cu")
		(net 328)
	)
	(segment
		(start 55 109.8995)
		(end 55 108.9)
		(width 0.15)
		(layer "F.Cu")
		(net 328)
	)
	(via
		(at 44.05 82.35)
		(size 0.45)
		(drill 0.1)
		(layers "F.Cu" "B.Cu")
		(free yes)
		(net 328)
	)
	(via
		(at 62.05 112.55)
		(size 0.45)
		(drill 0.1)
		(layers "F.Cu" "B.Cu")
		(free yes)
		(net 328)
	)
	(via
		(at 44.05 81.6)
		(size 0.45)
		(drill 0.1)
		(layers "F.Cu" "B.Cu")
		(free yes)
		(net 328)
	)
	(via
		(at 44.8 80.85)
		(size 0.45)
		(drill 0.1)
		(layers "F.Cu" "B.Cu")
		(free yes)
		(net 328)
	)
	(via
		(at 55.95 110.9)
		(size 0.45)
		(drill 0.1)
		(layers "F.Cu" "B.Cu")
		(free yes)
		(net 328)
	)
	(via
		(at 44.05 80.85)
		(size 0.45)
		(drill 0.1)
		(layers "F.Cu" "B.Cu")
		(free yes)
		(net 328)
	)
	(via
		(at 56.4 111.65)
		(size 0.45)
		(drill 0.1)
		(layers "F.Cu" "B.Cu")
		(free yes)
		(net 328)
	)
	(via
		(at 56.4 111.15)
		(size 0.45)
		(drill 0.1)
		(layers "F.Cu" "B.Cu")
		(free yes)
		(net 328)
	)
	(via
		(at 54.95 110.4)
		(size 0.45)
		(drill 0.1)
		(layers "F.Cu" "B.Cu")
		(free yes)
		(net 328)
	)
	(via
		(at 54.95 111.4)
		(size 0.45)
		(drill 0.1)
		(layers "F.Cu" "B.Cu")
		(free yes)
		(net 328)
	)
	(via
		(at 55.95 111.4)
		(size 0.45)
		(drill 0.1)
		(layers "F.Cu" "B.Cu")
		(free yes)
		(net 328)
	)
	(via
		(at 44.8 81.6)
		(size 0.45)
		(drill 0.1)
		(layers "F.Cu" "B.Cu")
		(free yes)
		(net 328)
	)
	(via
		(at 62.55 113.060409)
		(size 0.45)
		(drill 0.1)
		(layers "F.Cu" "B.Cu")
		(free yes)
		(net 328)
	)
	(via
		(at 55.95 110.4)
		(size 0.45)
		(drill 0.1)
		(layers "F.Cu" "B.Cu")
		(free yes)
		(net 328)
	)
	(via
		(at 55.45 111.4)
		(size 0.45)
		(drill 0.1)
		(layers "F.Cu" "B.Cu")
		(free yes)
		(net 328)
	)
	(via
		(at 62.55 112.55)
		(size 0.45)
		(drill 0.1)
		(layers "F.Cu" "B.Cu")
		(free yes)
		(net 328)
	)
	(via
		(at 55.45 110.9)
		(size 0.45)
		(drill 0.1)
		(layers "F.Cu" "B.Cu")
		(free yes)
		(net 328)
	)
	(via
		(at 55.45 110.4)
		(size 0.45)
		(drill 0.1)
		(layers "F.Cu" "B.Cu")
		(free yes)
		(net 328)
	)
	(via
		(at 54.95 110.9)
		(size 0.45)
		(drill 0.1)
		(layers "F.Cu" "B.Cu")
		(free yes)
		(net 328)
	)
	(via
		(at 44.8 82.35)
		(size 0.45)
		(drill 0.1)
		(layers "F.Cu" "B.Cu")
		(free yes)
		(net 328)
	)
	(via
		(at 61.55 113.05)
		(size 0.45)
		(drill 0.1)
		(layers "F.Cu" "B.Cu")
		(free yes)
		(net 328)
	)
	(via
		(at 54.95 109.8995)
		(size 0.45)
		(drill 0.1)
		(layers "F.Cu" "B.Cu")
		(free yes)
		(net 328)
	)
	(via
		(at 61.55 112.55)
		(size 0.45)
		(drill 0.1)
		(layers "F.Cu" "B.Cu")
		(free yes)
		(net 328)
	)
	(via
		(at 56.4 110.65)
		(size 0.45)
		(drill 0.1)
		(layers "F.Cu" "B.Cu")
		(free yes)
		(net 328)
	)
	(via
		(at 62.049226 113.041534)
		(size 0.45)
		(drill 0.1)
		(layers "F.Cu" "B.Cu")
		(free yes)
		(net 328)
	)
	(segment
		(start 42.752 75.427)
		(end 42.752 77.982)
		(width 0.15)
		(layer "B.Cu")
		(net 328)
	)
	(segment
		(start 43.694 78.924)
		(end 43.9 78.924)
		(width 0.15)
		(layer "B.Cu")
		(net 328)
	)
	(segment
		(start 42.752 77.982)
		(end 43.694 78.924)
		(width 0.15)
		(layer "B.Cu")
		(net 328)
	)
	(segment
		(start 96.45 102.95)
		(end 96.45 103.772842)
		(width 0.15)
		(layer "F.Cu")
		(net 329)
	)
	(segment
		(start 96.19 102.69)
		(end 96.45 102.95)
		(width 0.15)
		(layer "F.Cu")
		(net 329)
	)
	(segment
		(start 96.19 102.27753)
		(end 96.19 102.69)
		(width 0.15)
		(layer "F.Cu")
		(net 329)
	)
	(segment
		(start 96.45 103.772842)
		(end 96.856447 104.179289)
		(width 0.15)
		(layer "F.Cu")
		(net 329)
	)
	(segment
		(start 96.106235 102.193765)
		(end 96.19 102.27753)
		(width 0.15)
		(layer "F.Cu")
		(net 329)
	)
	(via
		(at 96.106235 102.193765)
		(size 0.45)
		(drill 0.1)
		(layers "F.Cu" "B.Cu")
		(net 329)
	)
	(segment
		(start 96.106235 101.806235)
		(end 96.106235 102.193765)
		(width 0.15)
		(layer "B.Cu")
		(net 329)
	)
	(segment
		(start 98.58 96.78)
		(end 95.1 96.78)
		(width 0.15)
		(layer "B.Cu")
		(net 329)
	)
	(segment
		(start 93.825 100.4)
		(end 95.1 101.675)
		(width 0.15)
		(layer "B.Cu")
		(net 329)
	)
	(segment
		(start 93.825 98.055)
		(end 93.825 100.4)
		(width 0.15)
		(layer "B.Cu")
		(net 329)
	)
	(segment
		(start 95.975 101.675)
		(end 96.106235 101.806235)
		(width 0.15)
		(layer "B.Cu")
		(net 329)
	)
	(segment
		(start 96.106235 102.193765)
		(end 96.19 102.27753)
		(width 0.15)
		(layer "B.Cu")
		(net 329)
	)
	(segment
		(start 99.65 98.35)
		(end 99.65 97.85)
		(width 0.15)
		(layer "B.Cu")
		(net 329)
	)
	(segment
		(start 99.65 97.85)
		(end 98.58 96.78)
		(width 0.15)
		(layer "B.Cu")
		(net 329)
	)
	(segment
		(start 95.1 96.78)
		(end 93.825 98.055)
		(width 0.15)
		(layer "B.Cu")
		(net 329)
	)
	(segment
		(start 96.19 102.27753)
		(end 96.19 103.1061)
		(width 0.15)
		(layer "B.Cu")
		(net 329)
	)
	(segment
		(start 96.19 103.1061)
		(end 96.1268 103.1693)
		(width 0.15)
		(layer "B.Cu")
		(net 329)
	)
	(segment
		(start 95.1 101.675)
		(end 95.975 101.675)
		(width 0.15)
		(layer "B.Cu")
		(net 329)
	)
	(segment
		(start 96.175 103.1176)
		(end 96.175 104.063528)
		(width 0.15)
		(layer "F.Cu")
		(net 330)
	)
	(segment
		(start 96.175 104.063528)
		(end 96.573604 104.462132)
		(width 0.15)
		(layer "F.Cu")
		(net 330)
	)
	(segment
		(start 95.7204 102.663)
		(end 96.175 103.1176)
		(width 0.15)
		(layer "F.Cu")
		(net 330)
	)
	(via
		(at 95.7204 102.663)
		(size 0.45)
		(drill 0.1)
		(layers "F.Cu" "B.Cu")
		(net 330)
	)
	(segment
		(start 94.93 96.48)
		(end 98.78 96.48)
		(width 0.15)
		(layer "B.Cu")
		(net 330)
	)
	(segment
		(start 94.7 102.55)
		(end 93.525 101.375)
		(width 0.15)
		(layer "B.Cu")
		(net 330)
	)
	(segment
		(start 95.6074 102.55)
		(end 94.7 102.55)
		(width 0.15)
		(layer "B.Cu")
		(net 330)
	)
	(segment
		(start 93.525 101.375)
		(end 93.525 97.885)
		(width 0.15)
		(layer "B.Cu")
		(net 330)
	)
	(segment
		(start 93.525 97.885)
		(end 94.93 96.48)
		(width 0.15)
		(layer "B.Cu")
		(net 330)
	)
	(segment
		(start 100.15 97.85)
		(end 100.15 98.35)
		(width 0.15)
		(layer "B.Cu")
		(net 330)
	)
	(segment
		(start 98.78 96.48)
		(end 100.15 97.85)
		(width 0.15)
		(layer "B.Cu")
		(net 330)
	)
	(segment
		(start 95.7204 102.663)
		(end 95.7204 103.1693)
		(width 0.15)
		(layer "B.Cu")
		(net 330)
	)
	(segment
		(start 95.7204 102.663)
		(end 95.6074 102.55)
		(width 0.15)
		(layer "B.Cu")
		(net 330)
	)
	(segment
		(start 106.8504 97.6304)
		(end 107.3493 97.6304)
		(width 0.15)
		(layer "F.Cu")
		(net 331)
	)
	(segment
		(start 106.66 97.44)
		(end 106.8504 97.6304)
		(width 0.15)
		(layer "F.Cu")
		(net 331)
	)
	(via
		(at 106.66 97.44)
		(size 0.45)
		(drill 0.1)
		(layers "F.Cu" "B.Cu")
		(net 331)
	)
	(segment
		(start 100.65 97.9)
		(end 100.85 97.7)
		(width 0.15)
		(layer "B.Cu")
		(net 331)
	)
	(segment
		(start 106.8504 97.6304)
		(end 107.3693 97.6304)
		(width 0.15)
		(layer "B.Cu")
		(net 331)
	)
	(segment
		(start 100.65 98.35)
		(end 100.65 97.9)
		(width 0.15)
		(layer "B.Cu")
		(net 331)
	)
	(segment
		(start 100.85 97.7)
		(end 106.4 97.7)
		(width 0.15)
		(layer "B.Cu")
		(net 331)
	)
	(segment
		(start 106.4 97.7)
		(end 106.66 97.44)
		(width 0.15)
		(layer "B.Cu")
		(net 331)
	)
	(segment
		(start 106.66 97.44)
		(end 106.8504 97.6304)
		(width 0.15)
		(layer "B.Cu")
		(net 331)
	)
	(segment
		(start 106.49 98.19)
		(end 106.6432 98.0368)
		(width 0.15)
		(layer "F.Cu")
		(net 333)
	)
	(segment
		(start 106.6432 98.0368)
		(end 107.3493 98.0368)
		(width 0.15)
		(layer "F.Cu")
		(net 333)
	)
	(via
		(at 106.49 98.19)
		(size 0.45)
		(drill 0.1)
		(layers "F.Cu" "B.Cu")
		(net 333)
	)
	(segment
		(start 106.33 98.35)
		(end 101.15 98.35)
		(width 0.15)
		(layer "B.Cu")
		(net 333)
	)
	(segment
		(start 106.6432 98.0368)
		(end 107.3693 98.0368)
		(width 0.15)
		(layer "B.Cu")
		(net 333)
	)
	(segment
		(start 106.49 98.19)
		(end 106.6432 98.0368)
		(width 0.15)
		(layer "B.Cu")
		(net 333)
	)
	(segment
		(start 106.49 98.19)
		(end 106.33 98.35)
		(width 0.15)
		(layer "B.Cu")
		(net 333)
	)
	(segment
		(start 137.534 115.899)
		(end 138.185 116.55)
		(width 0.125)
		(layer "B.Cu")
		(net 334)
	)
	(segment
		(start 137.534 115.249)
		(end 137.534 115.899)
		(width 0.125)
		(layer "B.Cu")
		(net 334)
	)
	(segment
		(start 133.954 115.249)
		(end 133.954 116.019)
		(width 0.125)
		(layer "B.Cu")
		(net 335)
	)
	(segment
		(start 133.954 116.019)
		(end 134.485 116.55)
		(width 0.125)
		(layer "B.Cu")
		(net 335)
	)
	(segment
		(start 106.9668 98.4432)
		(end 107.3493 98.4432)
		(width 0.15)
		(layer "F.Cu")
		(net 336)
	)
	(segment
		(start 106.56 98.85)
		(end 106.9668 98.4432)
		(width 0.15)
		(layer "F.Cu")
		(net 336)
	)
	(via
		(at 106.56 98.85)
		(size 0.45)
		(drill 0.1)
		(layers "F.Cu" "B.Cu")
		(net 336)
	)
	(segment
		(start 106.9668 98.4432)
		(end 107.3693 98.4432)
		(width 0.15)
		(layer "B.Cu")
		(net 336)
	)
	(segment
		(start 106.56 98.85)
		(end 106.9668 98.4432)
		(width 0.15)
		(layer "B.Cu")
		(net 336)
	)
	(segment
		(start 106.41001 98.99999)
		(end 101.79999 98.99999)
		(width 0.15)
		(layer "B.Cu")
		(net 336)
	)
	(segment
		(start 106.56 98.85)
		(end 106.41001 98.99999)
		(width 0.15)
		(layer "B.Cu")
		(net 336)
	)
	(segment
		(start 107.16 99.29)
		(end 107.3493 99.1007)
		(width 0.15)
		(layer "F.Cu")
		(net 337)
	)
	(segment
		(start 107.3493 99.1007)
		(end 107.3493 98.8496)
		(width 0.15)
		(layer "F.Cu")
		(net 337)
	)
	(via
		(at 107.16 99.29)
		(size 0.45)
		(drill 0.1)
		(layers "F.Cu" "B.Cu")
		(net 337)
	)
	(segment
		(start 107.16 99.29)
		(end 107.16 99.0589)
		(width 0.15)
		(layer "B.Cu")
		(net 337)
	)
	(segment
		(start 107.16 99.0589)
		(end 107.3693 98.8496)
		(width 0.15)
		(layer "B.Cu")
		(net 337)
	)
	(segment
		(start 107.16 99.29)
		(end 106.95001 99.49999)
		(width 0.15)
		(layer "B.Cu")
		(net 337)
	)
	(segment
		(start 106.95001 99.49999)
		(end 101.79999 99.49999)
		(width 0.15)
		(layer "B.Cu")
		(net 337)
	)
	(segment
		(start 94.890089 98.359911)
		(end 95.55 97.7)
		(width 0.15)
		(layer "F.Cu")
		(net 338)
	)
	(segment
		(start 94.890089 98.930089)
		(end 94.890089 98.359911)
		(width 0.15)
		(layer "F.Cu")
		(net 338)
	)
	(segment
		(start 94.6 84.25)
		(end 94.45 84.25)
		(width 0.125)
		(layer "F.Cu")
		(net 338)
	)
	(segment
		(start 94.45 84.25)
		(end 94.27 84.43)
		(width 0.125)
		(layer "F.Cu")
		(net 338)
	)
	(segment
		(start 94.27 88.67)
		(end 95.55 89.95)
		(width 0.125)
		(layer "F.Cu")
		(net 338)
	)
	(segment
		(start 95.11 99.15)
		(end 94.890089 98.930089)
		(width 0.15)
		(layer "F.Cu")
		(net 338)
	)
	(segment
		(start 94.27 84.43)
		(end 94.27 88.67)
		(width 0.125)
		(layer "F.Cu")
		(net 338)
	)
	(segment
		(start 95.55 97.7)
		(end 95.55 89.95)
		(width 0.15)
		(layer "F.Cu")
		(net 338)
	)
	(via
		(at 94.6 84.25)
		(size 0.45)
		(drill 0.1)
		(layers "F.Cu" "B.Cu")
		(net 338)
	)
	(via
		(at 95.11 99.15)
		(size 0.45)
		(drill 0.1)
		(layers "F.Cu" "B.Cu")
		(net 338)
	)
	(via
		(at 87.35 102.55)
		(size 0.45)
		(drill 0.1)
		(layers "F.Cu" "B.Cu")
		(net 338)
	)
	(segment
		(start 93.36 100.9)
		(end 90.225 100.9)
		(width 0.15)
		(layer "In3.Cu")
		(net 338)
	)
	(segment
		(start 95.11 99.15)
		(end 93.36 100.9)
		(width 0.15)
		(layer "In3.Cu")
		(net 338)
	)
	(segment
		(start 88.575 102.55)
		(end 87.35 102.55)
		(width 0.15)
		(layer "In3.Cu")
		(net 338)
	)
	(segment
		(start 90.225 100.9)
		(end 88.575 102.55)
		(width 0.15)
		(layer "In3.Cu")
		(net 338)
	)
	(segment
		(start 94.85 84.5)
		(end 95.3 84.5)
		(width 0.125)
		(layer "B.Cu")
		(net 338)
	)
	(segment
		(start 94.6 84.25)
		(end 94.85 84.5)
		(width 0.125)
		(layer "B.Cu")
		(net 338)
	)
	(segment
		(start 98.3 82.1)
		(end 98.45 82.25)
		(width 0.125)
		(layer "B.Cu")
		(net 338)
	)
	(segment
		(start 95.9 83.9)
		(end 95.9 82.25)
		(width 0.125)
		(layer "B.Cu")
		(net 338)
	)
	(segment
		(start 88.685 104.420894)
		(end 87.707053 103.442947)
		(width 0.13)
		(layer "B.Cu")
		(net 338)
	)
	(segment
		(start 98.45 82.25)
		(end 98.45 83)
		(width 0.125)
		(layer "B.Cu")
		(net 338)
	)
	(segment
		(start 89.5 105.1)
		(end 88.685 105.1)
		(width 0.15)
		(layer "B.Cu")
		(net 338)
	)
	(segment
		(start 95.3 84.5)
		(end 95.9 83.9)
		(width 0.125)
		(layer "B.Cu")
		(net 338)
	)
	(segment
		(start 94.55 84.2)
		(end 94.55 83.2)
		(width 0.125)
		(layer "B.Cu")
		(net 338)
	)
	(segment
		(start 95.9 82.25)
		(end 96.05 82.1)
		(width 0.125)
		(layer "B.Cu")
		(net 338)
	)
	(segment
		(start 94.55 83.2)
		(end 94.75 83)
		(width 0.125)
		(layer "B.Cu")
		(net 338)
	)
	(segment
		(start 94.6 84.25)
		(end 94.55 84.2)
		(width 0.125)
		(layer "B.Cu")
		(net 338)
	)
	(segment
		(start 87.35 102.55)
		(end 87.35 103.085894)
		(width 0.13)
		(layer "B.Cu")
		(net 338)
	)
	(segment
		(start 88.685 105.1)
		(end 88.685 104.420894)
		(width 0.13)
		(layer "B.Cu")
		(net 338)
	)
	(segment
		(start 89.9318 105.7293)
		(end 89.9318 105.5318)
		(width 0.15)
		(layer "B.Cu")
		(net 338)
	)
	(segment
		(start 96.05 82.1)
		(end 98.3 82.1)
		(width 0.125)
		(layer "B.Cu")
		(net 338)
	)
	(segment
		(start 89.9318 105.5318)
		(end 89.5 105.1)
		(width 0.15)
		(layer "B.Cu")
		(net 338)
	)
	(segment
		(start 87.35 103.085894)
		(end 87.707053 103.442947)
		(width 0.13)
		(layer "B.Cu")
		(net 338)
	)
	(segment
		(start 55.75 80.09)
		(end 56.36 80.7)
		(width 0.15)
		(layer "B.Cu")
		(net 342)
	)
	(segment
		(start 55.75 78.8)
		(end 55.75 80.09)
		(width 0.15)
		(layer "B.Cu")
		(net 342)
	)
	(segment
		(start 97.5 83.835)
		(end 97.915 84.25)
		(width 0.155)
		(layer "B.Cu")
		(net 343)
	)
	(segment
		(start 97.5 83)
		(end 97.5 83.835)
		(width 0.155)
		(layer "B.Cu")
		(net 343)
	)
	(segment
		(start 93.8 83)
		(end 93.8 82.15)
		(width 0.125)
		(layer "B.Cu")
		(net 344)
	)
	(segment
		(start 93.8 82.15)
		(end 93.55 81.9)
		(width 0.125)
		(layer "B.Cu")
		(net 344)
	)
	(segment
		(start 93.55 81.9)
		(end 91.985 81.9)
		(width 0.125)
		(layer "B.Cu")
		(net 344)
	)
	(segment
		(start 91.985 81.9)
		(end 91.485 81.4)
		(width 0.125)
		(layer "B.Cu")
		(net 344)
	)
	(segment
		(start 138.44 93.91)
		(end 138.65 93.7)
		(width 0.15)
		(layer "F.Cu")
		(net 345)
	)
	(segment
		(start 138.65 93.7)
		(end 141.35 93.7)
		(width 0.15)
		(layer "F.Cu")
		(net 345)
	)
	(segment
		(start 141.35 93.7)
		(end 141.5 93.55)
		(width 0.15)
		(layer "F.Cu")
		(net 345)
	)
	(segment
		(start 137.85 93.91)
		(end 138.44 93.91)
		(width 0.15)
		(layer "F.Cu")
		(net 345)
	)
	(segment
		(start 138.4 94.55)
		(end 137.96 94.55)
		(width 0.15)
		(layer "F.Cu")
		(net 346)
	)
	(segment
		(start 140.15 94.7)
		(end 138.55 94.7)
		(width 0.15)
		(layer "F.Cu")
		(net 346)
	)
	(segment
		(start 137.96 94.55)
		(end 137.85 94.44)
		(width 0.15)
		(layer "F.Cu")
		(net 346)
	)
	(segment
		(start 141.5 94.35)
		(end 140.5 94.35)
		(width 0.15)
		(layer "F.Cu")
		(net 346)
	)
	(segment
		(start 140.5 94.35)
		(end 140.15 94.7)
		(width 0.15)
		(layer "F.Cu")
		(net 346)
	)
	(segment
		(start 138.55 94.7)
		(end 138.4 94.55)
		(width 0.15)
		(layer "F.Cu")
		(net 346)
	)
	(segment
		(start 147 94.7)
		(end 147.35 94.7)
		(width 0.15)
		(layer "F.Cu")
		(net 347)
	)
	(segment
		(start 146.65 94.35)
		(end 147 94.7)
		(width 0.15)
		(layer "F.Cu")
		(net 347)
	)
	(segment
		(start 146 94.35)
		(end 146.65 94.35)
		(width 0.15)
		(layer "F.Cu")
		(net 347)
	)
	(segment
		(start 141.35 95)
		(end 141.5 95.15)
		(width 0.15)
		(layer "F.Cu")
		(net 348)
	)
	(segment
		(start 137.92 95)
		(end 141.35 95)
		(width 0.15)
		(layer "F.Cu")
		(net 348)
	)
	(segment
		(start 87.55 111.15)
		(end 87 111.7)
		(width 0.15)
		(layer "B.Cu")
		(net 349)
	)
	(segment
		(start 87.7 110.25)
		(end 87.55 110.4)
		(width 0.15)
		(layer "B.Cu")
		(net 349)
	)
	(segment
		(start 87 111.7)
		(end 87 112.115)
		(width 0.15)
		(layer "B.Cu")
		(net 349)
	)
	(segment
		(start 88.1 110.25)
		(end 87.7 110.25)
		(width 0.15)
		(layer "B.Cu")
		(net 349)
	)
	(segment
		(start 87.55 110.4)
		(end 87.55 111.15)
		(width 0.15)
		(layer "B.Cu")
		(net 349)
	)
	(segment
		(start 88.75 111.365)
		(end 88 112.115)
		(width 0.15)
		(layer "B.Cu")
		(net 350)
	)
	(segment
		(start 88.75 110.9)
		(end 88.75 111.365)
		(width 0.15)
		(layer "B.Cu")
		(net 350)
	)
	(segment
		(start 88.35 107.95)
		(end 88.35 107.7)
		(width 0.15)
		(layer "B.Cu")
		(net 351)
	)
	(segment
		(start 88.75 108.1)
		(end 88.5 108.1)
		(width 0.15)
		(layer "B.Cu")
		(net 351)
	)
	(segment
		(start 88.35 107.7)
		(end 87.735 107.085)
		(width 0.15)
		(layer "B.Cu")
		(net 351)
	)
	(segment
		(start 87.735 107.085)
		(end 87.3 107.085)
		(width 0.15)
		(layer "B.Cu")
		(net 351)
	)
	(segment
		(start 88.5 108.1)
		(end 88.35 107.95)
		(width 0.15)
		(layer "B.Cu")
		(net 351)
	)
	(segment
		(start 88.0275 107.9775)
		(end 87.65 107.6)
		(width 0.155)
		(layer "B.Cu")
		(net 352)
	)
	(segment
		(start 88.0275 108.6775)
		(end 88.0275 107.9775)
		(width 0.155)
		(layer "B.Cu")
		(net 352)
	)
	(segment
		(start 86.715 107.6)
		(end 86.115 108.2)
		(width 0.155)
		(layer "B.Cu")
		(net 352)
	)
	(segment
		(start 87.65 107.6)
		(end 86.715 107.6)
		(width 0.155)
		(layer "B.Cu")
		(net 352)
	)
	(segment
		(start 88.1 108.75)
		(end 88.0275 108.6775)
		(width 0.155)
		(layer "B.Cu")
		(net 352)
	)
	(segment
		(start 89.5254 106.7707)
		(end 89.5254 107.3746)
		(width 0.15)
		(layer "B.Cu")
		(net 353)
	)
	(segment
		(start 89.5254 107.3746)
		(end 89.25 107.65)
		(width 0.15)
		(layer "B.Cu")
		(net 353)
	)
	(segment
		(start 89.25 107.65)
		(end 89.25 108.1)
		(width 0.15)
		(layer "B.Cu")
		(net 353)
	)
	(segment
		(start 89.75 108.1)
		(end 89.75 107.675)
		(width 0.15)
		(layer "B.Cu")
		(net 354)
	)
	(segment
		(start 89.9318 107.4932)
		(end 89.9318 106.7707)
		(width 0.15)
		(layer "B.Cu")
		(net 354)
	)
	(segment
		(start 89.75 107.675)
		(end 89.9318 107.4932)
		(width 0.15)
		(layer "B.Cu")
		(net 354)
	)
	(segment
		(start 90.25 108.1)
		(end 90.25 107.65)
		(width 0.15)
		(layer "B.Cu")
		(net 355)
	)
	(segment
		(start 90.25 107.65)
		(end 90.35 107.55)
		(width 0.15)
		(layer "B.Cu")
		(net 355)
	)
	(segment
		(start 90.35 106.565)
		(end 90.335 106.55)
		(width 0.15)
		(layer "B.Cu")
		(net 355)
	)
	(segment
		(start 90.35 107.55)
		(end 90.35 106.565)
		(width 0.15)
		(layer "B.Cu")
		(net 355)
	)
	(segment
		(start 90.7446 107.6946)
		(end 90.7446 106.7707)
		(width 0.15)
		(layer "B.Cu")
		(net 356)
	)
	(segment
		(start 90.9 107.85)
		(end 90.7446 107.6946)
		(width 0.15)
		(layer "B.Cu")
		(net 356)
	)
	(segment
		(start 90.9 108.75)
		(end 90.9 107.85)
		(width 0.15)
		(layer "B.Cu")
		(net 356)
	)
	(segment
		(start 114.489601 82.028176)
		(end 114.439793 81.978368)
		(width 0.155)
		(layer "F.Cu")
		(net 357)
	)
	(segment
		(start 110.389413 81.787987)
		(end 110.349335 81.747909)
		(width 0.155)
		(layer "F.Cu")
		(net 357)
	)
	(segment
		(start 114.73789 82.07211)
		(end 114.595667 82.07211)
		(width 0.155)
		(layer "F.Cu")
		(net 357)
	)
	(segment
		(start 133.395181 83.3005)
		(end 135.369525 83.3005)
		(width 0.155)
		(layer "F.Cu")
		(net 357)
	)
	(segment
		(start 132.94211 85.55789)
		(end 132.94211 85.49851)
		(width 0.155)
		(layer "F.Cu")
		(net 357)
	)
	(segment
		(start 110.246823 81.030636)
		(end 110.347323 80.930136)
		(width 0.155)
		(layer "F.Cu")
		(net 357)
	)
	(segment
		(start 132.839597 85.251022)
		(end 132.646946 85.058371)
		(width 0.155)
		(layer "F.Cu")
		(net 357)
	)
	(segment
		(start 132.646947 83.841627)
		(end 133.041628 83.446946)
		(width 0.155)
		(layer "F.Cu")
		(net 357)
	)
	(segment
		(start 114.227661 81.8905)
		(end 110.636901 81.8905)
		(width 0.155)
		(layer "F.Cu")
		(net 357)
	)
	(segment
		(start 135.617013 83.197987)
		(end 135.865 82.95)
		(width 0.155)
		(layer "F.Cu")
		(net 357)
	)
	(segment
		(start 110.246823 81.500422)
		(end 110.246823 81.030636)
		(width 0.155)
		(layer "F.Cu")
		(net 357)
	)
	(segment
		(start 132.5005 84.704818)
		(end 132.5005 84.195181)
		(width 0.155)
		(layer "F.Cu")
		(net 357)
	)
	(via
		(at 132.94211 85.55789)
		(size 0.45)
		(drill 0.1)
		(layers "F.Cu" "B.Cu")
		(net 357)
	)
	(via
		(at 114.73789 82.07211)
		(size 0.45)
		(drill 0.1)
		(layers "F.Cu" "B.Cu")
		(net 357)
	)
	(arc
		(start 132.94211 85.49851)
		(mid 132.915468 85.36457)
		(end 132.839597 85.251022)
		(width 0.155)
		(layer "F.Cu")
		(net 357)
	)
	(arc
		(start 132.646946 85.058371)
		(mid 132.53856 84.896159)
		(end 132.5005 84.704818)
		(width 0.155)
		(layer "F.Cu")
		(net 357)
	)
	(arc
		(start 114.227661 81.8905)
		(mid 114.342466 81.913336)
		(end 114.439793 81.978368)
		(width 0.155)
		(layer "F.Cu")
		(net 357)
	)
	(arc
		(start 135.369525 83.3005)
		(mid 135.503465 83.273858)
		(end 135.617013 83.197987)
		(width 0.155)
		(layer "F.Cu")
		(net 357)
	)
	(arc
		(start 110.349335 81.747909)
		(mid 110.273465 81.634361)
		(end 110.246823 81.500422)
		(width 0.155)
		(layer "F.Cu")
		(net 357)
	)
	(arc
		(start 114.595667 82.07211)
		(mid 114.538264 82.060692)
		(end 114.489601 82.028176)
		(width 0.155)
		(layer "F.Cu")
		(net 357)
	)
	(arc
		(start 133.395181 83.3005)
		(mid 133.20384 83.33856)
		(end 133.041628 83.446946)
		(width 0.155)
		(layer "F.Cu")
		(net 357)
	)
	(arc
		(start 110.636901 81.8905)
		(mid 110.502961 81.863858)
		(end 110.389413 81.787987)
		(width 0.155)
		(layer "F.Cu")
		(net 357)
	)
	(arc
		(start 132.646947 83.841627)
		(mid 132.53856 84.003839)
		(end 132.5005 84.195181)
		(width 0.155)
		(layer "F.Cu")
		(net 357)
	)
	(segment
		(start 114.73789 82.277172)
		(end 115.799 83.338282)
		(width 0.16)
		(layer "In5.Cu")
		(net 357)
	)
	(segment
		(start 120.228568 95.759959)
		(end 120.216042 95.772482)
		(width 0.16)
		(layer "In5.Cu")
		(net 357)
	)
	(segment
		(start 120.228569 95.477118)
		(end 120.228568 95.477117)
		(width 0.16)
		(layer "In5.Cu")
		(net 357)
	)
	(segment
		(start 128.228282 97.261)
		(end 131.001 94.488282)
		(width 0.16)
		(layer "In5.Cu")
		(net 357)
	)
	(segment
		(start 118.974 94.813282)
		(end 119.650359 95.489641)
		(width 0.16)
		(layer "In5.Cu")
		(net 357)
	)
	(segment
		(start 119.933201 95.489641)
		(end 119.945726 95.477117)
		(width 0.16)
		(layer "In5.Cu")
		(net 357)
	)
	(segment
		(start 133.147172 85.55789)
		(end 132.94211 85.55789)
		(width 0.16)
		(layer "In5.Cu")
		(net 357)
	)
	(segment
		(start 133.301 85.711718)
		(end 133.147172 85.55789)
		(width 0.16)
		(layer "In5.Cu")
		(net 357)
	)
	(segment
		(start 133.301 87.788282)
		(end 133.301 85.711718)
		(width 0.16)
		(layer "In5.Cu")
		(net 357)
	)
	(segment
		(start 115.799 85.888282)
		(end 118.974 89.063282)
		(width 0.16)
		(layer "In5.Cu")
		(net 357)
	)
	(segment
		(start 132.988282 88.101)
		(end 133.301 87.788282)
		(width 0.16)
		(layer "In5.Cu")
		(net 357)
	)
	(segment
		(start 120.228567 95.75996)
		(end 120.228568 95.759959)
		(width 0.16)
		(layer "In5.Cu")
		(net 357)
	)
	(segment
		(start 131.001 88.988282)
		(end 131.888282 88.101)
		(width 0.16)
		(layer "In5.Cu")
		(net 357)
	)
	(segment
		(start 121.421718 97.261)
		(end 128.228282 97.261)
		(width 0.16)
		(layer "In5.Cu")
		(net 357)
	)
	(segment
		(start 131.001 94.488282)
		(end 131.001 88.988282)
		(width 0.16)
		(layer "In5.Cu")
		(net 357)
	)
	(segment
		(start 118.974 89.063282)
		(end 118.974 94.813282)
		(width 0.16)
		(layer "In5.Cu")
		(net 357)
	)
	(segment
		(start 120.216043 96.055325)
		(end 120.216042 96.055324)
		(width 0.16)
		(layer "In5.Cu")
		(net 357)
	)
	(segment
		(start 119.933202 95.48964)
		(end 119.933201 95.489641)
		(width 0.16)
		(layer "In5.Cu")
		(net 357)
	)
	(segment
		(start 115.799 83.338282)
		(end 115.799 85.888282)
		(width 0.16)
		(layer "In5.Cu")
		(net 357)
	)
	(segment
		(start 114.73789 82.07211)
		(end 114.73789 82.277172)
		(width 0.16)
		(layer "In5.Cu")
		(net 357)
	)
	(segment
		(start 120.216042 96.055324)
		(end 121.421718 97.261)
		(width 0.16)
		(layer "In5.Cu")
		(net 357)
	)
	(segment
		(start 131.888282 88.101)
		(end 132.988282 88.101)
		(width 0.16)
		(layer "In5.Cu")
		(net 357)
	)
	(arc
		(start 120.216042 95.772482)
		(mid 120.157464 95.913904)
		(end 120.216043 96.055325)
		(width 0.16)
		(layer "In5.Cu")
		(net 357)
	)
	(arc
		(start 119.650359 95.489641)
		(mid 119.791781 95.548219)
		(end 119.933202 95.48964)
		(width 0.16)
		(layer "In5.Cu")
		(net 357)
	)
	(arc
		(start 119.945726 95.477117)
		(mid 120.087148 95.418539)
		(end 120.228569 95.477118)
		(width 0.16)
		(layer "In5.Cu")
		(net 357)
	)
	(arc
		(start 120.228568 95.477117)
		(mid 120.287146 95.618539)
		(end 120.228567 95.75996)
		(width 0.16)
		(layer "In5.Cu")
		(net 357)
	)
	(segment
		(start 76.125 87.475)
		(end 76.125 86.565)
		(width 0.125)
		(layer "F.Cu")
		(net 358)
	)
	(segment
		(start 76.125 86.565)
		(end 75.9 86.34)
		(width 0.125)
		(layer "F.Cu")
		(net 358)
	)
	(segment
		(start 141.4925 98.5075)
		(end 142 98)
		(width 0.15)
		(layer "B.Cu")
		(net 360)
	)
	(segment
		(start 139.75 98.5075)
		(end 141.4925 98.5075)
		(width 0.15)
		(layer "B.Cu")
		(net 360)
	)
	(segment
		(start 142 98)
		(end 143.15 98)
		(width 0.15)
		(layer "B.Cu")
		(net 360)
	)
	(segment
		(start 110.114948 104.745)
		(end 110.455 104.745)
		(width 0.15)
		(layer "F.Cu")
		(net 362)
	)
	(segment
		(start 110.8 103.135)
		(end 110.8 103.15)
		(width 0.15)
		(layer "F.Cu")
		(net 362)
	)
	(segment
		(start 110.8 103.15)
		(end 111.3 103.65)
		(width 0.15)
		(layer "F.Cu")
		(net 362)
	)
	(segment
		(start 110.455 104.745)
		(end 111.3 103.9)
		(width 0.15)
		(layer "F.Cu")
		(net 362)
	)
	(segment
		(start 111.3 103.9)
		(end 111.3 103.65)
		(width 0.15)
		(layer "F.Cu")
		(net 362)
	)
	(via
		(at 111.3 103.65)
		(size 0.45)
		(drill 0.1)
		(layers "F.Cu" "B.Cu")
		(net 362)
	)
	(segment
		(start 110.285 105.4)
		(end 110.285 104.665)
		(width 0.125)
		(layer "B.Cu")
		(net 362)
	)
	(segment
		(start 110.285 104.665)
		(end 111.3 103.65)
		(width 0.125)
		(layer "B.Cu")
		(net 362)
	)
	(segment
		(start 109.955 104.345)
		(end 110.040938 104.259062)
		(width 0.15)
		(layer "F.Cu")
		(net 363)
	)
	(segment
		(start 110.040938 103.375938)
		(end 109.8 103.135)
		(width 0.15)
		(layer "F.Cu")
		(net 363)
	)
	(segment
		(start 109.689938 104.345)
		(end 109.955 104.345)
		(width 0.15)
		(layer "F.Cu")
		(net 363)
	)
	(segment
		(start 110.040938 104.259062)
		(end 110.040938 103.375938)
		(width 0.15)
		(layer "F.Cu")
		(net 363)
	)
	(via
		(at 110.040938 104.259062)
		(size 0.45)
		(drill 0.1)
		(layers "F.Cu" "B.Cu")
		(net 363)
	)
	(segment
		(start 109.385 104.4)
		(end 109.9 104.4)
		(width 0.125)
		(layer "B.Cu")
		(net 363)
	)
	(segment
		(start 109.9 104.4)
		(end 110.040938 104.259062)
		(width 0.125)
		(layer "B.Cu")
		(net 363)
	)
	(segment
		(start 108.089938 108.745)
		(end 108.089938 109.110062)
		(width 0.15)
		(layer "F.Cu")
		(net 364)
	)
	(segment
		(start 108.089938 109.110062)
		(end 107.2 110)
		(width 0.15)
		(layer "F.Cu")
		(net 364)
	)
	(segment
		(start 107.1 106.35)
		(end 107.105 106.345)
		(width 0.15)
		(layer "F.Cu")
		(net 365)
	)
	(segment
		(start 107.105 106.345)
		(end 107.689938 106.345)
		(width 0.15)
		(layer "F.Cu")
		(net 365)
	)
	(via
		(at 107.1 106.35)
		(size 0.45)
		(drill 0.1)
		(layers "F.Cu" "B.Cu")
		(net 365)
	)
	(segment
		(start 106.1 106.35)
		(end 107.1 106.35)
		(width 0.2)
		(layer "B.Cu")
		(net 365)
	)
	(segment
		(start 103.25 109.2)
		(end 106.1 106.35)
		(width 0.2)
		(layer "B.Cu")
		(net 365)
	)
	(segment
		(start 103.25 113.015)
		(end 103.25 109.2)
		(width 0.2)
		(layer "B.Cu")
		(net 365)
	)
	(segment
		(start 109.973572 120.828634)
		(end 109.973572 120.128634)
		(width 0.165)
		(layer "F.Cu")
		(net 366)
	)
	(segment
		(start 109.5605 119.671926)
		(end 109.5605 117.03)
		(width 0.155)
		(layer "F.Cu")
		(net 366)
	)
	(segment
		(start 111.545 120.834559)
		(end 111.113328 121.266231)
		(width 0.165)
		(layer "F.Cu")
		(net 366)
	)
	(segment
		(start 109.55 117.0195)
		(end 109.5605 117.03)
		(width 0.155)
		(layer "F.Cu")
		(net 366)
	)
	(segment
		(start 109.55 116.20625)
		(end 109.55 115.793749)
		(width 0.155)
		(layer "F.Cu")
		(net 366)
	)
	(segment
		(start 109.6505 113.161926)
		(end 109.340438 112.851864)
		(width 0.155)
		(layer "F.Cu")
		(net 366)
	)
	(segment
		(start 109.55 115.915)
		(end 109.55 115.502499)
		(width 0.155)
		(layer "F.Cu")
		(net 366)
	)
	(segment
		(start 109.55 116.563749)
		(end 109.55 117.0195)
		(width 0.155)
		(layer "F.Cu")
		(net 366)
	)
	(segment
		(start 109.55 116.438749)
		(end 109.6505 116.338249)
		(width 0.155)
		(layer "F.Cu")
		(net 366)
	)
	(segment
		(start 109.55 115.502499)
		(end 109.6505 115.401999)
		(width 0.155)
		(layer "F.Cu")
		(net 366)
	)
	(segment
		(start 109.973572 120.084998)
		(end 109.5605 119.671926)
		(width 0.155)
		(layer "F.Cu")
		(net 366)
	)
	(segment
		(start 111.8 120.15)
		(end 111.545 120.405)
		(width 0.165)
		(layer "F.Cu")
		(net 366)
	)
	(segment
		(start 109.6505 116.338249)
		(end 109.6505 116.30675)
		(width 0.155)
		(layer "F.Cu")
		(net 366)
	)
	(segment
		(start 109.6505 115.401999)
		(end 109.6505 113.161926)
		(width 0.155)
		(layer "F.Cu")
		(net 366)
	)
	(segment
		(start 111.113328 121.266231)
		(end 110.411169 121.266231)
		(width 0.165)
		(layer "F.Cu")
		(net 366)
	)
	(segment
		(start 109.973572 120.128634)
		(end 109.973572 120.084998)
		(width 0.155)
		(layer "F.Cu")
		(net 366)
	)
	(segment
		(start 110.411169 121.266231)
		(end 109.973572 120.828634)
		(width 0.165)
		(layer "F.Cu")
		(net 366)
	)
	(segment
		(start 109.340438 112.851864)
		(end 109.340438 109.133001)
		(width 0.155)
		(layer "F.Cu")
		(net 366)
	)
	(segment
		(start 109.289938 109.082501)
		(end 109.289938 108.745)
		(width 0.155)
		(layer "F.Cu")
		(net 366)
	)
	(segment
		(start 109.340438 109.133001)
		(end 109.289938 109.082501)
		(width 0.155)
		(layer "F.Cu")
		(net 366)
	)
	(segment
		(start 109.6505 116.30675)
		(end 109.55 116.20625)
		(width 0.155)
		(layer "F.Cu")
		(net 366)
	)
	(segment
		(start 111.545 120.405)
		(end 111.545 120.834559)
		(width 0.165)
		(layer "F.Cu")
		(net 366)
	)
	(segment
		(start 109.745 76.991777)
		(end 110.256706 77.503483)
		(width 0.125)
		(layer "F.Cu")
		(net 367)
	)
	(segment
		(start 110.222323 73.680899)
		(end 109.745 74.158222)
		(width 0.125)
		(layer "F.Cu")
		(net 367)
	)
	(segment
		(start 110.256706 77.503483)
		(end 110.256706 77.733294)
		(width 0.125)
		(layer "F.Cu")
		(net 367)
	)
	(segment
		(start 109.745 74.158222)
		(end 109.745 76.991777)
		(width 0.125)
		(layer "F.Cu")
		(net 367)
	)
	(segment
		(start 110.097323 72.005136)
		(end 110.097323 72.730136)
		(width 0.125)
		(layer "F.Cu")
		(net 367)
	)
	(segment
		(start 110.097323 72.730136)
		(end 110.222323 72.855136)
		(width 0.125)
		(layer "F.Cu")
		(net 367)
	)
	(segment
		(start 110.222323 72.855136)
		(end 110.222323 73.680899)
		(width 0.125)
		(layer "F.Cu")
		(net 367)
	)
	(via
		(at 110.256706 77.733294)
		(size 0.45)
		(drill 0.1)
		(layers "F.Cu" "B.Cu")
		(net 367)
	)
	(segment
		(start 99.763222 94.3)
		(end 102.965 91.098222)
		(width 0.125)
		(layer "B.Cu")
		(net 367)
	)
	(segment
		(start 110.528222 80.025)
		(end 111.125 79.428222)
		(width 0.125)
		(layer "B.Cu")
		(net 367)
	)
	(segment
		(start 111.125 78.371777)
		(end 110.486517 77.733294)
		(width 0.125)
		(layer "B.Cu")
		(net 367)
	)
	(segment
		(start 96.035 93.95)
		(end 96.385 94.3)
		(width 0.125)
		(layer "B.Cu")
		(net 367)
	)
	(segment
		(start 108.505 81.578222)
		(end 108.505 80.588222)
		(width 0.125)
		(layer "B.Cu")
		(net 367)
	)
	(segment
		(start 102.58621 89.385)
		(end 102.58621 89.36379)
		(width 0.125)
		(layer "B.Cu")
		(net 367)
	)
	(segment
		(start 96.385 94.3)
		(end 99.763222 94.3)
		(width 0.125)
		(layer "B.Cu")
		(net 367)
	)
	(segment
		(start 110.486517 77.733294)
		(end 110.256706 77.733294)
		(width 0.125)
		(layer "B.Cu")
		(net 367)
	)
	(segment
		(start 102.965 87.118222)
		(end 108.505 81.578222)
		(width 0.125)
		(layer "B.Cu")
		(net 367)
	)
	(segment
		(start 102.965 88.985)
		(end 102.965 87.118222)
		(width 0.125)
		(layer "B.Cu")
		(net 367)
	)
	(segment
		(start 102.965 91.098222)
		(end 102.965 89.76379)
		(width 0.125)
		(layer "B.Cu")
		(net 367)
	)
	(segment
		(start 108.505 80.588222)
		(end 109.068222 80.025)
		(width 0.125)
		(layer "B.Cu")
		(net 367)
	)
	(segment
		(start 109.068222 80.025)
		(end 110.528222 80.025)
		(width 0.125)
		(layer "B.Cu")
		(net 367)
	)
	(segment
		(start 111.125 79.428222)
		(end 111.125 78.371777)
		(width 0.125)
		(layer "B.Cu")
		(net 367)
	)
	(arc
		(start 102.775605 89.174395)
		(mid 102.909527 89.118922)
		(end 102.965 88.985)
		(width 0.125)
		(layer "B.Cu")
		(net 367)
	)
	(arc
		(start 102.775605 89.574395)
		(mid 102.641683 89.518922)
		(end 102.58621 89.385)
		(width 0.125)
		(layer "B.Cu")
		(net 367)
	)
	(arc
		(start 102.58621 89.36379)
		(mid 102.641683 89.229868)
		(end 102.775605 89.174395)
		(width 0.125)
		(layer "B.Cu")
		(net 367)
	)
	(arc
		(start 102.965 89.76379)
		(mid 102.909527 89.629868)
		(end 102.775605 89.574395)
		(width 0.125)
		(layer "B.Cu")
		(net 367)
	)
	(segment
		(start 109.639438 112.728012)
		(end 109.639438 109.133001)
		(width 0.155)
		(layer "F.Cu")
		(net 368)
	)
	(segment
		(start 109.8595 119.0895)
		(end 109.8595 119.548074)
		(width 0.155)
		(layer "F.Cu")
		(net 368)
	)
	(segment
		(start 109.9495 113.038074)
		(end 109.639438 112.728012)
		(width 0.155)
		(layer "F.Cu")
		(net 368)
	)
	(segment
		(start 110.05 116.20625)
		(end 110.05 115.793749)
		(width 0.155)
		(layer "F.Cu")
		(net 368)
	)
	(segment
		(start 110.057259 118.8645)
		(end 110.0345 118.8645)
		(width 0.155)
		(layer "F.Cu")
		(net 368)
	)
	(segment
		(start 109.8595 119.0395)
		(end 109.8595 119.0895)
		(width 0.155)
		(layer "F.Cu")
		(net 368)
	)
	(segment
		(start 110.263572 119.952146)
		(end 110.263572 120.00851)
		(width 0.155)
		(layer "F.Cu")
		(net 368)
	)
	(segment
		(start 110.993204 120.976231)
		(end 110.531293 120.976231)
		(width 0.165)
		(layer "F.Cu")
		(net 368)
	)
	(segment
		(start 109.8595 119.548074)
		(end 110.263572 119.952146)
		(width 0.155)
		(layer "F.Cu")
		(net 368)
	)
	(segment
		(start 109.639438 109.133001)
		(end 109.689938 109.082501)
		(width 0.155)
		(layer "F.Cu")
		(net 368)
	)
	(segment
		(start 111.255 120.714435)
		(end 110.993204 120.976231)
		(width 0.165)
		(layer "F.Cu")
		(net 368)
	)
	(segment
		(start 111.255 120.405)
		(end 111.255 120.714435)
		(width 0.165)
		(layer "F.Cu")
		(net 368)
	)
	(segment
		(start 110.05 115.915)
		(end 110.05 115.502499)
		(width 0.155)
		(layer "F.Cu")
		(net 368)
	)
	(segment
		(start 110.05 115.502499)
		(end 109.9495 115.401999)
		(width 0.155)
		(layer "F.Cu")
		(net 368)
	)
	(segment
		(start 111 120.15)
		(end 111.255 120.405)
		(width 0.165)
		(layer "F.Cu")
		(net 368)
	)
	(segment
		(start 109.9495 116.338249)
		(end 109.9495 116.30675)
		(width 0.155)
		(layer "F.Cu")
		(net 368)
	)
	(segment
		(start 110.05 116.563749)
		(end 110.05 116.8395)
		(width 0.155)
		(layer "F.Cu")
		(net 368)
	)
	(segment
		(start 110.531293 120.976231)
		(end 110.263572 120.70851)
		(width 0.165)
		(layer "F.Cu")
		(net 368)
	)
	(segment
		(start 110.057259 118.1645)
		(end 110.0345 118.1645)
		(width 0.155)
		(layer "F.Cu")
		(net 368)
	)
	(segment
		(start 110.0345 118.5145)
		(end 110.057259 118.5145)
		(width 0.155)
		(layer "F.Cu")
		(net 368)
	)
	(segment
		(start 109.9495 115.401999)
		(end 109.9495 113.038074)
		(width 0.155)
		(layer "F.Cu")
		(net 368)
	)
	(segment
		(start 110.05 116.8395)
		(end 109.8595 117.03)
		(width 0.155)
		(layer "F.Cu")
		(net 368)
	)
	(segment
		(start 109.8595 117.03)
		(end 109.8595 117.6395)
		(width 0.155)
		(layer "F.Cu")
		(net 368)
	)
	(segment
		(start 110.0345 117.8145)
		(end 110.057259 117.8145)
		(width 0.155)
		(layer "F.Cu")
		(net 368)
	)
	(segment
		(start 110.263572 120.70851)
		(end 110.263572 120.00851)
		(width 0.165)
		(layer "F.Cu")
		(net 368)
	)
	(segment
		(start 109.9495 116.30675)
		(end 110.05 116.20625)
		(width 0.155)
		(layer "F.Cu")
		(net 368)
	)
	(segment
		(start 109.689938 109.082501)
		(end 109.689938 108.745)
		(width 0.155)
		(layer "F.Cu")
		(net 368)
	)
	(segment
		(start 110.05 116.438749)
		(end 109.9495 116.338249)
		(width 0.155)
		(layer "F.Cu")
		(net 368)
	)
	(arc
		(start 110.232259 118.6895)
		(mid 110.181003 118.813244)
		(end 110.057259 118.8645)
		(width 0.155)
		(layer "F.Cu")
		(net 368)
	)
	(arc
		(start 110.0345 118.8645)
		(mid 109.910756 118.915756)
		(end 109.8595 119.0395)
		(width 0.155)
		(layer "F.Cu")
		(net 368)
	)
	(arc
		(start 109.8595 118.3395)
		(mid 109.910756 118.463244)
		(end 110.0345 118.5145)
		(width 0.155)
		(layer "F.Cu")
		(net 368)
	)
	(arc
		(start 110.057259 118.5145)
		(mid 110.181003 118.565756)
		(end 110.232259 118.6895)
		(width 0.155)
		(layer "F.Cu")
		(net 368)
	)
	(arc
		(start 109.8595 117.6395)
		(mid 109.910756 117.763244)
		(end 110.0345 117.8145)
		(width 0.155)
		(layer "F.Cu")
		(net 368)
	)
	(arc
		(start 110.232259 117.9895)
		(mid 110.181003 118.113244)
		(end 110.057259 118.1645)
		(width 0.155)
		(layer "F.Cu")
		(net 368)
	)
	(arc
		(start 110.057259 117.8145)
		(mid 110.181003 117.865756)
		(end 110.232259 117.9895)
		(width 0.155)
		(layer "F.Cu")
		(net 368)
	)
	(arc
		(start 110.0345 118.1645)
		(mid 109.910756 118.215756)
		(end 109.8595 118.3395)
		(width 0.155)
		(layer "F.Cu")
		(net 368)
	)
	(segment
		(start 115.250505 117.649505)
		(end 115.250505 117.498069)
		(width 0.155)
		(layer "F.Cu")
		(net 369)
	)
	(segment
		(start 115.250505 117.498069)
		(end 115.6505 117.098074)
		(width 0.155)
		(layer "F.Cu")
		(net 369)
	)
	(segment
		(start 115.55 115.502499)
		(end 115.55 115.3005)
		(width 0.155)
		(layer "F.Cu")
		(net 369)
	)
	(segment
		(start 115.6505 115.2)
		(end 115.6505 114.7605)
		(width 0.155)
		(layer "F.Cu")
		(net 369)
	)
	(segment
		(start 115.55 115.3005)
		(end 115.6505 115.2)
		(width 0.155)
		(layer "F.Cu")
		(net 369)
	)
	(segment
		(start 115.431117 114.1605)
		(end 115.4505 114.1605)
		(width 0.155)
		(layer "F.Cu")
		(net 369)
	)
	(segment
		(start 110.515439 107.4945)
		(end 110.464939 107.545)
		(width 0.155)
		(layer "F.Cu")
		(net 369)
	)
	(segment
		(start 115.6505 113.9605)
		(end 115.6505 110.911926)
		(width 0.155)
		(layer "F.Cu")
		(net 369)
	)
	(segment
		(start 112.233074 107.4945)
		(end 110.515439 107.4945)
		(width 0.155)
		(layer "F.Cu")
		(net 369)
	)
	(segment
		(start 115.55 116.81)
		(end 115.55 116.685)
		(width 0.155)
		(layer "F.Cu")
		(net 369)
	)
	(segment
		(start 115.6505 110.911926)
		(end 112.233074 107.4945)
		(width 0.155)
		(layer "F.Cu")
		(net 369)
	)
	(segment
		(start 115.6505 117.098074)
		(end 115.6505 116.9105)
		(width 0.155)
		(layer "F.Cu")
		(net 369)
	)
	(segment
		(start 115.6505 116.9105)
		(end 115.55 116.81)
		(width 0.155)
		(layer "F.Cu")
		(net 369)
	)
	(segment
		(start 115.4505 114.5605)
		(end 115.431117 114.5605)
		(width 0.155)
		(layer "F.Cu")
		(net 369)
	)
	(segment
		(start 115.55 116.563749)
		(end 115.55 115.793749)
		(width 0.155)
		(layer "F.Cu")
		(net 369)
	)
	(segment
		(start 110.464939 107.545)
		(end 110.089938 107.545)
		(width 0.155)
		(layer "F.Cu")
		(net 369)
	)
	(segment
		(start 115.55 115.502499)
		(end 115.55 115.915)
		(width 0.165)
		(layer "F.Cu")
		(net 369)
	)
	(segment
		(start 115.15001 117.75)
		(end 115.250505 117.649505)
		(width 0.155)
		(layer "F.Cu")
		(net 369)
	)
	(arc
		(start 115.231117 114.3605)
		(mid 115.289696 114.219079)
		(end 115.431117 114.1605)
		(width 0.155)
		(layer "F.Cu")
		(net 369)
	)
	(arc
		(start 115.6505 114.7605)
		(mid 115.591921 114.619079)
		(end 115.4505 114.5605)
		(width 0.155)
		(layer "F.Cu")
		(net 369)
	)
	(arc
		(start 115.4505 114.1605)
		(mid 115.591921 114.101921)
		(end 115.6505 113.9605)
		(width 0.155)
		(layer "F.Cu")
		(net 369)
	)
	(arc
		(start 115.431117 114.5605)
		(mid 115.289696 114.501921)
		(end 115.231117 114.3605)
		(width 0.155)
		(layer "F.Cu")
		(net 369)
	)
	(segment
		(start 133.051022 85.039597)
		(end 132.902012 84.890587)
		(width 0.155)
		(layer "F.Cu")
		(net 370)
	)
	(segment
		(start 133.456901 83.5995)
		(end 135.369525 83.5995)
		(width 0.155)
		(layer "F.Cu")
		(net 370)
	)
	(segment
		(start 135.617013 83.702013)
		(end 135.865 83.95)
		(width 0.155)
		(layer "F.Cu")
		(net 370)
	)
	(segment
		(start 132.902013 84.009413)
		(end 133.209414 83.702012)
		(width 0.155)
		(layer "F.Cu")
		(net 370)
	)
	(segment
		(start 114.278176 82.239601)
		(end 114.272009 82.233434)
		(width 0.155)
		(layer "F.Cu")
		(net 370)
	)
	(segment
		(start 110.221627 82.043053)
		(end 110.094269 81.915695)
		(width 0.155)
		(layer "F.Cu")
		(net 370)
	)
	(segment
		(start 133.35789 85.14211)
		(end 133.29851 85.14211)
		(width 0.155)
		(layer "F.Cu")
		(net 370)
	)
	(segment
		(start 132.7995 84.6431)
		(end 132.7995 84.256901)
		(width 0.155)
		(layer "F.Cu")
		(net 370)
	)
	(segment
		(start 114.165943 82.1895)
		(end 110.575181 82.1895)
		(width 0.155)
		(layer "F.Cu")
		(net 370)
	)
	(segment
		(start 109.947823 81.030636)
		(end 109.847323 80.930136)
		(width 0.155)
		(layer "F.Cu")
		(net 370)
	)
	(segment
		(start 109.947823 81.562142)
		(end 109.947823 81.030636)
		(width 0.155)
		(layer "F.Cu")
		(net 370)
	)
	(segment
		(start 114.32211 82.48789)
		(end 114.32211 82.345667)
		(width 0.155)
		(layer "F.Cu")
		(net 370)
	)
	(via
		(at 133.35789 85.14211)
		(size 0.45)
		(drill 0.1)
		(layers "F.Cu" "B.Cu")
		(net 370)
	)
	(via
		(at 114.32211 82.48789)
		(size 0.45)
		(drill 0.1)
		(layers "F.Cu" "B.Cu")
		(net 370)
	)
	(arc
		(start 132.902013 84.009413)
		(mid 132.826142 84.122961)
		(end 132.7995 84.256901)
		(width 0.155)
		(layer "F.Cu")
		(net 370)
	)
	(arc
		(start 132.902012 84.890587)
		(mid 132.826142 84.777039)
		(end 132.7995 84.6431)
		(width 0.155)
		(layer "F.Cu")
		(net 370)
	)
	(arc
		(start 133.456901 83.5995)
		(mid 133.322962 83.626142)
		(end 133.209414 83.702012)
		(width 0.155)
		(layer "F.Cu")
		(net 370)
	)
	(arc
		(start 110.575181 82.1895)
		(mid 110.383839 82.15144)
		(end 110.221627 82.043053)
		(width 0.155)
		(layer "F.Cu")
		(net 370)
	)
	(arc
		(start 133.051022 85.039597)
		(mid 133.16457 85.115468)
		(end 133.29851 85.14211)
		(width 0.155)
		(layer "F.Cu")
		(net 370)
	)
	(arc
		(start 114.32211 82.345667)
		(mid 114.310692 82.288264)
		(end 114.278176 82.239601)
		(width 0.155)
		(layer "F.Cu")
		(net 370)
	)
	(arc
		(start 110.094269 81.915695)
		(mid 109.985883 81.753483)
		(end 109.947823 81.562142)
		(width 0.155)
		(layer "F.Cu")
		(net 370)
	)
	(arc
		(start 135.369525 83.5995)
		(mid 135.503465 83.626142)
		(end 135.617013 83.702013)
		(width 0.155)
		(layer "F.Cu")
		(net 370)
	)
	(arc
		(start 114.165943 82.1895)
		(mid 114.223346 82.200918)
		(end 114.272009 82.233434)
		(width 0.155)
		(layer "F.Cu")
		(net 370)
	)
	(segment
		(start 133.599 87.911718)
		(end 133.111718 88.399)
		(width 0.16)
		(layer "In5.Cu")
		(net 370)
	)
	(segment
		(start 115.501 83.461718)
		(end 114.527172 82.48789)
		(width 0.16)
		(layer "In5.Cu")
		(net 370)
	)
	(segment
		(start 133.111718 88.399)
		(end 132.011718 88.399)
		(width 0.16)
		(layer "In5.Cu")
		(net 370)
	)
	(segment
		(start 133.35789 85.14211)
		(end 133.35789 85.347172)
		(width 0.16)
		(layer "In5.Cu")
		(net 370)
	)
	(segment
		(start 114.527172 82.48789)
		(end 114.32211 82.48789)
		(width 0.16)
		(layer "In5.Cu")
		(net 370)
	)
	(segment
		(start 131.299 94.611718)
		(end 128.351718 97.559)
		(width 0.16)
		(layer "In5.Cu")
		(net 370)
	)
	(segment
		(start 128.351718 97.559)
		(end 121.298282 97.559)
		(width 0.16)
		(layer "In5.Cu")
		(net 370)
	)
	(segment
		(start 121.298282 97.559)
		(end 118.676 94.936718)
		(width 0.16)
		(layer "In5.Cu")
		(net 370)
	)
	(segment
		(start 133.599 85.588282)
		(end 133.599 87.911718)
		(width 0.16)
		(layer "In5.Cu")
		(net 370)
	)
	(segment
		(start 131.299 89.111718)
		(end 131.299 94.611718)
		(width 0.16)
		(layer "In5.Cu")
		(net 370)
	)
	(segment
		(start 115.501 86.011718)
		(end 115.501 83.461718)
		(width 0.16)
		(layer "In5.Cu")
		(net 370)
	)
	(segment
		(start 133.35789 85.347172)
		(end 133.599 85.588282)
		(width 0.16)
		(layer "In5.Cu")
		(net 370)
	)
	(segment
		(start 118.676 89.186718)
		(end 115.501 86.011718)
		(width 0.16)
		(layer "In5.Cu")
		(net 370)
	)
	(segment
		(start 118.676 94.936718)
		(end 118.676 89.186718)
		(width 0.16)
		(layer "In5.Cu")
		(net 370)
	)
	(segment
		(start 132.011718 88.399)
		(end 131.299 89.111718)
		(width 0.16)
		(layer "In5.Cu")
		(net 370)
	)
	(segment
		(start 143.15 99)
		(end 139.8425 99)
		(width 0.15)
		(layer "B.Cu")
		(net 371)
	)
	(segment
		(start 139.8425 99)
		(end 139.75 99.0925)
		(width 0.15)
		(layer "B.Cu")
		(net 371)
	)
	(segment
		(start 108.972323 75.624455)
		(end 107.665 76.931778)
		(width 0.125)
		(layer "F.Cu")
		(net 375)
	)
	(segment
		(start 109.097323 72.730136)
		(end 108.972323 72.855136)
		(width 0.125)
		(layer "F.Cu")
		(net 375)
	)
	(segment
		(start 109.097323 72.005136)
		(end 109.097323 72.730136)
		(width 0.125)
		(layer "F.Cu")
		(net 375)
	)
	(segment
		(start 107.665 78.4575)
		(end 107.8275 78.62)
		(width 0.125)
		(layer "F.Cu")
		(net 375)
	)
	(segment
		(start 107.665 76.931778)
		(end 107.665 78.4575)
		(width 0.125)
		(layer "F.Cu")
		(net 375)
	)
	(segment
		(start 108.972323 72.855136)
		(end 108.972323 75.624455)
		(width 0.125)
		(layer "F.Cu")
		(net 375)
	)
	(via
		(at 107.8275 78.62)
		(size 0.45)
		(drill 0.1)
		(layers "F.Cu" "B.Cu")
		(net 375)
	)
	(segment
		(start 106.810027 81.011728)
		(end 106.810027 81.011727)
		(width 0.125)
		(layer "B.Cu")
		(net 375)
	)
	(segment
		(start 105.59839 82.011229)
		(end 105.598388 82.01123)
		(width 0.125)
		(layer "B.Cu")
		(net 375)
	)
	(segment
		(start 104.679152 82.647629)
		(end 104.679151 82.64763)
		(width 0.125)
		(layer "B.Cu")
		(net 375)
	)
	(segment
		(start 105.92614 81.400634)
		(end 105.598388 81.728387)
		(width 0.125)
		(layer "B.Cu")
		(net 375)
	)
	(segment
		(start 107.393389 80.251587)
		(end 107.481778 80.339976)
		(width 0.125)
		(layer "B.Cu")
		(net 375)
	)
	(segment
		(start 105.837753 80.67585)
		(end 105.837752 80.67585)
		(width 0.125)
		(layer "B.Cu")
		(net 375)
	)
	(segment
		(start 107.8275 78.62)
		(end 107.665 78.7825)
		(width 0.125)
		(layer "B.Cu")
		(net 375)
	)
	(segment
		(start 99.206778 93.1)
		(end 98.285 93.1)
		(width 0.125)
		(layer "B.Cu")
		(net 375)
	)
	(segment
		(start 105.440005 83.12564)
		(end 105.440004 83.12564)
		(width 0.125)
		(layer "B.Cu")
		(net 375)
	)
	(segment
		(start 101.845 90.461778)
		(end 99.206778 93.1)
		(width 0.125)
		(layer "B.Cu")
		(net 375)
	)
	(segment
		(start 105.440004 83.12564)
		(end 104.961993 82.64763)
		(width 0.125)
		(layer "B.Cu")
		(net 375)
	)
	(segment
		(start 105.873109 80.357652)
		(end 105.873108 80.357652)
		(width 0.125)
		(layer "B.Cu")
		(net 375)
	)
	(segment
		(start 106.810027 81.011727)
		(end 106.155951 80.357652)
		(width 0.125)
		(layer "B.Cu")
		(net 375)
	)
	(segment
		(start 104.679151 82.64763)
		(end 104.363389 82.963389)
		(width 0.125)
		(layer "B.Cu")
		(net 375)
	)
	(segment
		(start 107.481778 81.011728)
		(end 107.481777 81.011728)
		(width 0.125)
		(layer "B.Cu")
		(net 375)
	)
	(segment
		(start 105.598388 81.728387)
		(end 105.598389 81.728388)
		(width 0.125)
		(layer "B.Cu")
		(net 375)
	)
	(segment
		(start 107.665 79.661778)
		(end 107.393389 79.933389)
		(width 0.125)
		(layer "B.Cu")
		(net 375)
	)
	(segment
		(start 104.363389 82.963389)
		(end 101.845 85.481778)
		(width 0.125)
		(layer "B.Cu")
		(net 375)
	)
	(segment
		(start 101.845 85.481778)
		(end 101.845 90.461778)
		(width 0.125)
		(layer "B.Cu")
		(net 375)
	)
	(segment
		(start 105.873108 80.357652)
		(end 105.837752 80.393007)
		(width 0.125)
		(layer "B.Cu")
		(net 375)
	)
	(segment
		(start 105.598388 82.01123)
		(end 106.0764 82.489241)
		(width 0.125)
		(layer "B.Cu")
		(net 375)
	)
	(segment
		(start 105.837752 80.67585)
		(end 105.92614 80.764238)
		(width 0.125)
		(layer "B.Cu")
		(net 375)
	)
	(segment
		(start 98.285 93.1)
		(end 97.935 93.45)
		(width 0.125)
		(layer "B.Cu")
		(net 375)
	)
	(segment
		(start 107.665 78.7825)
		(end 107.665 79.661778)
		(width 0.125)
		(layer "B.Cu")
		(net 375)
	)
	(arc
		(start 107.393389 79.933389)
		(mid 107.327488 80.092488)
		(end 107.393389 80.251587)
		(width 0.125)
		(layer "B.Cu")
		(net 375)
	)
	(arc
		(start 107.481777 81.011728)
		(mid 107.145903 81.150851)
		(end 106.810027 81.011728)
		(width 0.125)
		(layer "B.Cu")
		(net 375)
	)
	(arc
		(start 106.0764 82.489241)
		(mid 106.208203 82.807439)
		(end 106.076402 83.125639)
		(width 0.125)
		(layer "B.Cu")
		(net 375)
	)
	(arc
		(start 107.481778 80.339976)
		(mid 107.620902 80.675852)
		(end 107.481778 81.011728)
		(width 0.125)
		(layer "B.Cu")
		(net 375)
	)
	(arc
		(start 104.961993 82.64763)
		(mid 104.820574 82.589052)
		(end 104.679152 82.647629)
		(width 0.125)
		(layer "B.Cu")
		(net 375)
	)
	(arc
		(start 105.837752 80.393007)
		(mid 105.779174 80.534429)
		(end 105.837753 80.67585)
		(width 0.125)
		(layer "B.Cu")
		(net 375)
	)
	(arc
		(start 105.598389 81.728388)
		(mid 105.53981 81.86981)
		(end 105.59839 82.011229)
		(width 0.125)
		(layer "B.Cu")
		(net 375)
	)
	(arc
		(start 105.92614 80.764238)
		(mid 106.057942 81.082436)
		(end 105.92614 81.400634)
		(width 0.125)
		(layer "B.Cu")
		(net 375)
	)
	(arc
		(start 106.076402 83.125639)
		(mid 105.758202 83.257442)
		(end 105.440005 83.12564)
		(width 0.125)
		(layer "B.Cu")
		(net 375)
	)
	(arc
		(start 106.155951 80.357652)
		(mid 106.01453 80.299074)
		(end 105.873109 80.357652)
		(width 0.125)
		(layer "B.Cu")
		(net 375)
	)
	(segment
		(start 116.05 116.563749)
		(end 116.05 115.793749)
		(width 0.155)
		(layer "F.Cu")
		(net 390)
	)
	(segment
		(start 115.9495 117.221926)
		(end 115.9495 116.9105)
		(width 0.155)
		(layer "F.Cu")
		(net 390)
	)
	(segment
		(start 115.9495 116.9105)
		(end 116.05 116.81)
		(width 0.155)
		(layer "F.Cu")
		(net 390)
	)
	(segment
		(start 115.9495 115.2)
		(end 115.9495 110.788074)
		(width 0.155)
		(layer "F.Cu")
		(net 390)
	)
	(segment
		(start 115.9495 110.788074)
		(end 112.356926 107.1955)
		(width 0.155)
		(layer "F.Cu")
		(net 390)
	)
	(segment
		(start 110.515439 107.1955)
		(end 110.464939 107.145)
		(width 0.155)
		(layer "F.Cu")
		(net 390)
	)
	(segment
		(start 112.356926 107.1955)
		(end 110.515439 107.1955)
		(width 0.155)
		(layer "F.Cu")
		(net 390)
	)
	(segment
		(start 115.549505 117.621921)
		(end 115.9495 117.221926)
		(width 0.155)
		(layer "F.Cu")
		(net 390)
	)
	(segment
		(start 116.05 115.3005)
		(end 115.9495 115.2)
		(width 0.155)
		(layer "F.Cu")
		(net 390)
	)
	(segment
		(start 116.05 115.502499)
		(end 116.05 115.3005)
		(width 0.155)
		(layer "F.Cu")
		(net 390)
	)
	(segment
		(start 116.05 115.502499)
		(end 116.05 115.915)
		(width 0.165)
		(layer "F.Cu")
		(net 390)
	)
	(segment
		(start 115.549505 117.649505)
		(end 115.549505 117.621921)
		(width 0.155)
		(layer "F.Cu")
		(net 390)
	)
	(segment
		(start 116.05 116.81)
		(end 116.05 116.685)
		(width 0.155)
		(layer "F.Cu")
		(net 390)
	)
	(segment
		(start 115.65 117.75)
		(end 115.549505 117.649505)
		(width 0.155)
		(layer "F.Cu")
		(net 390)
	)
	(segment
		(start 110.464939 107.145)
		(end 110.089938 107.145)
		(width 0.155)
		(layer "F.Cu")
		(net 390)
	)
	(segment
		(start 111.4992 104.1508)
		(end 111.9 104.1508)
		(width 0.15)
		(layer "F.Cu")
		(net 391)
	)
	(segment
		(start 110.089938 105.145)
		(end 110.505 105.145)
		(width 0.15)
		(layer "F.Cu")
		(net 391)
	)
	(segment
		(start 110.505 105.145)
		(end 111.4992 104.1508)
		(width 0.15)
		(layer "F.Cu")
		(net 391)
	)
	(via
		(at 111.9 104.1508)
		(size 0.45)
		(drill 0.1)
		(layers "F.Cu" "B.Cu")
		(net 391)
	)
	(segment
		(start 111.9 103.115)
		(end 111.915 103.1)
		(width 0.15)
		(layer "B.Cu")
		(net 391)
	)
	(segment
		(start 111.9 104.1508)
		(end 111.9 103.115)
		(width 0.15)
		(layer "B.Cu")
		(net 391)
	)
	(via
		(at 92.5 108.85)
		(size 0.45)
		(drill 0.1)
		(layers "F.Cu" "B.Cu")
		(net 393)
	)
	(via
		(at 96.8255 105.442844)
		(size 0.45)
		(drill 0.1)
		(layers "F.Cu" "B.Cu")
		(net 393)
	)
	(via
		(at 95.153578 84.024967)
		(size 0.45)
		(drill 0.1)
		(layers "F.Cu" "B.Cu")
		(net 393)
	)
	(segment
		(start 96.8255 105.442844)
		(end 96.8255 106.0745)
		(width 0.125)
		(layer "In3.Cu")
		(net 393)
	)
	(segment
		(start 96.8255 106.0745)
		(end 94.05 108.85)
		(width 0.125)
		(layer "In3.Cu")
		(net 393)
	)
	(segment
		(start 94.05 108.85)
		(end 92.5 108.85)
		(width 0.125)
		(layer "In3.Cu")
		(net 393)
	)
	(segment
		(start 94.3 85.2)
		(end 94.3 88.250497)
		(width 0.125)
		(layer "In5.Cu")
		(net 393)
	)
	(segment
		(start 94.15 97.375)
		(end 94.15 102.75)
		(width 0.125)
		(layer "In5.Cu")
		(net 393)
	)
	(segment
		(start 95.153578 84.024967)
		(end 95.153578 84.346422)
		(width 0.125)
		(layer "In5.Cu")
		(net 393)
	)
	(segment
		(start 94.55 88.500497)
		(end 94.55 96.975)
		(width 0.125)
		(layer "In5.Cu")
		(net 393)
	)
	(segment
		(start 94.55 96.975)
		(end 94.15 97.375)
		(width 0.125)
		(layer "In5.Cu")
		(net 393)
	)
	(segment
		(start 94.15 102.75)
		(end 96.8255 105.4255)
		(width 0.125)
		(layer "In5.Cu")
		(net 393)
	)
	(segment
		(start 94.3 88.250497)
		(end 94.55 88.500497)
		(width 0.125)
		(layer "In5.Cu")
		(net 393)
	)
	(segment
		(start 95.153578 84.346422)
		(end 94.3 85.2)
		(width 0.125)
		(layer "In5.Cu")
		(net 393)
	)
	(segment
		(start 96.8255 105.4255)
		(end 96.8255 105.442844)
		(width 0.125)
		(layer "In5.Cu")
		(net 393)
	)
	(segment
		(start 95.153578 84.024967)
		(end 95.35 83.828545)
		(width 0.125)
		(layer "B.Cu")
		(net 393)
	)
	(segment
		(start 92.55 113.8)
		(end 92.8 113.55)
		(width 0.125)
		(layer "B.Cu")
		(net 393)
	)
	(segment
		(start 94.75 81.15)
		(end 94.75 80.4)
		(width 0.125)
		(layer "B.Cu")
		(net 393)
	)
	(segment
		(start 98.45 81.1)
		(end 98.25 81.3)
		(width 0.125)
		(layer "B.Cu")
		(net 393)
	)
	(segment
		(start 92.8 109.15)
		(end 92.5 108.85)
		(width 0.125)
		(layer "B.Cu")
		(net 393)
	)
	(segment
		(start 92.15 113.8)
		(end 92.55 113.8)
		(width 0.125)
		(layer "B.Cu")
		(net 393)
	)
	(segment
		(start 95.6 81.3)
		(end 95.45 81.3)
		(width 0.125)
		(layer "B.Cu")
		(net 393)
	)
	(segment
		(start 98.25 81.3)
		(end 95.6 81.3)
		(width 0.125)
		(layer "B.Cu")
		(net 393)
	)
	(segment
		(start 91.8 112.55)
		(end 91.8245 112.5745)
		(width 0.125)
		(layer "B.Cu")
		(net 393)
	)
	(segment
		(start 95.45 81.3)
		(end 95.35 81.4)
		(width 0.125)
		(layer "B.Cu")
		(net 393)
	)
	(segment
		(start 91.8245 112.5745)
		(end 91.8245 113.4745)
		(width 0.125)
		(layer "B.Cu")
		(net 393)
	)
	(segment
		(start 91.8245 113.4745)
		(end 92.15 113.8)
		(width 0.125)
		(layer "B.Cu")
		(net 393)
	)
	(segment
		(start 95.25 81.3)
		(end 95.35 81.4)
		(width 0.125)
		(layer "B.Cu")
		(net 393)
	)
	(segment
		(start 98.45 80.4)
		(end 98.45 81.1)
		(width 0.125)
		(layer "B.Cu")
		(net 393)
	)
	(segment
		(start 95.35 83.828545)
		(end 95.35 81.4)
		(width 0.125)
		(layer "B.Cu")
		(net 393)
	)
	(segment
		(start 95.6 81.3)
		(end 95.25 81.3)
		(width 0.125)
		(layer "B.Cu")
		(net 393)
	)
	(segment
		(start 92.8 113.55)
		(end 92.8 109.15)
		(width 0.125)
		(layer "B.Cu")
		(net 393)
	)
	(segment
		(start 95.25 81.3)
		(end 94.9 81.3)
		(width 0.125)
		(layer "B.Cu")
		(net 393)
	)
	(segment
		(start 94.9 81.3)
		(end 94.75 81.15)
		(width 0.125)
		(layer "B.Cu")
		(net 393)
	)
	(segment
		(start 65.5 97.3)
		(end 65.5 99.04)
		(width 0.125)
		(layer "B.Cu")
		(net 394)
	)
	(segment
		(start 65.75 97.05)
		(end 65.5 97.3)
		(width 0.125)
		(layer "B.Cu")
		(net 394)
	)
	(segment
		(start 70 96.4508)
		(end 69.4008 97.05)
		(width 0.125)
		(layer "B.Cu")
		(net 394)
	)
	(segment
		(start 65.7 99.24)
		(end 65.7 99.75)
		(width 0.125)
		(layer "B.Cu")
		(net 394)
	)
	(segment
		(start 65.5 99.04)
		(end 65.7 99.24)
		(width 0.125)
		(layer "B.Cu")
		(net 394)
	)
	(segment
		(start 69.4008 97.05)
		(end 65.75 97.05)
		(width 0.125)
		(layer "B.Cu")
		(net 394)
	)
	(segment
		(start 67.45 96.45)
		(end 68 95.9)
		(width 0.125)
		(layer "B.Cu")
		(net 395)
	)
	(segment
		(start 68.6 95.3)
		(end 68.6 94.885)
		(width 0.125)
		(layer "B.Cu")
		(net 395)
	)
	(segment
		(start 64.9 99.75)
		(end 64.9 97)
		(width 0.125)
		(layer "B.Cu")
		(net 395)
	)
	(segment
		(start 64.9 97)
		(end 65.45 96.45)
		(width 0.125)
		(layer "B.Cu")
		(net 395)
	)
	(segment
		(start 65.45 96.45)
		(end 67.45 96.45)
		(width 0.125)
		(layer "B.Cu")
		(net 395)
	)
	(segment
		(start 68 95.9)
		(end 68.6 95.3)
		(width 0.125)
		(layer "B.Cu")
		(net 395)
	)
	(segment
		(start 65.575 96.75)
		(end 68.6008 96.75)
		(width 0.125)
		(layer "B.Cu")
		(net 396)
	)
	(segment
		(start 65.2 97.125)
		(end 65.575 96.75)
		(width 0.125)
		(layer "B.Cu")
		(net 396)
	)
	(segment
		(start 65.3 99.75)
		(end 65.3 99.28)
		(width 0.125)
		(layer "B.Cu")
		(net 396)
	)
	(segment
		(start 69 95.485)
		(end 69.6 94.885)
		(width 0.125)
		(layer "B.Cu")
		(net 396)
	)
	(segment
		(start 69 96.3508)
		(end 69 95.485)
		(width 0.125)
		(layer "B.Cu")
		(net 396)
	)
	(segment
		(start 65.3 99.28)
		(end 65.2 99.18)
		(width 0.125)
		(layer "B.Cu")
		(net 396)
	)
	(segment
		(start 65.2 99.18)
		(end 65.2 97.125)
		(width 0.125)
		(layer "B.Cu")
		(net 396)
	)
	(segment
		(start 68.6008 96.75)
		(end 69 96.3508)
		(width 0.125)
		(layer "B.Cu")
		(net 396)
	)
	(segment
		(start 48.35 115.39)
		(end 48.35 112.8)
		(width 0.15)
		(layer "F.Cu")
		(net 397)
	)
	(segment
		(start 46.76 116.6)
		(end 47.14 116.6)
		(width 0.15)
		(layer "F.Cu")
		(net 397)
	)
	(segment
		(start 47.16 116.6)
		(end 46.76 116.6)
		(width 0.15)
		(layer "F.Cu")
		(net 397)
	)
	(segment
		(start 48.925999 112.224001)
		(end 50.035295 112.224001)
		(width 0.15)
		(layer "F.Cu")
		(net 397)
	)
	(segment
		(start 47.14 116.6)
		(end 48.35 115.39)
		(width 0.15)
		(layer "F.Cu")
		(net 397)
	)
	(segment
		(start 47.85 118.56)
		(end 47.85 117.29)
		(width 0.15)
		(layer "F.Cu")
		(net 397)
	)
	(segment
		(start 47.85 117.29)
		(end 47.16 116.6)
		(width 0.15)
		(layer "F.Cu")
		(net 397)
	)
	(segment
		(start 50.035295 112.224001)
		(end 50.092165 112.280871)
		(width 0.15)
		(layer "F.Cu")
		(net 397)
	)
	(segment
		(start 48.35 112.8)
		(end 48.925999 112.224001)
		(width 0.15)
		(layer "F.Cu")
		(net 397)
	)
	(via
		(at 47.85 118.56)
		(size 0.45)
		(drill 0.1)
		(layers "F.Cu" "B.Cu")
		(net 397)
	)
	(via
		(at 46.76 116.6)
		(size 0.45)
		(drill 0.1)
		(layers "F.Cu" "B.Cu")
		(net 397)
	)
	(via
		(at 50.092165 112.280871)
		(size 0.45)
		(drill 0.1)
		(layers "F.Cu" "B.Cu")
		(net 397)
	)
	(segment
		(start 48.03 120.48)
		(end 47.44 119.89)
		(width 0.15)
		(layer "B.Cu")
		(net 397)
	)
	(segment
		(start 47.44 119.48)
		(end 47.848 119.072)
		(width 0.15)
		(layer "B.Cu")
		(net 397)
	)
	(segment
		(start 50.03 112.218706)
		(end 50.092165 112.280871)
		(width 0.15)
		(layer "B.Cu")
		(net 397)
	)
	(segment
		(start 50.03 111.7745)
		(end 50.03 112.218706)
		(width 0.15)
		(layer "B.Cu")
		(net 397)
	)
	(segment
		(start 47.848 119.072)
		(end 47.848 119.05)
		(width 0.15)
		(layer "B.Cu")
		(net 397)
	)
	(segment
		(start 47.825 117.402)
		(end 47.562 117.402)
		(width 0.15)
		(layer "B.Cu")
		(net 397)
	)
	(segment
		(start 48.03 120.65)
		(end 48.03 120.48)
		(width 0.15)
		(layer "B.Cu")
		(net 397)
	)
	(segment
		(start 47.44 119.89)
		(end 47.44 119.48)
		(width 0.15)
		(layer "B.Cu")
		(net 397)
	)
	(segment
		(start 47.848 119.05)
		(end 47.848 118.562)
		(width 0.15)
		(layer "B.Cu")
		(net 397)
	)
	(segment
		(start 47.562 117.402)
		(end 46.76 116.6)
		(width 0.15)
		(layer "B.Cu")
		(net 397)
	)
	(segment
		(start 47.848 118.562)
		(end 47.85 118.56)
		(width 0.15)
		(layer "B.Cu")
		(net 397)
	)
	(segment
		(start 53.03 110.65)
		(end 53.03 110.8)
		(width 0.15)
		(layer "B.Cu")
		(net 398)
	)
	(segment
		(start 52.85 110.75)
		(end 51.951462 110.75)
		(width 0.15)
		(layer "B.Cu")
		(net 398)
	)
	(segment
		(start 52.85 110.75)
		(end 52.93 110.75)
		(width 0.15)
		(layer "B.Cu")
		(net 398)
	)
	(segment
		(start 53.03 110.8)
		(end 53.03 110.85)
		(width 0.15)
		(layer "B.Cu")
		(net 398)
	)
	(segment
		(start 50.614883 110.959383)
		(end 50.53 110.8745)
		(width 0.15)
		(layer "B.Cu")
		(net 398)
	)
	(segment
		(start 52.98 110.75)
		(end 52.85 110.75)
		(width 0.15)
		(layer "B.Cu")
		(net 398)
	)
	(segment
		(start 53.03 110.85)
		(end 53.03 111.305)
		(width 0.15)
		(layer "B.Cu")
		(net 398)
	)
	(segment
		(start 53.03 110.8)
		(end 52.98 110.75)
		(width 0.15)
		(layer "B.Cu")
		(net 398)
	)
	(segment
		(start 52.93 110.75)
		(end 53.03 110.85)
		(width 0.15)
		(layer "B.Cu")
		(net 398)
	)
	(segment
		(start 51.742079 110.959383)
		(end 50.614883 110.959383)
		(width 0.15)
		(layer "B.Cu")
		(net 398)
	)
	(segment
		(start 53.03 111.305)
		(end 53.075 111.35)
		(width 0.15)
		(layer "B.Cu")
		(net 398)
	)
	(segment
		(start 52.93 110.75)
		(end 53.03 110.65)
		(width 0.15)
		(layer "B.Cu")
		(net 398)
	)
	(segment
		(start 51.951462 110.75)
		(end 51.742079 110.959383)
		(width 0.15)
		(layer "B.Cu")
		(net 398)
	)
	(segment
		(start 53.03 110.25)
		(end 53.03 110.65)
		(width 0.15)
		(layer "B.Cu")
		(net 398)
	)
	(segment
		(start 93.005 75.595)
		(end 91.9 76.7)
		(width 0.15)
		(layer "B.Cu")
		(net 402)
	)
	(segment
		(start 93.005 73.55)
		(end 93.005 75.595)
		(width 0.15)
		(layer "B.Cu")
		(net 402)
	)
	(segment
		(start 78.2 88.35)
		(end 69 88.35)
		(width 0.15)
		(layer "B.Cu")
		(net 402)
	)
	(segment
		(start 82.65 83.9)
		(end 78.2 88.35)
		(width 0.15)
		(layer "B.Cu")
		(net 402)
	)
	(segment
		(start 67.95 87.3)
		(end 67.95 86.69)
		(width 0.15)
		(layer "B.Cu")
		(net 402)
	)
	(segment
		(start 90.888909 79.6)
		(end 88.9 79.6)
		(width 0.15)
		(layer "B.Cu")
		(net 402)
	)
	(segment
		(start 69 88.35)
		(end 67.95 87.3)
		(width 0.15)
		(layer "B.Cu")
		(net 402)
	)
	(segment
		(start 91.9 76.7)
		(end 91.9 78.588909)
		(width 0.15)
		(layer "B.Cu")
		(net 402)
	)
	(segment
		(start 67.95 86.69)
		(end 67.81 86.55)
		(width 0.15)
		(layer "B.Cu")
		(net 402)
	)
	(segment
		(start 91.9 78.588909)
		(end 90.888909 79.6)
		(width 0.15)
		(layer "B.Cu")
		(net 402)
	)
	(segment
		(start 88.9 79.6)
		(end 84.6 83.9)
		(width 0.15)
		(layer "B.Cu")
		(net 402)
	)
	(segment
		(start 84.6 83.9)
		(end 82.65 83.9)
		(width 0.15)
		(layer "B.Cu")
		(net 402)
	)
	(segment
		(start 66.1 106.45)
		(end 66.1 105.95)
		(width 0.13)
		(layer "B.Cu")
		(net 403)
	)
	(segment
		(start 66.1 105.95)
		(end 66 105.85)
		(width 0.13)
		(layer "B.Cu")
		(net 403)
	)
	(segment
		(start 63.6 104.15)
		(end 63.55 104.1)
		(width 0.13)
		(layer "B.Cu")
		(net 403)
	)
	(segment
		(start 63.55 104.1)
		(end 62.95 104.1)
		(width 0.13)
		(layer "B.Cu")
		(net 403)
	)
	(segment
		(start 62.95 105.7)
		(end 63.55 105.7)
		(width 0.13)
		(layer "B.Cu")
		(net 403)
	)
	(segment
		(start 66.5 105.9)
		(end 66.55 105.85)
		(width 0.13)
		(layer "B.Cu")
		(net 404)
	)
	(segment
		(start 69.6 104.1)
		(end 69.05 104.1)
		(width 0.13)
		(layer "B.Cu")
		(net 404)
	)
	(segment
		(start 66.5 106.45)
		(end 66.5 105.9)
		(width 0.13)
		(layer "B.Cu")
		(net 404)
	)
	(segment
		(start 69.05 104.1)
		(end 69 104.15)
		(width 0.13)
		(layer "B.Cu")
		(net 404)
	)
	(segment
		(start 69.65 105.7)
		(end 69.05 105.7)
		(width 0.13)
		(layer "B.Cu")
		(net 404)
	)
	(segment
		(start 90.8 79.3)
		(end 88.75 79.3)
		(width 0.15)
		(layer "B.Cu")
		(net 406)
	)
	(segment
		(start 92.3 74.8)
		(end 92.3 75.8)
		(width 0.15)
		(layer "B.Cu")
		(net 406)
	)
	(segment
		(start 92.005 74.505)
		(end 92.3 74.8)
		(width 0.15)
		(layer "B.Cu")
		(net 406)
	)
	(segment
		(start 82.5 83.6)
		(end 78.09 88.01)
		(width 0.15)
		(layer "B.Cu")
		(net 406)
	)
	(segment
		(start 91.6 78.5)
		(end 90.8 79.3)
		(width 0.15)
		(layer "B.Cu")
		(net 406)
	)
	(segment
		(start 68.25 87.1)
		(end 68.25 86.695)
		(width 0.15)
		(layer "B.Cu")
		(net 406)
	)
	(segment
		(start 78.09 88.01)
		(end 69.16 88.01)
		(width 0.15)
		(layer "B.Cu")
		(net 406)
	)
	(segment
		(start 92.3 75.8)
		(end 91.6 76.5)
		(width 0.15)
		(layer "B.Cu")
		(net 406)
	)
	(segment
		(start 91.6 76.5)
		(end 91.6 78.5)
		(width 0.15)
		(layer "B.Cu")
		(net 406)
	)
	(segment
		(start 84.45 83.6)
		(end 82.5 83.6)
		(width 0.15)
		(layer "B.Cu")
		(net 406)
	)
	(segment
		(start 69.16 88.01)
		(end 68.25 87.1)
		(width 0.15)
		(layer "B.Cu")
		(net 406)
	)
	(segment
		(start 68.25 86.695)
		(end 68.395 86.55)
		(width 0.15)
		(layer "B.Cu")
		(net 406)
	)
	(segment
		(start 88.75 79.3)
		(end 84.45 83.6)
		(width 0.15)
		(layer "B.Cu")
		(net 406)
	)
	(segment
		(start 92.005 73.55)
		(end 92.005 74.505)
		(width 0.15)
		(layer "B.Cu")
		(net 406)
	)
	(segment
		(start 137.8 86.45)
		(end 137.035 86.45)
		(width 0.155)
		(layer "F.Cu")
		(net 411)
	)
	(segment
		(start 138.387633 86.6005)
		(end 140.887368 86.6005)
		(width 0.155)
		(layer "F.Cu")
		(net 411)
	)
	(segment
		(start 138.262869 86.537868)
		(end 138.281567 86.556566)
		(width 0.155)
		(layer "F.Cu")
		(net 411)
	)
	(segment
		(start 137.8 86.45)
		(end 138.050737 86.45)
		(width 0.155)
		(layer "F.Cu")
		(net 411)
	)
	(segment
		(start 140.993434 86.556566)
		(end 141.2 86.35)
		(width 0.155)
		(layer "F.Cu")
		(net 411)
	)
	(arc
		(start 138.387633 86.6005)
		(mid 138.33023 86.589082)
		(end 138.281567 86.556566)
		(width 0.155)
		(layer "F.Cu")
		(net 411)
	)
	(arc
		(start 138.262869 86.537868)
		(mid 138.165542 86.472836)
		(end 138.050737 86.45)
		(width 0.155)
		(layer "F.Cu")
		(net 411)
	)
	(arc
		(start 140.887368 86.6005)
		(mid 140.944771 86.589082)
		(end 140.993434 86.556566)
		(width 0.155)
		(layer "F.Cu")
		(net 411)
	)
	(segment
		(start 138.387633 86.8995)
		(end 140.887368 86.8995)
		(width 0.155)
		(layer "F.Cu")
		(net 412)
	)
	(segment
		(start 140.993434 86.943434)
		(end 141.2 87.15)
		(width 0.155)
		(layer "F.Cu")
		(net 412)
	)
	(segment
		(start 137.8 87.05)
		(end 137.035 87.05)
		(width 0.155)
		(layer "F.Cu")
		(net 412)
	)
	(segment
		(start 138.262869 86.962132)
		(end 138.281567 86.943434)
		(width 0.155)
		(layer "F.Cu")
		(net 412)
	)
	(segment
		(start 137.8 87.05)
		(end 138.050737 87.05)
		(width 0.155)
		(layer "F.Cu")
		(net 412)
	)
	(arc
		(start 138.262869 86.962132)
		(mid 138.165542 87.027164)
		(end 138.050737 87.05)
		(width 0.155)
		(layer "F.Cu")
		(net 412)
	)
	(arc
		(start 140.887368 86.8995)
		(mid 140.944771 86.910918)
		(end 140.993434 86.943434)
		(width 0.155)
		(layer "F.Cu")
		(net 412)
	)
	(arc
		(start 138.387633 86.8995)
		(mid 138.33023 86.910918)
		(end 138.281567 86.943434)
		(width 0.155)
		(layer "F.Cu")
		(net 412)
	)
	(segment
		(start 140.887368 84.4995)
		(end 140.675181 84.4995)
		(width 0.155)
		(layer "F.Cu")
		(net 413)
	)
	(segment
		(start 140.321627 84.353053)
		(end 139.695586 83.727012)
		(width 0.155)
		(layer "F.Cu")
		(net 413)
	)
	(segment
		(start 137.8 83.8)
		(end 136.985 83.8)
		(width 0.155)
		(layer "F.Cu")
		(net 413)
	)
	(segment
		(start 138.050737 83.8)
		(end 137.8 83.8)
		(width 0.155)
		(layer "F.Cu")
		(net 413)
	)
	(segment
		(start 138.306567 83.668434)
		(end 138.262869 83.712132)
		(width 0.155)
		(layer "F.Cu")
		(net 413)
	)
	(segment
		(start 139.448099 83.6245)
		(end 138.412633 83.6245)
		(width 0.155)
		(layer "F.Cu")
		(net 413)
	)
	(segment
		(start 141.2 84.75)
		(end 140.993434 84.543434)
		(width 0.155)
		(layer "F.Cu")
		(net 413)
	)
	(arc
		(start 140.887368 84.4995)
		(mid 140.944771 84.510918)
		(end 140.993434 84.543434)
		(width 0.155)
		(layer "F.Cu")
		(net 413)
	)
	(arc
		(start 140.675181 84.4995)
		(mid 140.483839 84.46144)
		(end 140.321627 84.353053)
		(width 0.155)
		(layer "F.Cu")
		(net 413)
	)
	(arc
		(start 139.695586 83.727012)
		(mid 139.582038 83.651142)
		(end 139.448099 83.6245)
		(width 0.155)
		(layer "F.Cu")
		(net 413)
	)
	(arc
		(start 138.306567 83.668434)
		(mid 138.35523 83.635918)
		(end 138.412633 83.6245)
		(width 0.155)
		(layer "F.Cu")
		(net 413)
	)
	(arc
		(start 138.050737 83.8)
		(mid 138.165542 83.777164)
		(end 138.262869 83.712132)
		(width 0.155)
		(layer "F.Cu")
		(net 413)
	)
	(segment
		(start 138.0495 91.286926)
		(end 137.236926 92.0995)
		(width 0.155)
		(layer "F.Cu")
		(net 414)
	)
	(segment
		(start 138.0495 90.886926)
		(end 138.0495 91.286926)
		(width 0.155)
		(layer "F.Cu")
		(net 414)
	)
	(segment
		(start 140.9495 91.6995)
		(end 140.188074 91.6995)
		(width 0.155)
		(layer "F.Cu")
		(net 414)
	)
	(segment
		(start 139.088074 90.5995)
		(end 138.336926 90.5995)
		(width 0.155)
		(layer "F.Cu")
		(net 414)
	)
	(segment
		(start 135.244 92.25)
		(end 135.194 92.3)
		(width 0.155)
		(layer "F.Cu")
		(net 414)
	)
	(segment
		(start 138.336926 90.5995)
		(end 138.0495 90.886926)
		(width 0.155)
		(layer "F.Cu")
		(net 414)
	)
	(segment
		(start 140.188074 91.6995)
		(end 139.088074 90.5995)
		(width 0.155)
		(layer "F.Cu")
		(net 414)
	)
	(segment
		(start 136.765501 92.0995)
		(end 136.615001 92.25)
		(width 0.155)
		(layer "F.Cu")
		(net 414)
	)
	(segment
		(start 137.236926 92.0995)
		(end 136.765501 92.0995)
		(width 0.155)
		(layer "F.Cu")
		(net 414)
	)
	(segment
		(start 136.615001 92.25)
		(end 135.244 92.25)
		(width 0.155)
		(layer "F.Cu")
		(net 414)
	)
	(segment
		(start 141.2 91.95)
		(end 140.9495 91.6995)
		(width 0.155)
		(layer "F.Cu")
		(net 414)
	)
	(segment
		(start 137.8 83.15)
		(end 137.035 83.15)
		(width 0.155)
		(layer "F.Cu")
		(net 415)
	)
	(segment
		(start 138.050737 83.15)
		(end 137.8 83.15)
		(width 0.155)
		(layer "F.Cu")
		(net 415)
	)
	(segment
		(start 140.489413 84.097987)
		(end 139.863372 83.471946)
		(width 0.155)
		(layer "F.Cu")
		(net 415)
	)
	(segment
		(start 141.2 83.95)
		(end 140.993434 84.156566)
		(width 0.155)
		(layer "F.Cu")
		(net 415)
	)
	(segment
		(start 139.509819 83.3255)
		(end 138.412633 83.3255)
		(width 0.155)
		(layer "F.Cu")
		(net 415)
	)
	(segment
		(start 138.306567 83.281566)
		(end 138.262869 83.237868)
		(width 0.155)
		(layer "F.Cu")
		(net 415)
	)
	(segment
		(start 140.887368 84.2005)
		(end 140.736901 84.2005)
		(width 0.155)
		(layer "F.Cu")
		(net 415)
	)
	(arc
		(start 140.489413 84.097987)
		(mid 140.602961 84.173858)
		(end 140.736901 84.2005)
		(width 0.155)
		(layer "F.Cu")
		(net 415)
	)
	(arc
		(start 139.863372 83.471946)
		(mid 139.70116 83.36356)
		(end 139.509819 83.3255)
		(width 0.155)
		(layer "F.Cu")
		(net 415)
	)
	(arc
		(start 140.993434 84.156566)
		(mid 140.944771 84.189082)
		(end 140.887368 84.2005)
		(width 0.155)
		(layer "F.Cu")
		(net 415)
	)
	(arc
		(start 138.050737 83.15)
		(mid 138.165542 83.172836)
		(end 138.262869 83.237868)
		(width 0.155)
		(layer "F.Cu")
		(net 415)
	)
	(arc
		(start 138.412633 83.3255)
		(mid 138.35523 83.314082)
		(end 138.306567 83.281566)
		(width 0.155)
		(layer "F.Cu")
		(net 415)
	)
	(segment
		(start 140.311926 91.4005)
		(end 139.211926 90.3005)
		(width 0.155)
		(layer "F.Cu")
		(net 416)
	)
	(segment
		(start 138.213074 90.3005)
		(end 137.7505 90.763074)
		(width 0.155)
		(layer "F.Cu")
		(net 416)
	)
	(segment
		(start 137.7505 90.763074)
		(end 137.7505 91.163074)
		(width 0.155)
		(layer "F.Cu")
		(net 416)
	)
	(segment
		(start 141.2 91.15)
		(end 140.9495 91.4005)
		(width 0.155)
		(layer "F.Cu")
		(net 416)
	)
	(segment
		(start 137.113074 91.8005)
		(end 136.765501 91.8005)
		(width 0.155)
		(layer "F.Cu")
		(net 416)
	)
	(segment
		(start 137.7505 91.163074)
		(end 137.113074 91.8005)
		(width 0.155)
		(layer "F.Cu")
		(net 416)
	)
	(segment
		(start 136.765501 91.8005)
		(end 136.615001 91.65)
		(width 0.155)
		(layer "F.Cu")
		(net 416)
	)
	(segment
		(start 139.211926 90.3005)
		(end 138.213074 90.3005)
		(width 0.155)
		(layer "F.Cu")
		(net 416)
	)
	(segment
		(start 140.9495 91.4005)
		(end 140.311926 91.4005)
		(width 0.155)
		(layer "F.Cu")
		(net 416)
	)
	(segment
		(start 136.615001 91.65)
		(end 135.534 91.65)
		(width 0.155)
		(layer "F.Cu")
		(net 416)
	)
	(segment
		(start 135.534 91.65)
		(end 135.194 91.31)
		(width 0.155)
		(layer "F.Cu")
		(net 416)
	)
	(segment
		(start 107.415 78.4575)
		(end 107.2525 78.62)
		(width 0.125)
		(layer "F.Cu")
		(net 417)
	)
	(segment
		(start 107.415 76.828222)
		(end 107.415 78.4575)
		(width 0.125)
		(layer "F.Cu")
		(net 417)
	)
	(segment
		(start 108.597323 72.730136)
		(end 108.722323 72.855136)
		(width 0.125)
		(layer "F.Cu")
		(net 417)
	)
	(segment
		(start 108.597323 72.005136)
		(end 108.597323 72.730136)
		(width 0.125)
		(layer "F.Cu")
		(net 417)
	)
	(segment
		(start 108.722323 72.855136)
		(end 108.722323 75.520899)
		(width 0.125)
		(layer "F.Cu")
		(net 417)
	)
	(segment
		(start 108.722323 75.520899)
		(end 107.415 76.828222)
		(width 0.125)
		(layer "F.Cu")
		(net 417)
	)
	(via
		(at 107.2525 78.62)
		(size 0.45)
		(drill 0.1)
		(layers "F.Cu" "B.Cu")
		(net 417)
	)
	(segment
		(start 105.42161 82.188008)
		(end 105.899622 82.666019)
		(width 0.125)
		(layer "B.Cu")
		(net 417)
	)
	(segment
		(start 105.696332 80.180875)
		(end 105.660976 80.21623)
		(width 0.125)
		(layer "B.Cu")
		(net 417)
	)
	(segment
		(start 107.216612 80.428364)
		(end 107.305001 80.516753)
		(width 0.125)
		(layer "B.Cu")
		(net 417)
	)
	(segment
		(start 100.835955 91.117264)
		(end 99.103222 92.85)
		(width 0.125)
		(layer "B.Cu")
		(net 417)
	)
	(segment
		(start 106.332728 80.180875)
		(end 106.986803 80.834951)
		(width 0.125)
		(layer "B.Cu")
		(net 417)
	)
	(segment
		(start 98.285 92.85)
		(end 97.935 92.5)
		(width 0.125)
		(layer "B.Cu")
		(net 417)
	)
	(segment
		(start 104.502375 82.470851)
		(end 104.502373 82.47085)
		(width 0.125)
		(layer "B.Cu")
		(net 417)
	)
	(segment
		(start 105.749364 81.223857)
		(end 105.42161 81.551611)
		(width 0.125)
		(layer "B.Cu")
		(net 417)
	)
	(segment
		(start 100.835954 91.117264)
		(end 100.835955 91.117264)
		(width 0.125)
		(layer "B.Cu")
		(net 417)
	)
	(segment
		(start 105.616783 82.948861)
		(end 105.616783 82.94886)
		(width 0.125)
		(layer "B.Cu")
		(net 417)
	)
	(segment
		(start 105.616783 82.94886)
		(end 105.138772 82.47085)
		(width 0.125)
		(layer "B.Cu")
		(net 417)
	)
	(segment
		(start 105.421611 82.188008)
		(end 105.42161 82.188008)
		(width 0.125)
		(layer "B.Cu")
		(net 417)
	)
	(segment
		(start 100.850987 90.566611)
		(end 100.835955 90.581642)
		(width 0.125)
		(layer "B.Cu")
		(net 417)
	)
	(segment
		(start 105.749363 81.223857)
		(end 105.749364 81.223857)
		(width 0.125)
		(layer "B.Cu")
		(net 417)
	)
	(segment
		(start 101.595 90.358222)
		(end 101.386611 90.566611)
		(width 0.125)
		(layer "B.Cu")
		(net 417)
	)
	(segment
		(start 107.415 78.7825)
		(end 107.415 79.558222)
		(width 0.125)
		(layer "B.Cu")
		(net 417)
	)
	(segment
		(start 101.595 85.378222)
		(end 101.595 90.358222)
		(width 0.125)
		(layer "B.Cu")
		(net 417)
	)
	(segment
		(start 100.835954 90.849453)
		(end 100.835955 90.849453)
		(width 0.125)
		(layer "B.Cu")
		(net 417)
	)
	(segment
		(start 107.2525 78.62)
		(end 107.415 78.7825)
		(width 0.125)
		(layer "B.Cu")
		(net 417)
	)
	(segment
		(start 99.103222 92.85)
		(end 98.285 92.85)
		(width 0.125)
		(layer "B.Cu")
		(net 417)
	)
	(segment
		(start 105.899625 82.94886)
		(end 105.899623 82.948861)
		(width 0.125)
		(layer "B.Cu")
		(net 417)
	)
	(segment
		(start 100.850988 90.56661)
		(end 100.850987 90.566611)
		(width 0.125)
		(layer "B.Cu")
		(net 417)
	)
	(segment
		(start 105.660976 80.852626)
		(end 105.749364 80.941014)
		(width 0.125)
		(layer "B.Cu")
		(net 417)
	)
	(segment
		(start 104.502373 82.47085)
		(end 101.595 85.378222)
		(width 0.125)
		(layer "B.Cu")
		(net 417)
	)
	(segment
		(start 107.415 79.558222)
		(end 107.216612 79.756612)
		(width 0.125)
		(layer "B.Cu")
		(net 417)
	)
	(arc
		(start 101.386611 90.566611)
		(mid 101.252705 90.622077)
		(end 101.118799 90.566611)
		(width 0.125)
		(layer "B.Cu")
		(net 417)
	)
	(arc
		(start 105.660976 80.21623)
		(mid 105.529174 80.534428)
		(end 105.660976 80.852626)
		(width 0.125)
		(layer "B.Cu")
		(net 417)
	)
	(arc
		(start 106.332728 80.180875)
		(mid 106.01453 80.049073)
		(end 105.696332 80.180875)
		(width 0.125)
		(layer "B.Cu")
		(net 417)
	)
	(arc
		(start 105.899623 82.948861)
		(mid 105.758203 83.007439)
		(end 105.616783 82.948861)
		(width 0.125)
		(layer "B.Cu")
		(net 417)
	)
	(arc
		(start 107.305001 80.516753)
		(mid 107.370902 80.675852)
		(end 107.305001 80.834951)
		(width 0.125)
		(layer "B.Cu")
		(net 417)
	)
	(arc
		(start 105.138772 82.47085)
		(mid 104.820573 82.339048)
		(end 104.502375 82.470851)
		(width 0.125)
		(layer "B.Cu")
		(net 417)
	)
	(arc
		(start 105.42161 81.551611)
		(mid 105.289808 81.869808)
		(end 105.421611 82.188008)
		(width 0.125)
		(layer "B.Cu")
		(net 417)
	)
	(arc
		(start 107.216612 79.756612)
		(mid 107.077488 80.092488)
		(end 107.216612 80.428364)
		(width 0.125)
		(layer "B.Cu")
		(net 417)
	)
	(arc
		(start 107.305001 80.834951)
		(mid 107.145902 80.900852)
		(end 106.986803 80.834951)
		(width 0.125)
		(layer "B.Cu")
		(net 417)
	)
	(arc
		(start 100.835955 90.849453)
		(mid 100.89142 90.983359)
		(end 100.835954 91.117264)
		(width 0.125)
		(layer "B.Cu")
		(net 417)
	)
	(arc
		(start 101.118799 90.566611)
		(mid 100.984894 90.511145)
		(end 100.850988 90.56661)
		(width 0.125)
		(layer "B.Cu")
		(net 417)
	)
	(arc
		(start 105.899622 82.666019)
		(mid 105.958202 82.80744)
		(end 105.899625 82.94886)
		(width 0.125)
		(layer "B.Cu")
		(net 417)
	)
	(arc
		(start 100.835955 90.581642)
		(mid 100.780489 90.715547)
		(end 100.835954 90.849453)
		(width 0.125)
		(layer "B.Cu")
		(net 417)
	)
	(arc
		(start 105.749364 80.941014)
		(mid 105.807942 81.082436)
		(end 105.749363 81.223857)
		(width 0.125)
		(layer "B.Cu")
		(net 417)
	)
	(segment
		(start 107.597323 72.730136)
		(end 107.472323 72.855136)
		(width 0.125)
		(layer "F.Cu")
		(net 418)
	)
	(segment
		(start 106.295 78.0775)
		(end 106.4575 78.24)
		(width 0.125)
		(layer "F.Cu")
		(net 418)
	)
	(segment
		(start 107.472323 72.855136)
		(end 107.472323 73.795545)
		(width 0.125)
		(layer "F.Cu")
		(net 418)
	)
	(segment
		(start 107.685 74.971778)
		(end 106.295 76.361778)
		(width 0.125)
		(layer "F.Cu")
		(net 418)
	)
	(segment
		(start 107.685 74.008222)
		(end 107.685 74.971778)
		(width 0.125)
		(layer "F.Cu")
		(net 418)
	)
	(segment
		(start 106.295 76.361778)
		(end 106.295 78.0775)
		(width 0.125)
		(layer "F.Cu")
		(net 418)
	)
	(segment
		(start 107.597323 72.005136)
		(end 107.597323 72.730136)
		(width 0.125)
		(layer "F.Cu")
		(net 418)
	)
	(segment
		(start 107.472323 73.795545)
		(end 107.685 74.008222)
		(width 0.125)
		(layer "F.Cu")
		(net 418)
	)
	(via
		(at 106.4575 78.24)
		(size 0.45)
		(drill 0.1)
		(layers "F.Cu" "B.Cu")
		(net 418)
	)
	(segment
		(start 103.506015 82.315024)
		(end 103.205493 82.014503)
		(width 0.125)
		(layer "B.Cu")
		(net 418)
	)
	(segment
		(start 99.730495 90.142729)
		(end 99.55372 89.965951)
		(width 0.125)
		(layer "B.Cu")
		(net 418)
	)
	(segment
		(start 104.195448 81.024553)
		(end 103.894926 80.724034)
		(width 0.125)
		(layer "B.Cu")
		(net 418)
	)
	(segment
		(start 106.295 79.101778)
		(end 106.295 78.4025)
		(width 0.125)
		(layer "B.Cu")
		(net 418)
	)
	(segment
		(start 102.025 84.151778)
		(end 102.025 83.371778)
		(width 0.125)
		(layer "B.Cu")
		(net 418)
	)
	(segment
		(start 103.894926 80.476546)
		(end 103.965638 80.405835)
		(width 0.125)
		(layer "B.Cu")
		(net 418)
	)
	(segment
		(start 100.172436 91.291775)
		(end 100.172436 91.291776)
		(width 0.125)
		(layer "B.Cu")
		(net 418)
	)
	(segment
		(start 96.385 91.575)
		(end 98.651778 91.575)
		(width 0.125)
		(layer "B.Cu")
		(net 418)
	)
	(segment
		(start 104.195444 81.024552)
		(end 104.195448 81.024553)
		(width 0.125)
		(layer "B.Cu")
		(net 418)
	)
	(segment
		(start 106.295 78.4025)
		(end 106.4575 78.24)
		(width 0.125)
		(layer "B.Cu")
		(net 418)
	)
	(segment
		(start 99.376942 91.203388)
		(end 99.376941 91.203388)
		(width 0.125)
		(layer "B.Cu")
		(net 418)
	)
	(segment
		(start 100.525992 89.700788)
		(end 100.935 89.291778)
		(width 0.125)
		(layer "B.Cu")
		(net 418)
	)
	(segment
		(start 99.907274 89.612397)
		(end 99.907273 89.612399)
		(width 0.125)
		(layer "B.Cu")
		(net 418)
	)
	(segment
		(start 100.935 85.241778)
		(end 102.025 84.151778)
		(width 0.125)
		(layer "B.Cu")
		(net 418)
	)
	(segment
		(start 96.035 91.925)
		(end 96.385 91.575)
		(width 0.125)
		(layer "B.Cu")
		(net 418)
	)
	(segment
		(start 100.172436 90.584669)
		(end 99.818885 90.231116)
		(width 0.125)
		(layer "B.Cu")
		(net 418)
	)
	(segment
		(start 98.651778 91.575)
		(end 99.023388 91.203388)
		(width 0.125)
		(layer "B.Cu")
		(net 418)
	)
	(segment
		(start 100.935 89.291778)
		(end 100.935 85.241778)
		(width 0.125)
		(layer "B.Cu")
		(net 418)
	)
	(segment
		(start 103.205497 82.014504)
		(end 102.904975 81.713985)
		(width 0.125)
		(layer "B.Cu")
		(net 418)
	)
	(segment
		(start 103.205493 82.014503)
		(end 103.205497 82.014504)
		(width 0.125)
		(layer "B.Cu")
		(net 418)
	)
	(segment
		(start 103.223175 81.395786)
		(end 103.824215 81.996825)
		(width 0.125)
		(layer "B.Cu")
		(net 418)
	)
	(segment
		(start 102.904975 81.466497)
		(end 102.975687 81.395786)
		(width 0.125)
		(layer "B.Cu")
		(net 418)
	)
	(segment
		(start 104.902556 80.494223)
		(end 106.295 79.101778)
		(width 0.125)
		(layer "B.Cu")
		(net 418)
	)
	(segment
		(start 102.745875 82.898388)
		(end 102.834263 82.986776)
		(width 0.125)
		(layer "B.Cu")
		(net 418)
	)
	(segment
		(start 103.435304 82.986776)
		(end 103.506014 82.916065)
		(width 0.125)
		(layer "B.Cu")
		(net 418)
	)
	(segment
		(start 99.553719 89.789175)
		(end 99.730497 89.612398)
		(width 0.125)
		(layer "B.Cu")
		(net 418)
	)
	(segment
		(start 102.745876 82.898388)
		(end 102.745875 82.898388)
		(width 0.125)
		(layer "B.Cu")
		(net 418)
	)
	(segment
		(start 100.172436 90.584668)
		(end 100.172436 90.584669)
		(width 0.125)
		(layer "B.Cu")
		(net 418)
	)
	(segment
		(start 99.376941 91.203388)
		(end 99.465329 91.291776)
		(width 0.125)
		(layer "B.Cu")
		(net 418)
	)
	(segment
		(start 104.213126 80.405835)
		(end 104.301515 80.494224)
		(width 0.125)
		(layer "B.Cu")
		(net 418)
	)
	(segment
		(start 103.435304 82.986775)
		(end 103.435304 82.986776)
		(width 0.125)
		(layer "B.Cu")
		(net 418)
	)
	(segment
		(start 102.025 83.371778)
		(end 102.498388 82.898388)
		(width 0.125)
		(layer "B.Cu")
		(net 418)
	)
	(segment
		(start 104.495966 81.325073)
		(end 104.195444 81.024552)
		(width 0.125)
		(layer "B.Cu")
		(net 418)
	)
	(segment
		(start 99.907273 89.612399)
		(end 99.995662 89.700788)
		(width 0.125)
		(layer "B.Cu")
		(net 418)
	)
	(segment
		(start 99.55372 89.789175)
		(end 99.553719 89.789175)
		(width 0.125)
		(layer "B.Cu")
		(net 418)
	)
	(segment
		(start 99.818885 90.231116)
		(end 99.730495 90.142729)
		(width 0.125)
		(layer "B.Cu")
		(net 418)
	)
	(segment
		(start 104.425255 81.996825)
		(end 104.495965 81.926114)
		(width 0.125)
		(layer "B.Cu")
		(net 418)
	)
	(arc
		(start 102.975687 81.395786)
		(mid 103.099431 81.34453)
		(end 103.223175 81.395786)
		(width 0.125)
		(layer "B.Cu")
		(net 418)
	)
	(arc
		(start 104.301515 80.494224)
		(mid 104.602036 80.618703)
		(end 104.902556 80.494223)
		(width 0.125)
		(layer "B.Cu")
		(net 418)
	)
	(arc
		(start 103.506014 82.916065)
		(mid 103.630494 82.615545)
		(end 103.506015 82.315024)
		(width 0.125)
		(layer "B.Cu")
		(net 418)
	)
	(arc
		(start 103.894926 80.724034)
		(mid 103.84367 80.60029)
		(end 103.894926 80.476546)
		(width 0.125)
		(layer "B.Cu")
		(net 418)
	)
	(arc
		(start 100.172436 91.291776)
		(mid 100.318883 90.938222)
		(end 100.172436 90.584668)
		(width 0.125)
		(layer "B.Cu")
		(net 418)
	)
	(arc
		(start 102.498388 82.898388)
		(mid 102.622132 82.847132)
		(end 102.745876 82.898388)
		(width 0.125)
		(layer "B.Cu")
		(net 418)
	)
	(arc
		(start 99.465329 91.291776)
		(mid 99.818883 91.438222)
		(end 100.172436 91.291775)
		(width 0.125)
		(layer "B.Cu")
		(net 418)
	)
	(arc
		(start 99.995662 89.700788)
		(mid 100.260827 89.810623)
		(end 100.525992 89.700788)
		(width 0.125)
		(layer "B.Cu")
		(net 418)
	)
	(arc
		(start 103.824215 81.996825)
		(mid 104.124735 82.121304)
		(end 104.425255 81.996825)
		(width 0.125)
		(layer "B.Cu")
		(net 418)
	)
	(arc
		(start 102.904975 81.713985)
		(mid 102.853719 81.590241)
		(end 102.904975 81.466497)
		(width 0.125)
		(layer "B.Cu")
		(net 418)
	)
	(arc
		(start 103.965638 80.405835)
		(mid 104.089382 80.354579)
		(end 104.213126 80.405835)
		(width 0.125)
		(layer "B.Cu")
		(net 418)
	)
	(arc
		(start 102.834263 82.986776)
		(mid 103.134784 83.111255)
		(end 103.435304 82.986775)
		(width 0.125)
		(layer "B.Cu")
		(net 418)
	)
	(arc
		(start 104.495965 81.926114)
		(mid 104.620445 81.625594)
		(end 104.495966 81.325073)
		(width 0.125)
		(layer "B.Cu")
		(net 418)
	)
	(arc
		(start 99.55372 89.965951)
		(mid 99.517108 89.877563)
		(end 99.55372 89.789175)
		(width 0.125)
		(layer "B.Cu")
		(net 418)
	)
	(arc
		(start 99.730497 89.612398)
		(mid 99.818885 89.575786)
		(end 99.907274 89.612397)
		(width 0.125)
		(layer "B.Cu")
		(net 418)
	)
	(arc
		(start 99.023388 91.203388)
		(mid 99.200165 91.130165)
		(end 99.376942 91.203388)
		(width 0.125)
		(layer "B.Cu")
		(net 418)
	)
	(segment
		(start 106.045 78.0775)
		(end 105.8825 78.24)
		(width 0.125)
		(layer "F.Cu")
		(net 419)
	)
	(segment
		(start 107.222323 72.855136)
		(end 107.222323 73.899101)
		(width 0.125)
		(layer "F.Cu")
		(net 419)
	)
	(segment
		(start 107.222323 73.899101)
		(end 107.435 74.111778)
		(width 0.125)
		(layer "F.Cu")
		(net 419)
	)
	(segment
		(start 107.435 74.111778)
		(end 107.435 74.868222)
		(width 0.125)
		(layer "F.Cu")
		(net 419)
	)
	(segment
		(start 107.435 74.868222)
		(end 106.045 76.258222)
		(width 0.125)
		(layer "F.Cu")
		(net 419)
	)
	(segment
		(start 106.045 76.258222)
		(end 106.045 78.0775)
		(width 0.125)
		(layer "F.Cu")
		(net 419)
	)
	(segment
		(start 107.097323 72.730136)
		(end 107.222323 72.855136)
		(width 0.125)
		(layer "F.Cu")
		(net 419)
	)
	(segment
		(start 107.097323 72.005136)
		(end 107.097323 72.730136)
		(width 0.125)
		(layer "F.Cu")
		(net 419)
	)
	(via
		(at 105.8825 78.24)
		(size 0.45)
		(drill 0.1)
		(layers "F.Cu" "B.Cu")
		(net 419)
	)
	(segment
		(start 100.084049 89.435623)
		(end 100.172438 89.524012)
		(width 0.125)
		(layer "B.Cu")
		(net 419)
	)
	(segment
		(start 103.399951 81.219011)
		(end 103.700472 81.519532)
		(width 0.125)
		(layer "B.Cu")
		(net 419)
	)
	(segment
		(start 99.553719 90.319505)
		(end 99.376941 90.14273)
		(width 0.125)
		(layer "B.Cu")
		(net 419)
	)
	(segment
		(start 102.728199 81.289721)
		(end 102.798911 81.21901)
		(width 0.125)
		(layer "B.Cu")
		(net 419)
	)
	(segment
		(start 102.922653 82.721611)
		(end 102.922652 82.721611)
		(width 0.125)
		(layer "B.Cu")
		(net 419)
	)
	(segment
		(start 103.258527 82.809999)
		(end 103.329237 82.739288)
		(width 0.125)
		(layer "B.Cu")
		(net 419)
	)
	(segment
		(start 101.775 84.048222)
		(end 101.775 83.268222)
		(width 0.125)
		(layer "B.Cu")
		(net 419)
	)
	(segment
		(start 103.399952 81.219009)
		(end 103.399951 81.219011)
		(width 0.125)
		(layer "B.Cu")
		(net 419)
	)
	(segment
		(start 103.028718 82.191283)
		(end 102.728199 81.890761)
		(width 0.125)
		(layer "B.Cu")
		(net 419)
	)
	(segment
		(start 99.642105 90.407891)
		(end 99.642106 90.407895)
		(width 0.125)
		(layer "B.Cu")
		(net 419)
	)
	(segment
		(start 106.045 78.998222)
		(end 106.045 78.4025)
		(width 0.125)
		(layer "B.Cu")
		(net 419)
	)
	(segment
		(start 103.258528 82.809999)
		(end 103.258527 82.809999)
		(width 0.125)
		(layer "B.Cu")
		(net 419)
	)
	(segment
		(start 104.389902 80.22906)
		(end 104.478291 80.317449)
		(width 0.125)
		(layer "B.Cu")
		(net 419)
	)
	(segment
		(start 99.99566 91.114999)
		(end 99.995659 91.114999)
		(width 0.125)
		(layer "B.Cu")
		(net 419)
	)
	(segment
		(start 99.642106 90.407895)
		(end 99.553719 90.319505)
		(width 0.125)
		(layer "B.Cu")
		(net 419)
	)
	(segment
		(start 99.376943 89.612398)
		(end 99.553719 89.435623)
		(width 0.125)
		(layer "B.Cu")
		(net 419)
	)
	(segment
		(start 99.995659 90.761445)
		(end 99.642105 90.407891)
		(width 0.125)
		(layer "B.Cu")
		(net 419)
	)
	(segment
		(start 96.035 90.975)
		(end 96.385 91.325)
		(width 0.125)
		(layer "B.Cu")
		(net 419)
	)
	(segment
		(start 100.685 85.45)
		(end 100.685 85.138222)
		(width 0.125)
		(layer "B.Cu")
		(net 419)
	)
	(segment
		(start 101.775 83.268222)
		(end 102.321611 82.721611)
		(width 0.125)
		(layer "B.Cu")
		(net 419)
	)
	(segment
		(start 103.700471 81.519528)
		(end 104.000991 81.820049)
		(width 0.125)
		(layer "B.Cu")
		(net 419)
	)
	(segment
		(start 103.329237 82.4918)
		(end 103.028718 82.191283)
		(width 0.125)
		(layer "B.Cu")
		(net 419)
	)
	(segment
		(start 102.922652 82.721611)
		(end 103.01104 82.809999)
		(width 0.125)
		(layer "B.Cu")
		(net 419)
	)
	(segment
		(start 99.553719 91.026611)
		(end 99.553718 91.026611)
		(width 0.125)
		(layer "B.Cu")
		(net 419)
	)
	(segment
		(start 100.685 89.188222)
		(end 100.685 86.355)
		(width 0.125)
		(layer "B.Cu")
		(net 419)
	)
	(segment
		(start 106.045 78.4025)
		(end 105.8825 78.24)
		(width 0.125)
		(layer "B.Cu")
		(net 419)
	)
	(segment
		(start 96.385 91.325)
		(end 98.548222 91.325)
		(width 0.125)
		(layer "B.Cu")
		(net 419)
	)
	(segment
		(start 104.248479 81.820049)
		(end 104.319189 81.749338)
		(width 0.125)
		(layer "B.Cu")
		(net 419)
	)
	(segment
		(start 100.685 85.605)
		(end 100.685 85.45)
		(width 0.125)
		(layer "B.Cu")
		(net 419)
	)
	(segment
		(start 104.725779 80.317449)
		(end 106.045 78.998222)
		(width 0.125)
		(layer "B.Cu")
		(net 419)
	)
	(segment
		(start 103.71815 80.29977)
		(end 103.788862 80.229059)
		(width 0.125)
		(layer "B.Cu")
		(net 419)
	)
	(segment
		(start 100.349215 89.524011)
		(end 100.685 89.188222)
		(width 0.125)
		(layer "B.Cu")
		(net 419)
	)
	(segment
		(start 98.548222 91.325)
		(end 98.846611 91.026611)
		(width 0.125)
		(layer "B.Cu")
		(net 419)
	)
	(segment
		(start 103.806537 80.9892)
		(end 103.71815 80.90081)
		(width 0.125)
		(layer "B.Cu")
		(net 419)
	)
	(segment
		(start 104.319189 81.50185)
		(end 103.806537 80.9892)
		(width 0.125)
		(layer "B.Cu")
		(net 419)
	)
	(segment
		(start 100.685 85.138222)
		(end 101.775 84.048222)
		(width 0.125)
		(layer "B.Cu")
		(net 419)
	)
	(segment
		(start 103.700472 81.519532)
		(end 103.700471 81.519528)
		(width 0.125)
		(layer "B.Cu")
		(net 419)
	)
	(segment
		(start 99.553718 91.026611)
		(end 99.642106 91.114999)
		(width 0.125)
		(layer "B.Cu")
		(net 419)
	)
	(segment
		(start 104.389903 80.229058)
		(end 104.389902 80.22906)
		(width 0.125)
		(layer "B.Cu")
		(net 419)
	)
	(segment
		(start 100.335 86.005)
		(end 100.335 85.955)
		(width 0.125)
		(layer "B.Cu")
		(net 419)
	)
	(arc
		(start 103.01104 82.809999)
		(mid 103.134784 82.861255)
		(end 103.258528 82.809999)
		(width 0.125)
		(layer "B.Cu")
		(net 419)
	)
	(arc
		(start 104.478291 80.317449)
		(mid 104.602035 80.368705)
		(end 104.725779 80.317449)
		(width 0.125)
		(layer "B.Cu")
		(net 419)
	)
	(arc
		(start 104.319189 81.749338)
		(mid 104.370445 81.625594)
		(end 104.319189 81.50185)
		(width 0.125)
		(layer "B.Cu")
		(net 419)
	)
	(arc
		(start 100.685 86.355)
		(mid 100.633744 86.231256)
		(end 100.51 86.18)
		(width 0.125)
		(layer "B.Cu")
		(net 419)
	)
	(arc
		(start 103.788862 80.229059)
		(mid 104.089382 80.104579)
		(end 104.389903 80.229058)
		(width 0.125)
		(layer "B.Cu")
		(net 419)
	)
	(arc
		(start 100.51 85.78)
		(mid 100.633744 85.728744)
		(end 100.685 85.605)
		(width 0.125)
		(layer "B.Cu")
		(net 419)
	)
	(arc
		(start 100.335 85.955)
		(mid 100.386256 85.831256)
		(end 100.51 85.78)
		(width 0.125)
		(layer "B.Cu")
		(net 419)
	)
	(arc
		(start 103.71815 80.90081)
		(mid 103.59367 80.600291)
		(end 103.71815 80.29977)
		(width 0.125)
		(layer "B.Cu")
		(net 419)
	)
	(arc
		(start 102.728199 81.890761)
		(mid 102.603719 81.590242)
		(end 102.728199 81.289721)
		(width 0.125)
		(layer "B.Cu")
		(net 419)
	)
	(arc
		(start 98.846611 91.026611)
		(mid 99.200165 90.880164)
		(end 99.553719 91.026611)
		(width 0.125)
		(layer "B.Cu")
		(net 419)
	)
	(arc
		(start 102.798911 81.21901)
		(mid 103.099431 81.09453)
		(end 103.399952 81.219009)
		(width 0.125)
		(layer "B.Cu")
		(net 419)
	)
	(arc
		(start 100.51 86.18)
		(mid 100.386256 86.128744)
		(end 100.335 86.005)
		(width 0.125)
		(layer "B.Cu")
		(net 419)
	)
	(arc
		(start 99.642106 91.114999)
		(mid 99.818883 91.188222)
		(end 99.99566 91.114999)
		(width 0.125)
		(layer "B.Cu")
		(net 419)
	)
	(arc
		(start 102.321611 82.721611)
		(mid 102.622132 82.597131)
		(end 102.922653 82.721611)
		(width 0.125)
		(layer "B.Cu")
		(net 419)
	)
	(arc
		(start 99.553719 89.435623)
		(mid 99.818884 89.325788)
		(end 100.084049 89.435623)
		(width 0.125)
		(layer "B.Cu")
		(net 419)
	)
	(arc
		(start 103.329237 82.739288)
		(mid 103.380493 82.615544)
		(end 103.329237 82.4918)
		(width 0.125)
		(layer "B.Cu")
		(net 419)
	)
	(arc
		(start 104.000991 81.820049)
		(mid 104.124735 81.871305)
		(end 104.248479 81.820049)
		(width 0.125)
		(layer "B.Cu")
		(net 419)
	)
	(arc
		(start 99.995659 91.114999)
		(mid 100.068882 90.938222)
		(end 99.995659 90.761445)
		(width 0.125)
		(layer "B.Cu")
		(net 419)
	)
	(arc
		(start 99.376941 90.14273)
		(mid 99.267106 89.877565)
		(end 99.376943 89.612398)
		(width 0.125)
		(layer "B.Cu")
		(net 419)
	)
	(arc
		(start 100.172438 89.524012)
		(mid 100.260827 89.560623)
		(end 100.349215 89.524011)
		(width 0.125)
		(layer "B.Cu")
		(net 419)
	)
	(segment
		(start 104.145 76.561778)
		(end 104.145 78.1275)
		(width 0.125)
		(layer "F.Cu")
		(net 420)
	)
	(segment
		(start 106.097323 72.005136)
		(end 106.097323 72.730136)
		(width 0.125)
		(layer "F.Cu")
		(net 420)
	)
	(segment
		(start 104.145 78.1275)
		(end 104.3075 78.29)
		(width 0.125)
		(layer "F.Cu")
		(net 420)
	)
	(segment
		(start 105.972323 74.734455)
		(end 104.145 76.561778)
		(width 0.125)
		(layer "F.Cu")
		(net 420)
	)
	(segment
		(start 106.097323 72.730136)
		(end 105.972323 72.855136)
		(width 0.125)
		(layer "F.Cu")
		(net 420)
	)
	(segment
		(start 105.972323 72.855136)
		(end 105.972323 74.734455)
		(width 0.125)
		(layer "F.Cu")
		(net 420)
	)
	(via
		(at 104.3075 78.29)
		(size 0.45)
		(drill 0.1)
		(layers "F.Cu" "B.Cu")
		(net 420)
	)
	(segment
		(start 101.932249 81.414531)
		(end 101.932248 81.41453)
		(width 0.125)
		(layer "B.Cu")
		(net 420)
	)
	(segment
		(start 101.932248 80.778134)
		(end 101.136753 79.982639)
		(width 0.125)
		(layer "B.Cu")
		(net 420)
	)
	(segment
		(start 101.242817 81.927181)
		(end 101.24282 81.927181)
		(width 0.125)
		(layer "B.Cu")
		(net 420)
	)
	(segment
		(start 101.419597 79.699796)
		(end 102.215093 80.495292)
		(width 0.125)
		(layer "B.Cu")
		(net 420)
	)
	(segment
		(start 97.935 90.2)
		(end 98.285 89.85)
		(width 0.125)
		(layer "B.Cu")
		(net 420)
	)
	(segment
		(start 101.631726 82.316089)
		(end 101.631726 82.31609)
		(width 0.125)
		(layer "B.Cu")
		(net 420)
	)
	(segment
		(start 101.631726 82.31609)
		(end 101.242817 81.927181)
		(width 0.125)
		(layer "B.Cu")
		(net 420)
	)
	(segment
		(start 102.851489 80.495292)
		(end 102.851487 80.495291)
		(width 0.125)
		(layer "B.Cu")
		(net 420)
	)
	(segment
		(start 101.24282 81.927181)
		(end 101.101397 81.785761)
		(width 0.125)
		(layer "B.Cu")
		(net 420)
	)
	(segment
		(start 99.975 83.371778)
		(end 100.553388 82.793388)
		(width 0.125)
		(layer "B.Cu")
		(net 420)
	)
	(segment
		(start 98.285 89.85)
		(end 98.656778 89.85)
		(width 0.125)
		(layer "B.Cu")
		(net 420)
	)
	(segment
		(start 102.798455 79.240177)
		(end 103.134331 79.576053)
		(width 0.125)
		(layer "B.Cu")
		(net 420)
	)
	(segment
		(start 101.136754 79.699796)
		(end 101.136753 79.699797)
		(width 0.125)
		(layer "B.Cu")
		(net 420)
	)
	(segment
		(start 99.975 88.531778)
		(end 99.975 83.371778)
		(width 0.125)
		(layer "B.Cu")
		(net 420)
	)
	(segment
		(start 102.798457 79.240176)
		(end 102.798455 79.240177)
		(width 0.125)
		(layer "B.Cu")
		(net 420)
	)
	(segment
		(start 102.851487 79.858895)
		(end 102.515612 79.52302)
		(width 0.125)
		(layer "B.Cu")
		(net 420)
	)
	(segment
		(start 104.145 78.4525)
		(end 104.3075 78.29)
		(width 0.125)
		(layer "B.Cu")
		(net 420)
	)
	(segment
		(start 102.515611 79.240177)
		(end 102.515613 79.240176)
		(width 0.125)
		(layer "B.Cu")
		(net 420)
	)
	(segment
		(start 100.83623 82.793388)
		(end 100.836231 82.793388)
		(width 0.125)
		(layer "B.Cu")
		(net 420)
	)
	(segment
		(start 101.101397 81.785761)
		(end 101.01301 81.697371)
		(width 0.125)
		(layer "B.Cu")
		(net 420)
	)
	(segment
		(start 104.145 79.201778)
		(end 104.145 78.4525)
		(width 0.125)
		(layer "B.Cu")
		(net 420)
	)
	(segment
		(start 103.770726 79.576052)
		(end 104.145 79.201778)
		(width 0.125)
		(layer "B.Cu")
		(net 420)
	)
	(segment
		(start 101.631727 82.952486)
		(end 101.631726 82.952487)
		(width 0.125)
		(layer "B.Cu")
		(net 420)
	)
	(segment
		(start 100.836231 82.793388)
		(end 100.99533 82.952487)
		(width 0.125)
		(layer "B.Cu")
		(net 420)
	)
	(segment
		(start 101.01301 81.697371)
		(end 100.217515 80.901876)
		(width 0.125)
		(layer "B.Cu")
		(net 420)
	)
	(segment
		(start 100.500359 80.619034)
		(end 100.500357 80.619035)
		(width 0.125)
		(layer "B.Cu")
		(net 420)
	)
	(segment
		(start 101.419597 79.699797)
		(end 101.419597 79.699796)
		(width 0.125)
		(layer "B.Cu")
		(net 420)
	)
	(segment
		(start 98.656778 89.85)
		(end 99.975 88.531778)
		(width 0.125)
		(layer "B.Cu")
		(net 420)
	)
	(segment
		(start 103.770727 79.576053)
		(end 103.770726 79.576052)
		(width 0.125)
		(layer "B.Cu")
		(net 420)
	)
	(segment
		(start 100.500357 80.619035)
		(end 101.295853 81.414531)
		(width 0.125)
		(layer "B.Cu")
		(net 420)
	)
	(arc
		(start 101.136753 79.982639)
		(mid 101.078175 79.841217)
		(end 101.136754 79.699796)
		(width 0.125)
		(layer "B.Cu")
		(net 420)
	)
	(arc
		(start 100.217515 80.619034)
		(mid 100.358936 80.560456)
		(end 100.500359 80.619034)
		(width 0.125)
		(layer "B.Cu")
		(net 420)
	)
	(arc
		(start 100.99533 82.952487)
		(mid 101.313529 83.084289)
		(end 101.631727 82.952486)
		(width 0.125)
		(layer "B.Cu")
		(net 420)
	)
	(arc
		(start 102.215093 80.495292)
		(mid 102.533291 80.627094)
		(end 102.851489 80.495292)
		(width 0.125)
		(layer "B.Cu")
		(net 420)
	)
	(arc
		(start 102.515612 79.52302)
		(mid 102.457033 79.381599)
		(end 102.515611 79.240177)
		(width 0.125)
		(layer "B.Cu")
		(net 420)
	)
	(arc
		(start 101.295853 81.414531)
		(mid 101.614051 81.546333)
		(end 101.932249 81.414531)
		(width 0.125)
		(layer "B.Cu")
		(net 420)
	)
	(arc
		(start 103.134331 79.576053)
		(mid 103.452529 79.707855)
		(end 103.770727 79.576053)
		(width 0.125)
		(layer "B.Cu")
		(net 420)
	)
	(arc
		(start 102.515613 79.240176)
		(mid 102.657034 79.181598)
		(end 102.798457 79.240176)
		(width 0.125)
		(layer "B.Cu")
		(net 420)
	)
	(arc
		(start 101.136753 79.699797)
		(mid 101.278176 79.641217)
		(end 101.419597 79.699797)
		(width 0.125)
		(layer "B.Cu")
		(net 420)
	)
	(arc
		(start 101.631726 82.952487)
		(mid 101.763528 82.634288)
		(end 101.631726 82.316089)
		(width 0.125)
		(layer "B.Cu")
		(net 420)
	)
	(arc
		(start 100.553388 82.793388)
		(mid 100.694809 82.73481)
		(end 100.83623 82.793388)
		(width 0.125)
		(layer "B.Cu")
		(net 420)
	)
	(arc
		(start 102.851487 80.495291)
		(mid 102.983289 80.177093)
		(end 102.851487 79.858895)
		(width 0.125)
		(layer "B.Cu")
		(net 420)
	)
	(arc
		(start 100.217515 80.901876)
		(mid 100.158936 80.760456)
		(end 100.217515 80.619034)
		(width 0.125)
		(layer "B.Cu")
		(net 420)
	)
	(arc
		(start 101.932248 81.41453)
		(mid 102.06405 81.096332)
		(end 101.932248 80.778134)
		(width 0.125)
		(layer "B.Cu")
		(net 420)
	)
	(segment
		(start 105.597323 72.005136)
		(end 105.597323 72.730136)
		(width 0.125)
		(layer "F.Cu")
		(net 422)
	)
	(segment
		(start 105.597323 72.730136)
		(end 105.722323 72.855136)
		(width 0.125)
		(layer "F.Cu")
		(net 422)
	)
	(segment
		(start 105.722323 74.630899)
		(end 103.895 76.458222)
		(width 0.125)
		(layer "F.Cu")
		(net 422)
	)
	(segment
		(start 103.895 78.1275)
		(end 103.7325 78.29)
		(width 0.125)
		(layer "F.Cu")
		(net 422)
	)
	(segment
		(start 103.895 76.458222)
		(end 103.895 78.1275)
		(width 0.125)
		(layer "F.Cu")
		(net 422)
	)
	(segment
		(start 105.722323 72.855136)
		(end 105.722323 74.630899)
		(width 0.125)
		(layer "F.Cu")
		(net 422)
	)
	(via
		(at 103.7325 78.29)
		(size 0.45)
		(drill 0.1)
		(layers "F.Cu" "B.Cu")
		(net 422)
	)
	(segment
		(start 99.725 83.268222)
		(end 99.725 87.115)
		(width 0.125)
		(layer "B.Cu")
		(net 422)
	)
	(segment
		(start 98.553222 89.6)
		(end 98.285 89.6)
		(width 0.125)
		(layer "B.Cu")
		(net 422)
	)
	(segment
		(start 99.725 87.893772)
		(end 99.725 87.915)
		(width 0.125)
		(layer "B.Cu")
		(net 422)
	)
	(segment
		(start 103.895 78.4525)
		(end 103.895 79.098222)
		(width 0.125)
		(layer "B.Cu")
		(net 422)
	)
	(segment
		(start 101.47263 81.237754)
		(end 100.677134 80.442258)
		(width 0.125)
		(layer "B.Cu")
		(net 422)
	)
	(segment
		(start 102.674711 80.318515)
		(end 102.674712 80.318514)
		(width 0.125)
		(layer "B.Cu")
		(net 422)
	)
	(segment
		(start 99.346227 87.493772)
		(end 99.346227 87.515)
		(width 0.125)
		(layer "B.Cu")
		(net 422)
	)
	(segment
		(start 103.311108 79.399276)
		(end 102.975232 79.0634)
		(width 0.125)
		(layer "B.Cu")
		(net 422)
	)
	(segment
		(start 102.674711 80.03567)
		(end 102.67471 80.035672)
		(width 0.125)
		(layer "B.Cu")
		(net 422)
	)
	(segment
		(start 99.535613 87.704386)
		(end 99.535614 87.704386)
		(width 0.125)
		(layer "B.Cu")
		(net 422)
	)
	(segment
		(start 100.836231 81.87415)
		(end 100.924621 81.962537)
		(width 0.125)
		(layer "B.Cu")
		(net 422)
	)
	(segment
		(start 99.725 88.428222)
		(end 98.553222 89.6)
		(width 0.125)
		(layer "B.Cu")
		(net 422)
	)
	(segment
		(start 102.338836 79.699795)
		(end 102.674711 80.03567)
		(width 0.125)
		(layer "B.Cu")
		(net 422)
	)
	(segment
		(start 101.172106 82.77571)
		(end 101.013007 82.616611)
		(width 0.125)
		(layer "B.Cu")
		(net 422)
	)
	(segment
		(start 101.755471 81.237753)
		(end 101.755472 81.237754)
		(width 0.125)
		(layer "B.Cu")
		(net 422)
	)
	(segment
		(start 100.959977 80.159414)
		(end 101.755472 80.954909)
		(width 0.125)
		(layer "B.Cu")
		(net 422)
	)
	(segment
		(start 98.285 89.6)
		(end 97.935 89.25)
		(width 0.125)
		(layer "B.Cu")
		(net 422)
	)
	(segment
		(start 100.040736 81.078655)
		(end 100.836231 81.87415)
		(width 0.125)
		(layer "B.Cu")
		(net 422)
	)
	(segment
		(start 100.376611 82.616611)
		(end 99.725 83.268222)
		(width 0.125)
		(layer "B.Cu")
		(net 422)
	)
	(segment
		(start 101.596373 79.523019)
		(end 101.596375 79.523018)
		(width 0.125)
		(layer "B.Cu")
		(net 422)
	)
	(segment
		(start 99.725 87.915)
		(end 99.725 88.428222)
		(width 0.125)
		(layer "B.Cu")
		(net 422)
	)
	(segment
		(start 99.535614 87.304386)
		(end 99.535613 87.304386)
		(width 0.125)
		(layer "B.Cu")
		(net 422)
	)
	(segment
		(start 102.975232 79.0634)
		(end 102.975234 79.063399)
		(width 0.125)
		(layer "B.Cu")
		(net 422)
	)
	(segment
		(start 102.67471 80.318514)
		(end 102.674711 80.318515)
		(width 0.125)
		(layer "B.Cu")
		(net 422)
	)
	(segment
		(start 100.677134 80.442258)
		(end 100.677136 80.442257)
		(width 0.125)
		(layer "B.Cu")
		(net 422)
	)
	(segment
		(start 102.391869 80.318515)
		(end 101.596373 79.523019)
		(width 0.125)
		(layer "B.Cu")
		(net 422)
	)
	(segment
		(start 103.895 79.098222)
		(end 103.593949 79.399275)
		(width 0.125)
		(layer "B.Cu")
		(net 422)
	)
	(segment
		(start 100.924621 81.962537)
		(end 101.454948 82.492866)
		(width 0.125)
		(layer "B.Cu")
		(net 422)
	)
	(segment
		(start 103.593952 79.399275)
		(end 103.593951 79.399277)
		(width 0.125)
		(layer "B.Cu")
		(net 422)
	)
	(segment
		(start 101.755472 81.237754)
		(end 101.755473 81.237753)
		(width 0.125)
		(layer "B.Cu")
		(net 422)
	)
	(segment
		(start 103.593949 79.399275)
		(end 103.593952 79.399275)
		(width 0.125)
		(layer "B.Cu")
		(net 422)
	)
	(segment
		(start 101.454948 82.77571)
		(end 101.454949 82.775709)
		(width 0.125)
		(layer "B.Cu")
		(net 422)
	)
	(segment
		(start 101.755472 80.954909)
		(end 101.755471 80.954911)
		(width 0.125)
		(layer "B.Cu")
		(net 422)
	)
	(segment
		(start 103.7325 78.29)
		(end 103.895 78.4525)
		(width 0.125)
		(layer "B.Cu")
		(net 422)
	)
	(arc
		(start 99.725 87.115)
		(mid 99.66953 87.248916)
		(end 99.535614 87.304386)
		(width 0.125)
		(layer "B.Cu")
		(net 422)
	)
	(arc
		(start 100.040738 80.442257)
		(mid 99.908936 80.760455)
		(end 100.040736 81.078655)
		(width 0.125)
		(layer "B.Cu")
		(net 422)
	)
	(arc
		(start 101.454949 82.775709)
		(mid 101.313528 82.834288)
		(end 101.172106 82.77571)
		(width 0.125)
		(layer "B.Cu")
		(net 422)
	)
	(arc
		(start 101.755473 81.237753)
		(mid 101.614052 81.296332)
		(end 101.47263 81.237754)
		(width 0.125)
		(layer "B.Cu")
		(net 422)
	)
	(arc
		(start 101.755471 80.954911)
		(mid 101.81405 81.096331)
		(end 101.755471 81.237753)
		(width 0.125)
		(layer "B.Cu")
		(net 422)
	)
	(arc
		(start 99.535613 87.304386)
		(mid 99.401697 87.359856)
		(end 99.346227 87.493772)
		(width 0.125)
		(layer "B.Cu")
		(net 422)
	)
	(arc
		(start 100.959977 79.523018)
		(mid 100.828175 79.841216)
		(end 100.959977 80.159414)
		(width 0.125)
		(layer "B.Cu")
		(net 422)
	)
	(arc
		(start 101.596375 79.523018)
		(mid 101.278175 79.391217)
		(end 100.959977 79.523018)
		(width 0.125)
		(layer "B.Cu")
		(net 422)
	)
	(arc
		(start 102.975234 79.063399)
		(mid 102.657034 78.931598)
		(end 102.338836 79.063399)
		(width 0.125)
		(layer "B.Cu")
		(net 422)
	)
	(arc
		(start 102.338836 79.063399)
		(mid 102.207034 79.381597)
		(end 102.338836 79.699795)
		(width 0.125)
		(layer "B.Cu")
		(net 422)
	)
	(arc
		(start 102.67471 80.035672)
		(mid 102.733289 80.177092)
		(end 102.67471 80.318514)
		(width 0.125)
		(layer "B.Cu")
		(net 422)
	)
	(arc
		(start 102.674712 80.318514)
		(mid 102.533291 80.377093)
		(end 102.391869 80.318515)
		(width 0.125)
		(layer "B.Cu")
		(net 422)
	)
	(arc
		(start 99.346227 87.515)
		(mid 99.401697 87.648916)
		(end 99.535613 87.704386)
		(width 0.125)
		(layer "B.Cu")
		(net 422)
	)
	(arc
		(start 99.535614 87.704386)
		(mid 99.66953 87.759856)
		(end 99.725 87.893772)
		(width 0.125)
		(layer "B.Cu")
		(net 422)
	)
	(arc
		(start 101.454948 82.492866)
		(mid 101.513527 82.634288)
		(end 101.454948 82.77571)
		(width 0.125)
		(layer "B.Cu")
		(net 422)
	)
	(arc
		(start 103.593951 79.399277)
		(mid 103.452529 79.457855)
		(end 103.311108 79.399276)
		(width 0.125)
		(layer "B.Cu")
		(net 422)
	)
	(arc
		(start 100.677136 80.442257)
		(mid 100.358936 80.310456)
		(end 100.040738 80.442257)
		(width 0.125)
		(layer "B.Cu")
		(net 422)
	)
	(arc
		(start 101.013007 82.616611)
		(mid 100.694809 82.484809)
		(end 100.376611 82.616611)
		(width 0.125)
		(layer "B.Cu")
		(net 422)
	)
	(segment
		(start 87.35 117.949)
		(end 87.35 118.85)
		(width 0.15)
		(layer "F.Cu")
		(net 424)
	)
	(segment
		(start 87.35 118.85)
		(end 87.001 119.199)
		(width 0.15)
		(layer "F.Cu")
		(net 424)
	)
	(segment
		(start 87.001 119.199)
		(end 87.001 119.4)
		(width 0.15)
		(layer "F.Cu")
		(net 424)
	)
	(segment
		(start 148.75 95.75)
		(end 148.25 95.75)
		(width 0.15)
		(layer "F.Cu")
		(net 427)
	)
	(segment
		(start 148.85 95.85)
		(end 148.75 95.75)
		(width 0.15)
		(layer "F.Cu")
		(net 427)
	)
	(via
		(at 131.15 104.07)
		(size 0.45)
		(drill 0.1)
		(layers "F.Cu" "B.Cu")
		(net 427)
	)
	(via
		(at 148.85 95.85)
		(size 0.45)
		(drill 0.1)
		(layers "F.Cu" "B.Cu")
		(net 427)
	)
	(segment
		(start 148.125 95.85)
		(end 143 100.975)
		(width 0.15)
		(layer "In5.Cu")
		(net 427)
	)
	(segment
		(start 143 100.975)
		(end 139.675 100.975)
		(width 0.15)
		(layer "In5.Cu")
		(net 427)
	)
	(segment
		(start 131.48 104.4)
		(end 131.15 104.07)
		(width 0.15)
		(layer "In5.Cu")
		(net 427)
	)
	(segment
		(start 133.7 100.75)
		(end 133.7 103.2)
		(width 0.15)
		(layer "In5.Cu")
		(net 427)
	)
	(segment
		(start 139.675 100.975)
		(end 138.85 101.8)
		(width 0.15)
		(layer "In5.Cu")
		(net 427)
	)
	(segment
		(start 133.95 100.5)
		(end 133.7 100.75)
		(width 0.15)
		(layer "In5.Cu")
		(net 427)
	)
	(segment
		(start 137.55 101.8)
		(end 136.65 100.9)
		(width 0.15)
		(layer "In5.Cu")
		(net 427)
	)
	(segment
		(start 133.7 103.2)
		(end 132.5 104.4)
		(width 0.15)
		(layer "In5.Cu")
		(net 427)
	)
	(segment
		(start 132.5 104.4)
		(end 131.48 104.4)
		(width 0.15)
		(layer "In5.Cu")
		(net 427)
	)
	(segment
		(start 136.65 100.9)
		(end 135.65 100.9)
		(width 0.15)
		(layer "In5.Cu")
		(net 427)
	)
	(segment
		(start 135.25 100.5)
		(end 133.95 100.5)
		(width 0.15)
		(layer "In5.Cu")
		(net 427)
	)
	(segment
		(start 138.85 101.8)
		(end 137.55 101.8)
		(width 0.15)
		(layer "In5.Cu")
		(net 427)
	)
	(segment
		(start 148.85 95.85)
		(end 148.125 95.85)
		(width 0.15)
		(layer "In5.Cu")
		(net 427)
	)
	(segment
		(start 135.65 100.9)
		(end 135.25 100.5)
		(width 0.15)
		(layer "In5.Cu")
		(net 427)
	)
	(segment
		(start 130.97 104.25)
		(end 131.15 104.07)
		(width 0.125)
		(layer "B.Cu")
		(net 427)
	)
	(segment
		(start 130.385 104.25)
		(end 130.97 104.25)
		(width 0.125)
		(layer "B.Cu")
		(net 427)
	)
	(segment
		(start 102.347323 82.147323)
		(end 102.85 82.65)
		(width 0.15)
		(layer "F.Cu")
		(net 428)
	)
	(segment
		(start 102.95 86.925)
		(end 102.475 86.925)
		(width 0.15)
		(layer "F.Cu")
		(net 428)
	)
	(segment
		(start 102.35 87.05)
		(end 101.885 87.05)
		(width 0.15)
		(layer "F.Cu")
		(net 428)
	)
	(segment
		(start 102.85 82.65)
		(end 102.85 86.1)
		(width 0.15)
		(layer "F.Cu")
		(net 428)
	)
	(segment
		(start 102.475 86.925)
		(end 102.35 87.05)
		(width 0.15)
		(layer "F.Cu")
		(net 428)
	)
	(segment
		(start 102.95 86.925)
		(end 102.95 86.2)
		(width 0.15)
		(layer "F.Cu")
		(net 428)
	)
	(segment
		(start 102.95 86.2)
		(end 102.85 86.1)
		(width 0.15)
		(layer "F.Cu")
		(net 428)
	)
	(segment
		(start 102.347323 80.205136)
		(end 102.347323 82.147323)
		(width 0.15)
		(layer "F.Cu")
		(net 428)
	)
	(segment
		(start 101.347323 80.205136)
		(end 101.347323 81.517637)
		(width 0.125)
		(layer "F.Cu")
		(net 429)
	)
	(segment
		(start 101.023117 85.259514)
		(end 101.037345 85.273742)
		(width 0.125)
		(layer "F.Cu")
		(net 429)
	)
	(segment
		(start 101.472323 82.999101)
		(end 101.725 83.251778)
		(width 0.125)
		(layer "F.Cu")
		(net 429)
	)
	(segment
		(start 101.347323 81.517637)
		(end 101.472323 81.642637)
		(width 0.125)
		(layer "F.Cu")
		(net 429)
	)
	(segment
		(start 99.411 86.135)
		(end 99.2 85.924)
		(width 0.125)
		(layer "F.Cu")
		(net 429)
	)
	(segment
		(start 101.249477 85.061611)
		(end 101.249478 85.061611)
		(width 0.125)
		(layer "F.Cu")
		(net 429)
	)
	(segment
		(start 100.388222 86.135)
		(end 99.411 86.135)
		(width 0.125)
		(layer "F.Cu")
		(net 429)
	)
	(segment
		(start 101.249478 85.061611)
		(end 101.235249 85.047382)
		(width 0.125)
		(layer "F.Cu")
		(net 429)
	)
	(segment
		(start 101.037345 85.485874)
		(end 101.037346 85.485875)
		(width 0.125)
		(layer "F.Cu")
		(net 429)
	)
	(segment
		(start 101.725 84.798222)
		(end 101.461611 85.061611)
		(width 0.125)
		(layer "F.Cu")
		(net 429)
	)
	(segment
		(start 101.037346 85.485875)
		(end 100.388222 86.135)
		(width 0.125)
		(layer "F.Cu")
		(net 429)
	)
	(segment
		(start 101.472323 81.642637)
		(end 101.472323 82.999101)
		(width 0.125)
		(layer "F.Cu")
		(net 429)
	)
	(segment
		(start 101.725 83.251778)
		(end 101.725 84.798222)
		(width 0.125)
		(layer "F.Cu")
		(net 429)
	)
	(via
		(at 99.2 85.924)
		(size 0.45)
		(drill 0.1)
		(layers "F.Cu" "B.Cu")
		(net 429)
	)
	(arc
		(start 101.461611 85.061611)
		(mid 101.355544 85.105545)
		(end 101.249477 85.061611)
		(width 0.125)
		(layer "F.Cu")
		(net 429)
	)
	(arc
		(start 101.235249 85.047382)
		(mid 101.129183 85.003448)
		(end 101.023117 85.047382)
		(width 0.125)
		(layer "F.Cu")
		(net 429)
	)
	(arc
		(start 101.023117 85.047382)
		(mid 100.979183 85.153448)
		(end 101.023117 85.259514)
		(width 0.125)
		(layer "F.Cu")
		(net 429)
	)
	(arc
		(start 101.037345 85.273742)
		(mid 101.081279 85.379808)
		(end 101.037345 85.485874)
		(width 0.125)
		(layer "F.Cu")
		(net 429)
	)
	(segment
		(start 96.254175 88.619047)
		(end 98.738222 86.135)
		(width 0.125)
		(layer "B.Cu")
		(net 429)
	)
	(segment
		(start 98.738222 86.135)
		(end 98.989 86.135)
		(width 0.125)
		(layer "B.Cu")
		(net 429)
	)
	(segment
		(start 94.754175 88.619047)
		(end 96.254175 88.619047)
		(width 0.125)
		(layer "B.Cu")
		(net 429)
	)
	(segment
		(start 98.989 86.135)
		(end 99.2 85.924)
		(width 0.125)
		(layer "B.Cu")
		(net 429)
	)
	(segment
		(start 94.298222 89.075)
		(end 94.754175 88.619047)
		(width 0.125)
		(layer "B.Cu")
		(net 429)
	)
	(segment
		(start 93.1325 89.075)
		(end 94.298222 89.075)
		(width 0.125)
		(layer "B.Cu")
		(net 429)
	)
	(segment
		(start 93.0075 88.95)
		(end 93.1325 89.075)
		(width 0.125)
		(layer "B.Cu")
		(net 429)
	)
	(segment
		(start 101.722323 82.895545)
		(end 101.975 83.148222)
		(width 0.125)
		(layer "F.Cu")
		(net 430)
	)
	(segment
		(start 101.847323 81.517637)
		(end 101.722323 81.642637)
		(width 0.125)
		(layer "F.Cu")
		(net 430)
	)
	(segment
		(start 101.975 84.901778)
		(end 100.491778 86.385)
		(width 0.125)
		(layer "F.Cu")
		(net 430)
	)
	(segment
		(start 101.975 83.148222)
		(end 101.975 84.901778)
		(width 0.125)
		(layer "F.Cu")
		(net 430)
	)
	(segment
		(start 101.722323 81.642637)
		(end 101.722323 82.895545)
		(width 0.125)
		(layer "F.Cu")
		(net 430)
	)
	(segment
		(start 99.411 86.385)
		(end 99.2 86.596)
		(width 0.125)
		(layer "F.Cu")
		(net 430)
	)
	(segment
		(start 101.847323 80.205136)
		(end 101.847323 81.517637)
		(width 0.125)
		(layer "F.Cu")
		(net 430)
	)
	(segment
		(start 100.491778 86.385)
		(end 99.411 86.385)
		(width 0.125)
		(layer "F.Cu")
		(net 430)
	)
	(via
		(at 99.2 86.596)
		(size 0.45)
		(drill 0.1)
		(layers "F.Cu" "B.Cu")
		(net 430)
	)
	(segment
		(start 98.989 86.385)
		(end 99.2 86.596)
		(width 0.125)
		(layer "B.Cu")
		(net 430)
	)
	(segment
		(start 93.0075 89.45)
		(end 93.1325 89.325)
		(width 0.125)
		(layer "B.Cu")
		(net 430)
	)
	(segment
		(start 96.357731 88.869047)
		(end 98.841778 86.385)
		(width 0.125)
		(layer "B.Cu")
		(net 430)
	)
	(segment
		(start 94.857731 88.869047)
		(end 96.357731 88.869047)
		(width 0.125)
		(layer "B.Cu")
		(net 430)
	)
	(segment
		(start 93.1325 89.325)
		(end 94.401778 89.325)
		(width 0.125)
		(layer "B.Cu")
		(net 430)
	)
	(segment
		(start 98.841778 86.385)
		(end 98.989 86.385)
		(width 0.125)
		(layer "B.Cu")
		(net 430)
	)
	(segment
		(start 94.401778 89.325)
		(end 94.857731 88.869047)
		(width 0.125)
		(layer "B.Cu")
		(net 430)
	)
	(segment
		(start 99.2505 78.4555)
		(end 99.2505 76.786926)
		(width 0.155)
		(layer "F.Cu")
		(net 433)
	)
	(segment
		(start 98.697823 76.234249)
		(end 99.2505 76.786926)
		(width 0.155)
		(layer "F.Cu")
		(net 433)
	)
	(segment
		(start 113.15 117.25)
		(end 113.05 117.15)
		(width 0.13)
		(layer "F.Cu")
		(net 433)
	)
	(segment
		(start 113.05 116.563749)
		(end 113.05 115.793749)
		(width 0.13)
		(layer "F.Cu")
		(net 433)
	)
	(segment
		(start 112.8 112.961426)
		(end 113.390155 113.551581)
		(width 0.155)
		(layer "F.Cu")
		(net 433)
	)
	(segment
		(start 113.05 115.793749)
		(end 113.05 114.75)
		(width 0.155)
		(layer "F.Cu")
		(net 433)
	)
	(segment
		(start 113.05 114.75)
		(end 113.25 114.55)
		(width 0.155)
		(layer "F.Cu")
		(net 433)
	)
	(segment
		(start 113.25 114.541017)
		(end 113.390155 114.400862)
		(width 0.155)
		(layer "F.Cu")
		(net 433)
	)
	(segment
		(start 98.597323 72.005136)
		(end 98.597323 73.317637)
		(width 0.155)
		(layer "F.Cu")
		(net 433)
	)
	(segment
		(start 113.15 118.2)
		(end 113.15 118.8)
		(width 0.13)
		(layer "F.Cu")
		(net 433)
	)
	(segment
		(start 112.8 110.996638)
		(end 112.8 112.961426)
		(width 0.155)
		(layer "F.Cu")
		(net 433)
	)
	(segment
		(start 112.8 110.996638)
		(end 112.6525 110.849138)
		(width 0.155)
		(layer "F.Cu")
		(net 433)
	)
	(segment
		(start 113.05 117.15)
		(end 113.05 116.685)
		(width 0.13)
		(layer "F.Cu")
		(net 433)
	)
	(segment
		(start 99.106 78.6)
		(end 99.2505 78.4555)
		(width 0.155)
		(layer "F.Cu")
		(net 433)
	)
	(segment
		(start 113.15 118.8)
		(end 113.8 119.45)
		(width 0.13)
		(layer "F.Cu")
		(net 433)
	)
	(segment
		(start 113.390155 113.551581)
		(end 113.390155 114.400862)
		(width 0.155)
		(layer "F.Cu")
		(net 433)
	)
	(segment
		(start 113.15 118.2)
		(end 113.15 117.25)
		(width 0.13)
		(layer "F.Cu")
		(net 433)
	)
	(segment
		(start 98.597323 73.317637)
		(end 98.697823 73.418137)
		(width 0.155)
		(layer "F.Cu")
		(net 433)
	)
	(segment
		(start 113.25 114.55)
		(end 113.25 114.541017)
		(width 0.155)
		(layer "F.Cu")
		(net 433)
	)
	(segment
		(start 98.697823 73.418137)
		(end 98.697823 76.234249)
		(width 0.155)
		(layer "F.Cu")
		(net 433)
	)
	(via
		(at 100.506 97.2)
		(size 0.45)
		(drill 0.1)
		(layers "F.Cu" "B.Cu")
		(net 433)
	)
	(via
		(at 112.6525 110.849138)
		(size 0.45)
		(drill 0.1)
		(layers "F.Cu" "B.Cu")
		(net 433)
	)
	(via
		(at 99.106 78.6)
		(size 0.45)
		(drill 0.1)
		(layers "F.Cu" "B.Cu")
		(net 433)
	)
	(segment
		(start 112.8005 110.311218)
		(end 112.8005 110.701138)
		(width 0.16)
		(layer "In3.Cu")
		(net 433)
	)
	(segment
		(start 106.688282 107.099)
		(end 108.768935 107.099)
		(width 0.16)
		(layer "In3.Cu")
		(net 433)
	)
	(segment
		(start 112.8005 110.701138)
		(end 112.6525 110.849138)
		(width 0.16)
		(layer "In3.Cu")
		(net 433)
	)
	(segment
		(start 111.385561 108.896279)
		(end 112.8005 110.311218)
		(width 0.16)
		(layer "In3.Cu")
		(net 433)
	)
	(segment
		(start 105.801 106.211718)
		(end 106.688282 107.099)
		(width 0.16)
		(layer "In3.Cu")
		(net 433)
	)
	(segment
		(start 104.158282 102.749)
		(end 105.801 104.391718)
		(width 0.16)
		(layer "In3.Cu")
		(net 433)
	)
	(segment
		(start 103.618282 102.749)
		(end 104.158282 102.749)
		(width 0.16)
		(layer "In3.Cu")
		(net 433)
	)
	(segment
		(start 105.801 104.391718)
		(end 105.801 106.211718)
		(width 0.16)
		(layer "In3.Cu")
		(net 433)
	)
	(segment
		(start 100.651 97.345)
		(end 100.651 99.781718)
		(width 0.16)
		(layer "In3.Cu")
		(net 433)
	)
	(segment
		(start 108.768935 107.099)
		(end 110.566214 108.896279)
		(width 0.16)
		(layer "In3.Cu")
		(net 433)
	)
	(segment
		(start 100.651 99.781718)
		(end 103.618282 102.749)
		(width 0.16)
		(layer "In3.Cu")
		(net 433)
	)
	(segment
		(start 110.566214 108.896279)
		(end 111.385561 108.896279)
		(width 0.16)
		(layer "In3.Cu")
		(net 433)
	)
	(segment
		(start 100.506 97.2)
		(end 100.651 97.345)
		(width 0.16)
		(layer "In3.Cu")
		(net 433)
	)
	(segment
		(start 100.651 97.055)
		(end 100.651 95.361718)
		(width 0.16)
		(layer "In5.Cu")
		(net 433)
	)
	(segment
		(start 100.238282 79.524)
		(end 99.638282 79.524)
		(width 0.16)
		(layer "In5.Cu")
		(net 433)
	)
	(segment
		(start 99.251 78.745)
		(end 99.106 78.6)
		(width 0.16)
		(layer "In5.Cu")
		(net 433)
	)
	(segment
		(start 101.676 84.861718)
		(end 101.676 80.961718)
		(width 0.16)
		(layer "In5.Cu")
		(net 433)
	)
	(segment
		(start 102.451 87.738282)
		(end 102.451 85.636718)
		(width 0.16)
		(layer "In5.Cu")
		(net 433)
	)
	(segment
		(start 102.451 85.636718)
		(end 101.676 84.861718)
		(width 0.16)
		(layer "In5.Cu")
		(net 433)
	)
	(segment
		(start 100.351 89.838282)
		(end 102.451 87.738282)
		(width 0.16)
		(layer "In5.Cu")
		(net 433)
	)
	(segment
		(start 99.251 79.136718)
		(end 99.251 78.745)
		(width 0.16)
		(layer "In5.Cu")
		(net 433)
	)
	(segment
		(start 100.651 95.361718)
		(end 100.351 95.061718)
		(width 0.16)
		(layer "In5.Cu")
		(net 433)
	)
	(segment
		(start 99.638282 79.524)
		(end 99.251 79.136718)
		(width 0.16)
		(layer "In5.Cu")
		(net 433)
	)
	(segment
		(start 100.506 97.2)
		(end 100.651 97.055)
		(width 0.16)
		(layer "In5.Cu")
		(net 433)
	)
	(segment
		(start 100.351 95.061718)
		(end 100.351 89.838282)
		(width 0.16)
		(layer "In5.Cu")
		(net 433)
	)
	(segment
		(start 101.676 80.961718)
		(end 100.238282 79.524)
		(width 0.16)
		(layer "In5.Cu")
		(net 433)
	)
	(segment
		(start 97.897 78.5)
		(end 97.7495 78.3525)
		(width 0.155)
		(layer "F.Cu")
		(net 434)
	)
	(segment
		(start 97.496823 75.510397)
		(end 97.496823 73.418137)
		(width 0.155)
		(layer "F.Cu")
		(net 434)
	)
	(segment
		(start 130.4225 91.997)
		(end 130.5 91.997)
		(width 0.155)
		(layer "F.Cu")
		(net 434)
	)
	(segment
		(start 97.7495 78.3525)
		(end 97.7495 75.763074)
		(width 0.155)
		(layer "F.Cu")
		(net 434)
	)
	(segment
		(start 130.3 91.8745)
		(end 130.4225 91.997)
		(width 0.155)
		(layer "F.Cu")
		(net 434)
	)
	(segment
		(start 97.496823 73.418137)
		(end 97.597323 73.317637)
		(width 0.155)
		(layer "F.Cu")
		(net 434)
	)
	(segment
		(start 129.785 92.2)
		(end 130.1105 91.8745)
		(width 0.155)
		(layer "F.Cu")
		(net 434)
	)
	(segment
		(start 97.597323 73.317637)
		(end 97.597323 72.005136)
		(width 0.155)
		(layer "F.Cu")
		(net 434)
	)
	(segment
		(start 97.7495 75.763074)
		(end 97.496823 75.510397)
		(width 0.155)
		(layer "F.Cu")
		(net 434)
	)
	(segment
		(start 130.1105 91.8745)
		(end 130.3 91.8745)
		(width 0.155)
		(layer "F.Cu")
		(net 434)
	)
	(via
		(at 130.5 91.997)
		(size 0.45)
		(drill 0.1)
		(layers "F.Cu" "B.Cu")
		(net 434)
	)
	(via
		(at 132.70789 103.29211)
		(size 0.45)
		(drill 0.1)
		(layers "F.Cu" "B.Cu")
		(net 434)
	)
	(via
		(at 97.897 78.5)
		(size 0.45)
		(drill 0.1)
		(layers "F.Cu" "B.Cu")
		(net 434)
	)
	(segment
		(start 99.911718 80.026)
		(end 100.649 80.763282)
		(width 0.16)
		(layer "In5.Cu")
		(net 434)
	)
	(segment
		(start 101.738282 97.751)
		(end 102.051 97.438282)
		(width 0.16)
		(layer "In5.Cu")
		(net 434)
	)
	(segment
		(start 98.749 96.938282)
		(end 99.561718 97.751)
		(width 0.16)
		(layer "In5.Cu")
		(net 434)
	)
	(segment
		(start 118.161718 106.951)
		(end 121.238282 106.951)
		(width 0.16)
		(layer "In5.Cu")
		(net 434)
	)
	(segment
		(start 100.649 86.969)
		(end 100.649 87.019)
		(width 0.16)
		(layer "In5.Cu")
		(net 434)
	)
	(segment
		(start 100.949 86.069)
		(end 101.10151 86.069)
		(width 0.16)
		(layer "In5.Cu")
		(net 434)
	)
	(segment
		(start 131.561718 102.351)
		(end 132.502828 103.29211)
		(width 0.16)
		(layer "In5.Cu")
		(net 434)
	)
	(segment
		(start 109.461718 94.251)
		(end 112.599 97.388282)
		(width 0.16)
		(layer "In5.Cu")
		(net 434)
	)
	(segment
		(start 99.749 89.261718)
		(end 99.749 94.761718)
		(width 0.16)
		(layer "In5.Cu")
		(net 434)
	)
	(segment
		(start 102.051 96.738282)
		(end 104.538282 94.251)
		(width 0.16)
		(layer "In5.Cu")
		(net 434)
	)
	(segment
		(start 101.10151 86.669)
		(end 100.949 86.669)
		(width 0.16)
		(layer "In5.Cu")
		(net 434)
	)
	(segment
		(start 100.649 88.361718)
		(end 99.749 89.261718)
		(width 0.16)
		(layer "In5.Cu")
		(net 434)
	)
	(segment
		(start 112.599 101.388282)
		(end 118.161718 106.951)
		(width 0.16)
		(layer "In5.Cu")
		(net 434)
	)
	(segment
		(start 125.838282 102.351)
		(end 131.561718 102.351)
		(width 0.16)
		(layer "In5.Cu")
		(net 434)
	)
	(segment
		(start 132.502828 103.29211)
		(end 132.70789 103.29211)
		(width 0.16)
		(layer "In5.Cu")
		(net 434)
	)
	(segment
		(start 99.561718 97.751)
		(end 101.738282 97.751)
		(width 0.16)
		(layer "In5.Cu")
		(net 434)
	)
	(segment
		(start 97.897 78.5)
		(end 97.749 78.648)
		(width 0.16)
		(layer "In5.Cu")
		(net 434)
	)
	(segment
		(start 99.749 94.761718)
		(end 98.749 95.761718)
		(width 0.16)
		(layer "In5.Cu")
		(net 434)
	)
	(segment
		(start 97.749 78.648)
		(end 97.749 79.388282)
		(width 0.16)
		(layer "In5.Cu")
		(net 434)
	)
	(segment
		(start 104.538282 94.251)
		(end 109.461718 94.251)
		(width 0.16)
		(layer "In5.Cu")
		(net 434)
	)
	(segment
		(start 100.649 87.019)
		(end 100.649 88.361718)
		(width 0.16)
		(layer "In5.Cu")
		(net 434)
	)
	(segment
		(start 121.238282 106.951)
		(end 125.838282 102.351)
		(width 0.16)
		(layer "In5.Cu")
		(net 434)
	)
	(segment
		(start 100.649 80.763282)
		(end 100.649 85.769)
		(width 0.16)
		(layer "In5.Cu")
		(net 434)
	)
	(segment
		(start 102.051 97.438282)
		(end 102.051 96.738282)
		(width 0.16)
		(layer "In5.Cu")
		(net 434)
	)
	(segment
		(start 112.599 97.388282)
		(end 112.599 101.388282)
		(width 0.16)
		(layer "In5.Cu")
		(net 434)
	)
	(segment
		(start 98.386718 80.026)
		(end 99.911718 80.026)
		(width 0.16)
		(layer "In5.Cu")
		(net 434)
	)
	(segment
		(start 98.749 95.761718)
		(end 98.749 96.938282)
		(width 0.16)
		(layer "In5.Cu")
		(net 434)
	)
	(segment
		(start 97.749 79.388282)
		(end 98.386718 80.026)
		(width 0.16)
		(layer "In5.Cu")
		(net 434)
	)
	(arc
		(start 101.10151 86.069)
		(mid 101.313642 86.156868)
		(end 101.40151 86.369)
		(width 0.16)
		(layer "In5.Cu")
		(net 434)
	)
	(arc
		(start 100.649 85.769)
		(mid 100.736868 85.981132)
		(end 100.949 86.069)
		(width 0.16)
		(layer "In5.Cu")
		(net 434)
	)
	(arc
		(start 101.40151 86.369)
		(mid 101.313642 86.581132)
		(end 101.10151 86.669)
		(width 0.16)
		(layer "In5.Cu")
		(net 434)
	)
	(arc
		(start 100.949 86.669)
		(mid 100.736868 86.756868)
		(end 100.649 86.969)
		(width 0.16)
		(layer "In5.Cu")
		(net 434)
	)
	(segment
		(start 132.70789 103.29211)
		(end 132.503535 103.29211)
		(width 0.155)
		(layer "B.Cu")
		(net 434)
	)
	(segment
		(start 130.061926 91.8495)
		(end 130.3525 91.8495)
		(width 0.155)
		(layer "B.Cu")
		(net 434)
	)
	(segment
		(start 132.503535 103.29211)
		(end 129.7495 100.538075)
		(width 0.155)
		(layer "B.Cu")
		(net 434)
	)
	(segment
		(start 129.7495 100.538075)
		(end 129.7495 92.161926)
		(width 0.155)
		(layer "B.Cu")
		(net 434)
	)
	(segment
		(start 130.6 92.715)
		(end 130.9505 92.3645)
		(width 0.155)
		(layer "B.Cu")
		(net 434)
	)
	(segment
		(start 130.9505 92.3645)
		(end 130.9505 92.061926)
		(width 0.155)
		(layer "B.Cu")
		(net 434)
	)
	(segment
		(start 130.3525 91.8495)
		(end 130.5 91.997)
		(width 0.155)
		(layer "B.Cu")
		(net 434)
	)
	(segment
		(start 129.7495 92.161926)
		(end 130.061926 91.8495)
		(width 0.155)
		(layer "B.Cu")
		(net 434)
	)
	(segment
		(start 130.6475 91.8495)
		(end 130.5 91.997)
		(width 0.155)
		(layer "B.Cu")
		(net 434)
	)
	(segment
		(start 130.738074 91.8495)
		(end 130.6475 91.8495)
		(width 0.155)
		(layer "B.Cu")
		(net 434)
	)
	(segment
		(start 130.9505 92.061926)
		(end 130.738074 91.8495)
		(width 0.155)
		(layer "B.Cu")
		(net 434)
	)
	(segment
		(start 97.197823 73.418137)
		(end 97.097323 73.317637)
		(width 0.155)
		(layer "F.Cu")
		(net 436)
	)
	(segment
		(start 130.1105 91.5755)
		(end 130.3275 91.5755)
		(width 0.155)
		(layer "F.Cu")
		(net 436)
	)
	(segment
		(start 97.4505 78.3525)
		(end 97.4505 75.886926)
		(width 0.155)
		(layer "F.Cu")
		(net 436)
	)
	(segment
		(start 130.3275 91.5755)
		(end 130.5 91.403)
		(width 0.155)
		(layer "F.Cu")
		(net 436)
	)
	(segment
		(start 97.303 78.5)
		(end 97.4505 78.3525)
		(width 0.155)
		(layer "F.Cu")
		(net 436)
	)
	(segment
		(start 97.197823 75.634249)
		(end 97.197823 73.418137)
		(width 0.155)
		(layer "F.Cu")
		(net 436)
	)
	(segment
		(start 97.4505 75.886926)
		(end 97.197823 75.634249)
		(width 0.155)
		(layer "F.Cu")
		(net 436)
	)
	(segment
		(start 129.785 91.25)
		(end 130.1105 91.5755)
		(width 0.155)
		(layer "F.Cu")
		(net 436)
	)
	(segment
		(start 97.097323 73.317637)
		(end 97.097323 72.005136)
		(width 0.155)
		(layer "F.Cu")
		(net 436)
	)
	(via
		(at 130.5 91.403)
		(size 0.45)
		(drill 0.1)
		(layers "F.Cu" "B.Cu")
		(net 436)
	)
	(via
		(at 132.29211 103.70789)
		(size 0.45)
		(drill 0.1)
		(layers "F.Cu" "B.Cu")
		(net 436)
	)
	(via
		(at 97.303 78.5)
		(size 0.45)
		(drill 0.1)
		(layers "F.Cu" "B.Cu")
		(net 436)
	)
	(segment
		(start 132.29211 103.70789)
		(end 132.29211 103.502828)
		(width 0.16)
		(layer "In5.Cu")
		(net 436)
	)
	(segment
		(start 131.438282 102.649)
		(end 125.961718 102.649)
		(width 0.16)
		(layer "In5.Cu")
		(net 436)
	)
	(segment
		(start 112.301 97.511718)
		(end 109.338282 94.549)
		(width 0.16)
		(layer "In5.Cu")
		(net 436)
	)
	(segment
		(start 99.451 89.138282)
		(end 100.351 88.238282)
		(width 0.16)
		(layer "In5.Cu")
		(net 436)
	)
	(segment
		(start 109.338282 94.549)
		(end 104.661718 94.549)
		(width 0.16)
		(layer "In5.Cu")
		(net 436)
	)
	(segment
		(start 100.351 80.886718)
		(end 99.788282 80.324)
		(width 0.16)
		(layer "In5.Cu")
		(net 436)
	)
	(segment
		(start 98.451 97.061718)
		(end 98.451 95.638282)
		(width 0.16)
		(layer "In5.Cu")
		(net 436)
	)
	(segment
		(start 99.451 94.638282)
		(end 99.451 89.138282)
		(width 0.16)
		(layer "In5.Cu")
		(net 436)
	)
	(segment
		(start 98.451 95.638282)
		(end 99.451 94.638282)
		(width 0.16)
		(layer "In5.Cu")
		(net 436)
	)
	(segment
		(start 99.788282 80.324)
		(end 98.263282 80.324)
		(width 0.16)
		(layer "In5.Cu")
		(net 436)
	)
	(segment
		(start 98.263282 80.324)
		(end 97.451 79.511718)
		(width 0.16)
		(layer "In5.Cu")
		(net 436)
	)
	(segment
		(start 118.038282 107.249)
		(end 112.301 101.511718)
		(width 0.16)
		(layer "In5.Cu")
		(net 436)
	)
	(segment
		(start 102.349 96.861718)
		(end 102.349 97.561718)
		(width 0.16)
		(layer "In5.Cu")
		(net 436)
	)
	(segment
		(start 97.451 78.648)
		(end 97.303 78.5)
		(width 0.16)
		(layer "In5.Cu")
		(net 436)
	)
	(segment
		(start 132.29211 103.502828)
		(end 131.438282 102.649)
		(width 0.16)
		(layer "In5.Cu")
		(net 436)
	)
	(segment
		(start 102.349 97.561718)
		(end 101.861718 98.049)
		(width 0.16)
		(layer "In5.Cu")
		(net 436)
	)
	(segment
		(start 104.661718 94.549)
		(end 102.349 96.861718)
		(width 0.16)
		(layer "In5.Cu")
		(net 436)
	)
	(segment
		(start 101.861718 98.049)
		(end 99.438282 98.049)
		(width 0.16)
		(layer "In5.Cu")
		(net 436)
	)
	(segment
		(start 99.438282 98.049)
		(end 98.451 97.061718)
		(width 0.16)
		(layer "In5.Cu")
		(net 436)
	)
	(segment
		(start 97.451 79.511718)
		(end 97.451 78.648)
		(width 0.16)
		(layer "In5.Cu")
		(net 436)
	)
	(segment
		(start 100.351 88.238282)
		(end 100.351 80.886718)
		(width 0.16)
		(layer "In5.Cu")
		(net 436)
	)
	(segment
		(start 121.361718 107.249)
		(end 118.038282 107.249)
		(width 0.16)
		(layer "In5.Cu")
		(net 436)
	)
	(segment
		(start 125.961718 102.649)
		(end 121.361718 107.249)
		(width 0.16)
		(layer "In5.Cu")
		(net 436)
	)
	(segment
		(start 112.301 101.511718)
		(end 112.301 97.511718)
		(width 0.16)
		(layer "In5.Cu")
		(net 436)
	)
	(segment
		(start 129.4505 92.038074)
		(end 129.938074 91.5505)
		(width 0.155)
		(layer "B.Cu")
		(net 436)
	)
	(segment
		(start 131.2495 92.3645)
		(end 131.2495 91.938074)
		(width 0.155)
		(layer "B.Cu")
		(net 436)
	)
	(segment
		(start 129.4505 100.661925)
		(end 129.4505 92.038074)
		(width 0.155)
		(layer "B.Cu")
		(net 436)
	)
	(segment
		(start 129.938074 91.5505)
		(end 130.3525 91.5505)
		(width 0.155)
		(layer "B.Cu")
		(net 436)
	)
	(segment
		(start 132.29211 103.503535)
		(end 129.4505 100.661925)
		(width 0.155)
		(layer "B.Cu")
		(net 436)
	)
	(segment
		(start 132.29211 103.70789)
		(end 132.29211 103.503535)
		(width 0.155)
		(layer "B.Cu")
		(net 436)
	)
	(segment
		(start 130.6475 91.5505)
		(end 130.5 91.403)
		(width 0.155)
		(layer "B.Cu")
		(net 436)
	)
	(segment
		(start 131.6 92.715)
		(end 131.2495 92.3645)
		(width 0.155)
		(layer "B.Cu")
		(net 436)
	)
	(segment
		(start 131.2495 91.938074)
		(end 130.861926 91.5505)
		(width 0.155)
		(layer "B.Cu")
		(net 436)
	)
	(segment
		(start 130.3525 91.5505)
		(end 130.5 91.403)
		(width 0.155)
		(layer "B.Cu")
		(net 436)
	)
	(segment
		(start 130.861926 91.5505)
		(end 130.6475 91.5505)
		(width 0.155)
		(layer "B.Cu")
		(net 436)
	)
	(segment
		(start 75.5 115.885)
		(end 75.5 115.115)
		(width 0.155)
		(layer "F.Cu")
		(net 437)
	)
	(segment
		(start 95.996823 75.464603)
		(end 95.996823 73.418137)
		(width 0.155)
		(layer "F.Cu")
		(net 437)
	)
	(segment
		(start 96.097323 73.317637)
		(end 96.097323 72.005136)
		(width 0.155)
		(layer "F.Cu")
		(net 437)
	)
	(segment
		(start 74.99992 118.115)
		(end 74.99992 116.70008)
		(width 0.155)
		(layer "F.Cu")
		(net 437)
	)
	(segment
		(start 75.39 113.43)
		(end 75.140424 113.679576)
		(width 0.155)
		(layer "F.Cu")
		(net 437)
	)
	(segment
		(start 74.34992 119.35008)
		(end 74.99992 118.70008)
		(width 0.2)
		(layer "F.Cu")
		(net 437)
	)
	(segment
		(start 75.5 114.263716)
		(end 75.5 115.115)
		(width 0.155)
		(layer "F.Cu")
		(net 437)
	)
	(segment
		(start 95.897 78.5)
		(end 95.7495 78.3525)
		(width 0.155)
		(layer "F.Cu")
		(net 437)
	)
	(segment
		(start 75.56 113.43)
		(end 75.39 113.43)
		(width 0.155)
		(layer "F.Cu")
		(net 437)
	)
	(segment
		(start 75.140424 113.679576)
		(end 75.140424 113.90414)
		(width 0.155)
		(layer "F.Cu")
		(net 437)
	)
	(segment
		(start 74.99992 118.70008)
		(end 74.99992 118.115)
		(width 0.2)
		(layer "F.Cu")
		(net 437)
	)
	(segment
		(start 75.140424 113.90414)
		(end 75.5 114.263716)
		(width 0.155)
		(layer "F.Cu")
		(net 437)
	)
	(segment
		(start 95.7495 78.3525)
		(end 95.7495 75.711926)
		(width 0.155)
		(layer "F.Cu")
		(net 437)
	)
	(segment
		(start 95.996823 73.418137)
		(end 96.097323 73.317637)
		(width 0.155)
		(layer "F.Cu")
		(net 437)
	)
	(segment
		(start 75.5 116.2)
		(end 75.5 115.885)
		(width 0.155)
		(layer "F.Cu")
		(net 437)
	)
	(segment
		(start 74.99992 116.70008)
		(end 75.5 116.2)
		(width 0.155)
		(layer "F.Cu")
		(net 437)
	)
	(segment
		(start 95.7495 75.711926)
		(end 95.996823 75.464603)
		(width 0.155)
		(layer "F.Cu")
		(net 437)
	)
	(via
		(at 75.56 113.43)
		(size 0.45)
		(drill 0.1)
		(layers "F.Cu" "B.Cu")
		(net 437)
	)
	(via
		(at 101.05 106.06)
		(size 0.45)
		(drill 0.1)
		(layers "F.Cu" "B.Cu")
		(net 437)
	)
	(via
		(at 85.34 110.124)
		(size 0.45)
		(drill 0.1)
		(layers "F.Cu" "B.Cu")
		(net 437)
	)
	(via
		(at 95.897 78.5)
		(size 0.45)
		(drill 0.1)
		(layers "F.Cu" "B.Cu")
		(net 437)
	)
	(segment
		(start 85.485 109.979)
		(end 85.34 110.124)
		(width 0.16)
		(layer "In3.Cu")
		(net 437)
	)
	(segment
		(start 96.951718 109.979)
		(end 85.485 109.979)
		(width 0.16)
		(layer "In3.Cu")
		(net 437)
	)
	(segment
		(start 100.870718 106.06)
		(end 101.05 106.06)
		(width 0.16)
		(layer "In3.Cu")
		(net 437)
	)
	(segment
		(start 100.870718 106.06)
		(end 96.951718 109.979)
		(width 0.16)
		(layer "In3.Cu")
		(net 437)
	)
	(segment
		(start 98.849 88.861718)
		(end 99.974 87.736718)
		(width 0.16)
		(layer "In5.Cu")
		(net 437)
	)
	(segment
		(start 101.05 106.06)
		(end 101.05 105.870718)
		(width 0.16)
		(layer "In5.Cu")
		(net 437)
	)
	(segment
		(start 98.849 94.361718)
		(end 98.849 88.861718)
		(width 0.16)
		(layer "In5.Cu")
		(net 437)
	)
	(segment
		(start 95.749 78.963282)
		(end 95.749 78.648)
		(width 0.16)
		(layer "In5.Cu")
		(net 437)
	)
	(segment
		(start 103.351 97.338282)
		(end 103.351 97.738282)
		(width 0.16)
		(layer "In5.Cu")
		(net 437)
	)
	(segment
		(start 97.849 97.238282)
		(end 97.849 95.361718)
		(width 0.16)
		(layer "In5.Cu")
		(net 437)
	)
	(segment
		(start 85.195 109.979)
		(end 85.34 110.124)
		(width 0.16)
		(layer "In5.Cu")
		(net 437)
	)
	(segment
		(start 95.749 78.648)
		(end 95.897 78.5)
		(width 0.16)
		(layer "In5.Cu")
		(net 437)
	)
	(segment
		(start 96.536718 79.276)
		(end 96.061718 79.276)
		(width 0.16)
		(layer "In5.Cu")
		(net 437)
	)
	(segment
		(start 99.974 82.713282)
		(end 96.536718 79.276)
		(width 0.16)
		(layer "In5.Cu")
		(net 437)
	)
	(segment
		(start 105.438282 95.251)
		(end 103.351 97.338282)
		(width 0.16)
		(layer "In5.Cu")
		(net 437)
	)
	(segment
		(start 97.849 95.361718)
		(end 98.849 94.361718)
		(width 0.16)
		(layer "In5.Cu")
		(net 437)
	)
	(segment
		(start 75.56 113.43)
		(end 75.56 113.21)
		(width 0.16)
		(layer "In5.Cu")
		(net 437)
	)
	(segment
		(start 103.351 97.738282)
		(end 102.438282 98.651)
		(width 0.16)
		(layer "In5.Cu")
		(net 437)
	)
	(segment
		(start 96.061718 79.276)
		(end 95.749 78.963282)
		(width 0.16)
		(layer "In5.Cu")
		(net 437)
	)
	(segment
		(start 99.974 87.736718)
		(end 99.974 82.713282)
		(width 0.16)
		(layer "In5.Cu")
		(net 437)
	)
	(segment
		(start 108.941 95.251)
		(end 105.438282 95.251)
		(width 0.16)
		(layer "In5.Cu")
		(net 437)
	)
	(segment
		(start 104.311718 102.609)
		(end 109.821718 102.609)
		(width 0.16)
		(layer "In5.Cu")
		(net 437)
	)
	(segment
		(start 101.05 105.870718)
		(end 104.311718 102.609)
		(width 0.16)
		(layer "In5.Cu")
		(net 437)
	)
	(segment
		(start 111.009 101.421718)
		(end 111.009 97.319)
		(width 0.16)
		(layer "In5.Cu")
		(net 437)
	)
	(segment
		(start 102.438282 98.651)
		(end 99.261718 98.651)
		(width 0.16)
		(layer "In5.Cu")
		(net 437)
	)
	(segment
		(start 111.009 97.319)
		(end 108.941 95.251)
		(width 0.16)
		(layer "In5.Cu")
		(net 437)
	)
	(segment
		(start 109.821718 102.609)
		(end 111.009 101.421718)
		(width 0.16)
		(layer "In5.Cu")
		(net 437)
	)
	(segment
		(start 78.791 109.979)
		(end 85.195 109.979)
		(width 0.16)
		(layer "In5.Cu")
		(net 437)
	)
	(segment
		(start 99.261718 98.651)
		(end 97.849 97.238282)
		(width 0.16)
		(layer "In5.Cu")
		(net 437)
	)
	(segment
		(start 75.56 113.21)
		(end 78.791 109.979)
		(width 0.16)
		(layer "In5.Cu")
		(net 437)
	)
	(segment
		(start 74.5 116.35)
		(end 74.5 115.885)
		(width 0.2)
		(layer "F.Cu")
		(net 439)
	)
	(segment
		(start 74.49992 118.115)
		(end 74.49992 116.35008)
		(width 0.155)
		(layer "F.Cu")
		(net 439)
	)
	(segment
		(start 74.5 115.885)
		(end 74.5 115.115)
		(width 0.155)
		(layer "F.Cu")
		(net 439)
	)
	(segment
		(start 95.4505 75.588074)
		(end 95.697823 75.340751)
		(width 0.155)
		(layer "F.Cu")
		(net 439)
	)
	(segment
		(start 74.841424 113.397151)
		(end 74.841424 113.90414)
		(width 0.155)
		(layer "F.Cu")
		(net 439)
	)
	(segment
		(start 74.49992 116.35008)
		(end 74.5 116.35)
		(width 0.155)
		(layer "F.Cu")
		(net 439)
	)
	(segment
		(start 95.697823 75.340751)
		(end 95.697823 73.418137)
		(width 0.155)
		(layer "F.Cu")
		(net 439)
	)
	(segment
		(start 95.597323 73.317637)
		(end 95.597323 72.005136)
		(width 0.155)
		(layer "F.Cu")
		(net 439)
	)
	(segment
		(start 75.1 113.05)
		(end 75.1 113.138575)
		(width 0.155)
		(layer "F.Cu")
		(net 439)
	)
	(segment
		(start 95.303 78.5)
		(end 95.4505 78.3525)
		(width 0.155)
		(layer "F.Cu")
		(net 439)
	)
	(segment
		(start 95.4505 78.3525)
		(end 95.4505 75.588074)
		(width 0.155)
		(layer "F.Cu")
		(net 439)
	)
	(segment
		(start 74.5 115.115)
		(end 74.5 114.245564)
		(width 0.155)
		(layer "F.Cu")
		(net 439)
	)
	(segment
		(start 75.1 113.138575)
		(end 74.841424 113.397151)
		(width 0.155)
		(layer "F.Cu")
		(net 439)
	)
	(segment
		(start 74.5 114.245564)
		(end 74.841424 113.90414)
		(width 0.155)
		(layer "F.Cu")
		(net 439)
	)
	(segment
		(start 95.697823 73.418137)
		(end 95.597323 73.317637)
		(width 0.155)
		(layer "F.Cu")
		(net 439)
	)
	(via
		(at 100.66 105.59)
		(size 0.45)
		(drill 0.1)
		(layers "F.Cu" "B.Cu")
		(net 439)
	)
	(via
		(at 85.34 109.536)
		(size 0.45)
		(drill 0.1)
		(layers "F.Cu" "B.Cu")
		(net 439)
	)
	(via
		(at 95.303 78.5)
		(size 0.45)
		(drill 0.1)
		(layers "F.Cu" "B.Cu")
		(net 439)
	)
	(via
		(at 75.1 113.05)
		(size 0.45)
		(drill 0.1)
		(layers "F.Cu" "B.Cu")
		(net 439)
	)
	(via
		(at 74.5 116.35)
		(size 0.45)
		(drill 0.1)
		(layers "F.Cu" "B.Cu")
		(net 439)
	)
	(segment
		(start 85.485 109.681)
		(end 85.34 109.536)
		(width 0.16)
		(layer "In3.Cu")
		(net 439)
	)
	(segment
		(start 96.828282 109.681)
		(end 85.485 109.681)
		(width 0.16)
		(layer "In3.Cu")
		(net 439)
	)
	(segment
		(start 100.66 105.59)
		(end 100.66 105.849282)
		(width 0.16)
		(layer "In3.Cu")
		(net 439)
	)
	(segment
		(start 100.66 105.849282)
		(end 96.828282 109.681)
		(width 0.16)
		(layer "In3.Cu")
		(net 439)
	)
	(segment
		(start 97.551 95.238282)
		(end 98.551 94.238282)
		(width 0.16)
		(layer "In5.Cu")
		(net 439)
	)
	(segment
		(start 108.819 95.549)
		(end 105.561718 95.549)
		(width 0.16)
		(layer "In5.Cu")
		(net 439)
	)
	(segment
		(start 110.711 97.441)
		(end 108.819 95.549)
		(width 0.16)
		(layer "In5.Cu")
		(net 439)
	)
	(segment
		(start 105.248216 101.981783)
		(end 105.354 101.981783)
		(width 0.16)
		(layer "In5.Cu")
		(net 439)
	)
	(segment
		(start 105.083608 102.146392)
		(end 105.083608 102.146391)
		(width 0.16)
		(layer "In5.Cu")
		(net 439)
	)
	(segment
		(start 105.518608 102.146391)
		(end 105.518608 102.146392)
		(width 0.16)
		(layer "In5.Cu")
		(net 439)
	)
	(segment
		(start 102.561718 98.949)
		(end 99.138282 98.949)
		(width 0.16)
		(layer "In5.Cu")
		(net 439)
	)
	(segment
		(start 103.649 97.861718)
		(end 102.561718 98.949)
		(width 0.16)
		(layer "In5.Cu")
		(net 439)
	)
	(segment
		(start 99.676 82.836718)
		(end 96.413282 79.574)
		(width 0.16)
		(layer "In5.Cu")
		(net 439)
	)
	(segment
		(start 105.561718 95.549)
		(end 103.649 97.461718)
		(width 0.16)
		(layer "In5.Cu")
		(net 439)
	)
	(segment
		(start 85.34 109.536)
		(end 85.195 109.681)
		(width 0.16)
		(layer "In5.Cu")
		(net 439)
	)
	(segment
		(start 100.66 105.59)
		(end 100.909282 105.59)
		(width 0.16)
		(layer "In5.Cu")
		(net 439)
	)
	(segment
		(start 85.195 109.681)
		(end 78.649 109.681)
		(width 0.16)
		(layer "In5.Cu")
		(net 439)
	)
	(segment
		(start 95.451 78.648)
		(end 95.303 78.5)
		(width 0.16)
		(layer "In5.Cu")
		(net 439)
	)
	(segment
		(start 109.698282 102.311)
		(end 110.711 101.298282)
		(width 0.16)
		(layer "In5.Cu")
		(net 439)
	)
	(segment
		(start 74.5 116.35)
		(end 74.5 118.65)
		(width 0.2)
		(layer "In5.Cu")
		(net 439)
	)
	(segment
		(start 78.649 109.681)
		(end 75.28 113.05)
		(width 0.16)
		(layer "In5.Cu")
		(net 439)
	)
	(segment
		(start 105.683216 102.311)
		(end 109.698282 102.311)
		(width 0.16)
		(layer "In5.Cu")
		(net 439)
	)
	(segment
		(start 97.551 97.361718)
		(end 97.551 95.238282)
		(width 0.16)
		(layer "In5.Cu")
		(net 439)
	)
	(segment
		(start 104.188282 102.311)
		(end 104.919 102.311)
		(width 0.16)
		(layer "In5.Cu")
		(net 439)
	)
	(segment
		(start 110.711 101.298282)
		(end 110.711 97.441)
		(width 0.16)
		(layer "In5.Cu")
		(net 439)
	)
	(segment
		(start 74.5 118.65)
		(end 75.14992 119.29992)
		(width 0.2)
		(layer "In5.Cu")
		(net 439)
	)
	(segment
		(start 98.551 88.738282)
		(end 99.676 87.613282)
		(width 0.16)
		(layer "In5.Cu")
		(net 439)
	)
	(segment
		(start 100.909282 105.59)
		(end 104.188282 102.311)
		(width 0.16)
		(layer "In5.Cu")
		(net 439)
	)
	(segment
		(start 96.413282 79.574)
		(end 95.938282 79.574)
		(width 0.16)
		(layer "In5.Cu")
		(net 439)
	)
	(segment
		(start 75.28 113.05)
		(end 75.1 113.05)
		(width 0.16)
		(layer "In5.Cu")
		(net 439)
	)
	(segment
		(start 95.451 79.086718)
		(end 95.451 78.648)
		(width 0.16)
		(layer "In5.Cu")
		(net 439)
	)
	(segment
		(start 99.676 87.613282)
		(end 99.676 82.836718)
		(width 0.16)
		(layer "In5.Cu")
		(net 439)
	)
	(segment
		(start 99.138282 98.949)
		(end 97.551 97.361718)
		(width 0.16)
		(layer "In5.Cu")
		(net 439)
	)
	(segment
		(start 103.649 97.461718)
		(end 103.649 97.861718)
		(width 0.16)
		(layer "In5.Cu")
		(net 439)
	)
	(segment
		(start 95.938282 79.574)
		(end 95.451 79.086718)
		(width 0.16)
		(layer "In5.Cu")
		(net 439)
	)
	(segment
		(start 98.551 94.238282)
		(end 98.551 88.738282)
		(width 0.16)
		(layer "In5.Cu")
		(net 439)
	)
	(arc
		(start 105.083608 102.146391)
		(mid 105.131821 102.029996)
		(end 105.248216 101.981783)
		(width 0.16)
		(layer "In5.Cu")
		(net 439)
	)
	(arc
		(start 105.518608 102.146392)
		(mid 105.566821 102.262787)
		(end 105.683216 102.311)
		(width 0.16)
		(layer "In5.Cu")
		(net 439)
	)
	(arc
		(start 104.919 102.311)
		(mid 105.035395 102.262787)
		(end 105.083608 102.146392)
		(width 0.16)
		(layer "In5.Cu")
		(net 439)
	)
	(arc
		(start 105.354 101.981783)
		(mid 105.470395 102.029996)
		(end 105.518608 102.146391)
		(width 0.16)
		(layer "In5.Cu")
		(net 439)
	)
	(segment
		(start 136.785 120.675)
		(end 136.8 120.69)
		(width 0.2)
		(layer "F.Cu")
		(net 440)
	)
	(segment
		(start 136.345925 120.2245)
		(end 136.345925 120.139075)
		(width 0.2)
		(layer "F.Cu")
		(net 440)
	)
	(segment
		(start 94.847323 78.898823)
		(end 94.75 78.8015)
		(width 0.15)
		(layer "F.Cu")
		(net 440)
	)
	(segment
		(start 136.345925 120.139075)
		(end 136.785 119.7)
		(width 0.2)
		(layer "F.Cu")
		(net 440)
	)
	(segment
		(start 94.847323 80.205136)
		(end 94.847323 78.898823)
		(width 0.15)
		(layer "F.Cu")
		(net 440)
	)
	(segment
		(start 136.785 119.7)
		(end 136.785 120.675)
		(width 0.2)
		(layer "F.Cu")
		(net 440)
	)
	(via
		(at 109.3 101.4)
		(size 0.45)
		(drill 0.1)
		(layers "F.Cu" "B.Cu")
		(net 440)
	)
	(via
		(at 94.75 78.8015)
		(size 0.45)
		(drill 0.1)
		(layers "F.Cu" "B.Cu")
		(net 440)
	)
	(via
		(at 136.345925 120.2245)
		(size 0.45)
		(drill 0.1)
		(layers "F.Cu" "B.Cu")
		(net 440)
	)
	(segment
		(start 105.82 96.89)
		(end 106.11 96.6)
		(width 0.15)
		(layer "In5.Cu")
		(net 440)
	)
	(segment
		(start 97.4 87.25)
		(end 97.4 94.3)
		(width 0.15)
		(layer "In5.Cu")
		(net 440)
	)
	(segment
		(start 109.1 96.6)
		(end 109.8 97.3)
		(width 0.15)
		(layer "In5.Cu")
		(net 440)
	)
	(segment
		(start 98.9 99.55)
		(end 103.59 99.55)
		(width 0.15)
		(layer "In5.Cu")
		(net 440)
	)
	(segment
		(start 109.8 97.3)
		(end 109.8 100.9)
		(width 0.15)
		(layer "In5.Cu")
		(net 440)
	)
	(segment
		(start 106.11 96.6)
		(end 109.1 96.6)
		(width 0.15)
		(layer "In5.Cu")
		(net 440)
	)
	(segment
		(start 97.6625 86.9875)
		(end 97.4 87.25)
		(width 0.15)
		(layer "In5.Cu")
		(net 440)
	)
	(segment
		(start 97.1 97.75)
		(end 98.9 99.55)
		(width 0.15)
		(layer "In5.Cu")
		(net 440)
	)
	(segment
		(start 97.6625 81.714)
		(end 97.6625 86.9875)
		(width 0.15)
		(layer "In5.Cu")
		(net 440)
	)
	(segment
		(start 97.4 94.3)
		(end 97.1 94.6)
		(width 0.15)
		(layer "In5.Cu")
		(net 440)
	)
	(segment
		(start 109.8 100.9)
		(end 109.3 101.4)
		(width 0.15)
		(layer "In5.Cu")
		(net 440)
	)
	(segment
		(start 94.75 78.8015)
		(end 97.6625 81.714)
		(width 0.15)
		(layer "In5.Cu")
		(net 440)
	)
	(segment
		(start 105.82 97.32)
		(end 105.82 96.89)
		(width 0.15)
		(layer "In5.Cu")
		(net 440)
	)
	(segment
		(start 97.1 94.6)
		(end 97.1 97.75)
		(width 0.15)
		(layer "In5.Cu")
		(net 440)
	)
	(segment
		(start 103.59 99.55)
		(end 105.82 97.32)
		(width 0.15)
		(layer "In5.Cu")
		(net 440)
	)
	(segment
		(start 136.270425 120.3)
		(end 129.5 120.3)
		(width 0.15)
		(layer "B.Cu")
		(net 440)
	)
	(segment
		(start 115.9 108.3)
		(end 115.2 107.6)
		(width 0.15)
		(layer "B.Cu")
		(net 440)
	)
	(segment
		(start 115.2 102.45)
		(end 114.885 102.135)
		(width 0.15)
		(layer "B.Cu")
		(net 440)
	)
	(segment
		(start 128.5 108.3)
		(end 115.9 108.3)
		(width 0.15)
		(layer "B.Cu")
		(net 440)
	)
	(segment
		(start 129.5 120.3)
		(end 129.2 120)
		(width 0.15)
		(layer "B.Cu")
		(net 440)
	)
	(segment
		(start 110.035 102.135)
		(end 109.3 101.4)
		(width 0.15)
		(layer "B.Cu")
		(net 440)
	)
	(segment
		(start 115.2 107.6)
		(end 115.2 102.45)
		(width 0.15)
		(layer "B.Cu")
		(net 440)
	)
	(segment
		(start 129.2 109)
		(end 128.5 108.3)
		(width 0.15)
		(layer "B.Cu")
		(net 440)
	)
	(segment
		(start 129.2 120)
		(end 129.2 109)
		(width 0.15)
		(layer "B.Cu")
		(net 440)
	)
	(segment
		(start 136.345925 120.2245)
		(end 136.270425 120.3)
		(width 0.15)
		(layer "B.Cu")
		(net 440)
	)
	(segment
		(start 114.885 102.135)
		(end 110.035 102.135)
		(width 0.15)
		(layer "B.Cu")
		(net 440)
	)
	(segment
		(start 91.508873 84.852553)
		(end 92.378053 83.983373)
		(width 0.155)
		(layer "F.Cu")
		(net 441)
	)
	(segment
		(start 92.5245 82.449058)
		(end 92.5245 83.629819)
		(width 0.155)
		(layer "F.Cu")
		(net 441)
	)
	(segment
		(start 92.746823 81.030636)
		(end 92.746823 82.040339)
		(width 0.155)
		(layer "F.Cu")
		(net 441)
	)
	(segment
		(start 92.658955 82.252471)
		(end 92.568434 82.342992)
		(width 0.155)
		(layer "F.Cu")
		(net 441)
	)
	(segment
		(start 92.847323 80.930136)
		(end 92.746823 81.030636)
		(width 0.155)
		(layer "F.Cu")
		(net 441)
	)
	(segment
		(start 90.43 85.144)
		(end 90.531066 85.042934)
		(width 0.155)
		(layer "F.Cu")
		(net 441)
	)
	(segment
		(start 90.637132 84.999)
		(end 91.155319 84.999)
		(width 0.155)
		(layer "F.Cu")
		(net 441)
	)
	(via
		(at 128.7 84.525)
		(size 0.45)
		(drill 0.1)
		(layers "F.Cu" "B.Cu")
		(net 441)
	)
	(via
		(at 90.43 85.144)
		(size 0.45)
		(drill 0.1)
		(layers "F.Cu" "B.Cu")
		(net 441)
	)
	(arc
		(start 92.378053 83.983373)
		(mid 92.48644 83.821161)
		(end 92.5245 83.629819)
		(width 0.155)
		(layer "F.Cu")
		(net 441)
	)
	(arc
		(start 92.746823 82.040339)
		(mid 92.723987 82.155144)
		(end 92.658955 82.252471)
		(width 0.155)
		(layer "F.Cu")
		(net 441)
	)
	(arc
		(start 91.155319 84.999)
		(mid 91.346661 84.96094)
		(end 91.508873 84.852553)
		(width 0.155)
		(layer "F.Cu")
		(net 441)
	)
	(arc
		(start 90.531066 85.042934)
		(mid 90.579729 85.010418)
		(end 90.637132 84.999)
		(width 0.155)
		(layer "F.Cu")
		(net 441)
	)
	(arc
		(start 92.5245 82.449058)
		(mid 92.535918 82.391655)
		(end 92.568434 82.342992)
		(width 0.155)
		(layer "F.Cu")
		(net 441)
	)
	(segment
		(start 124.641513 87.449205)
		(end 124.869206 87.221512)
		(width 0.16)
		(layer "In3.Cu")
		(net 441)
	)
	(segment
		(start 112.697447 97.058165)
		(end 117.041836 101.402554)
		(width 0.16)
		(layer "In3.Cu")
		(net 441)
	)
	(segment
		(start 117.395389 101.549)
		(end 121.454611 101.549)
		(width 0.16)
		(layer "In3.Cu")
		(net 441)
	)
	(segment
		(start 123.214611 97.341)
		(end 122.986693 97.341)
		(width 0.16)
		(layer "In3.Cu")
		(net 441)
	)
	(segment
		(start 128.605434 84.430434)
		(end 128.7 84.525)
		(width 0.16)
		(layer "In3.Cu")
		(net 441)
	)
	(segment
		(start 112.551 94.356693)
		(end 112.551 96.704611)
		(width 0.16)
		(layer "In3.Cu")
		(net 441)
	)
	(segment
		(start 122.509 96.863307)
		(end 122.509 91.016693)
		(width 0.16)
		(layer "In3.Cu")
		(net 441)
	)
	(segment
		(start 123.156693 90.369)
		(end 123.634611 90.369)
		(width 0.16)
		(layer "In3.Cu")
		(net 441)
	)
	(segment
		(start 103.440795 85.101513)
		(end 112.448488 94.109206)
		(width 0.16)
		(layer "In3.Cu")
		(net 441)
	)
	(segment
		(start 122.611513 90.769205)
		(end 122.909206 90.471512)
		(width 0.16)
		(layer "In3.Cu")
		(net 441)
	)
	(segment
		(start 123.988165 90.222553)
		(end 124.392554 89.818164)
		(width 0.16)
		(layer "In3.Cu")
		(net 441)
	)
	(segment
		(start 90.531066 85.042934)
		(end 90.43 85.144)
		(width 0.16)
		(layer "In3.Cu")
		(net 441)
	)
	(segment
		(start 122.739205 97.238487)
		(end 122.611512 97.110794)
		(width 0.16)
		(layer "In3.Cu")
		(net 441)
	)
	(segment
		(start 124.049 98.954611)
		(end 124.049 98.175389)
		(width 0.16)
		(layer "In3.Cu")
		(net 441)
	)
	(segment
		(start 125.116693 87.119)
		(end 125.814611 87.119)
		(width 0.16)
		(layer "In3.Cu")
		(net 441)
	)
	(segment
		(start 126.168165 86.972553)
		(end 126.932554 86.208164)
		(width 0.16)
		(layer "In3.Cu")
		(net 441)
	)
	(segment
		(start 123.902553 97.821835)
		(end 123.568164 97.487446)
		(width 0.16)
		(layer "In3.Cu")
		(net 441)
	)
	(segment
		(start 121.808165 101.402553)
		(end 123.902554 99.308164)
		(width 0.16)
		(layer "In3.Cu")
		(net 441)
	)
	(segment
		(start 127.079 85.854611)
		(end 127.079 84.976693)
		(width 0.16)
		(layer "In3.Cu")
		(net 441)
	)
	(segment
		(start 127.669193 84.3865)
		(end 128.499368 84.3865)
		(width 0.16)
		(layer "In3.Cu")
		(net 441)
	)
	(segment
		(start 103.193307 84.999)
		(end 90.637132 84.999)
		(width 0.16)
		(layer "In3.Cu")
		(net 441)
	)
	(segment
		(start 124.539 89.464611)
		(end 124.539 87.696693)
		(width 0.16)
		(layer "In3.Cu")
		(net 441)
	)
	(segment
		(start 127.181513 84.729205)
		(end 127.421706 84.489012)
		(width 0.16)
		(layer "In3.Cu")
		(net 441)
	)
	(arc
		(start 126.932554 86.208164)
		(mid 127.04094 86.045952)
		(end 127.079 85.854611)
		(width 0.16)
		(layer "In3.Cu")
		(net 441)
	)
	(arc
		(start 123.634611 90.369)
		(mid 123.825953 90.33094)
		(end 123.988165 90.222553)
		(width 0.16)
		(layer "In3.Cu")
		(net 441)
	)
	(arc
		(start 121.454611 101.549)
		(mid 121.645953 101.51094)
		(end 121.808165 101.402553)
		(width 0.16)
		(layer "In3.Cu")
		(net 441)
	)
	(arc
		(start 122.509 96.863307)
		(mid 122.535642 96.997246)
		(end 122.611512 97.110794)
		(width 0.16)
		(layer "In3.Cu")
		(net 441)
	)
	(arc
		(start 122.986693 97.341)
		(mid 122.852753 97.314358)
		(end 122.739205 97.238487)
		(width 0.16)
		(layer "In3.Cu")
		(net 441)
	)
	(arc
		(start 112.697447 97.058165)
		(mid 112.58906 96.895953)
		(end 112.551 96.704611)
		(width 0.16)
		(layer "In3.Cu")
		(net 441)
	)
	(arc
		(start 90.531066 85.042934)
		(mid 90.579729 85.010418)
		(end 90.637132 84.999)
		(width 0.16)
		(layer "In3.Cu")
		(net 441)
	)
	(arc
		(start 122.509 91.016693)
		(mid 122.535642 90.882753)
		(end 122.611513 90.769205)
		(width 0.16)
		(layer "In3.Cu")
		(net 441)
	)
	(arc
		(start 124.869206 87.221512)
		(mid 124.982754 87.145642)
		(end 125.116693 87.119)
		(width 0.16)
		(layer "In3.Cu")
		(net 441)
	)
	(arc
		(start 103.440795 85.101513)
		(mid 103.327247 85.025642)
		(end 103.193307 84.999)
		(width 0.16)
		(layer "In3.Cu")
		(net 441)
	)
	(arc
		(start 123.214611 97.341)
		(mid 123.405952 97.37906)
		(end 123.568164 97.487446)
		(width 0.16)
		(layer "In3.Cu")
		(net 441)
	)
	(arc
		(start 124.392554 89.818164)
		(mid 124.50094 89.655952)
		(end 124.539 89.464611)
		(width 0.16)
		(layer "In3.Cu")
		(net 441)
	)
	(arc
		(start 124.049 98.175389)
		(mid 124.01094 97.984047)
		(end 123.902553 97.821835)
		(width 0.16)
		(layer "In3.Cu")
		(net 441)
	)
	(arc
		(start 112.551 94.356693)
		(mid 112.524358 94.222754)
		(end 112.448488 94.109206)
		(width 0.16)
		(layer "In3.Cu")
		(net 441)
	)
	(arc
		(start 125.814611 87.119)
		(mid 126.005953 87.08094)
		(end 126.168165 86.972553)
		(width 0.16)
		(layer "In3.Cu")
		(net 441)
	)
	(arc
		(start 127.669193 84.3865)
		(mid 127.535254 84.413142)
		(end 127.421706 84.489012)
		(width 0.16)
		(layer "In3.Cu")
		(net 441)
	)
	(arc
		(start 128.605434 84.430434)
		(mid 128.556771 84.397918)
		(end 128.499368 84.3865)
		(width 0.16)
		(layer "In3.Cu")
		(net 441)
	)
	(arc
		(start 124.049 98.954611)
		(mid 124.01094 99.145952)
		(end 123.902554 99.308164)
		(width 0.16)
		(layer "In3.Cu")
		(net 441)
	)
	(arc
		(start 124.641513 87.449205)
		(mid 124.565642 87.562753)
		(end 124.539 87.696693)
		(width 0.16)
		(layer "In3.Cu")
		(net 441)
	)
	(arc
		(start 123.156693 90.369)
		(mid 123.022754 90.395642)
		(end 122.909206 90.471512)
		(width 0.16)
		(layer "In3.Cu")
		(net 441)
	)
	(arc
		(start 127.079 84.976693)
		(mid 127.105642 84.842753)
		(end 127.181513 84.729205)
		(width 0.16)
		(layer "In3.Cu")
		(net 441)
	)
	(arc
		(start 117.041836 101.402554)
		(mid 117.204048 101.51094)
		(end 117.395389 101.549)
		(width 0.16)
		(layer "In3.Cu")
		(net 441)
	)
	(segment
		(start 127.543566 84.426434)
		(end 127.22 84.75)
		(width 0.155)
		(layer "B.Cu")
		(net 441)
	)
	(segment
		(start 128.7 84.525)
		(end 128.601434 84.426434)
		(width 0.155)
		(layer "B.Cu")
		(net 441)
	)
	(segment
		(start 128.495368 84.3825)
		(end 127.649632 84.3825)
		(width 0.155)
		(layer "B.Cu")
		(net 441)
	)
	(arc
		(start 128.601434 84.426434)
		(mid 128.552771 84.393918)
		(end 128.495368 84.3825)
		(width 0.155)
		(layer "B.Cu")
		(net 441)
	)
	(arc
		(start 127.543566 84.426434)
		(mid 127.592229 84.393918)
		(end 127.649632 84.3825)
		(width 0.155)
		(layer "B.Cu")
		(net 441)
	)
	(segment
		(start 91.388544 84.550028)
		(end 91.388543 84.550028)
		(width 0.155)
		(layer "F.Cu")
		(net 442)
	)
	(segment
		(start 91.742097 83.874287)
		(end 91.742098 83.874287)
		(width 0.155)
		(layer "F.Cu")
		(net 442)
	)
	(segment
		(start 92.347323 80.930136)
		(end 92.447823 81.030636)
		(width 0.155)
		(layer "F.Cu")
		(net 442)
	)
	(segment
		(start 91.419908 83.874286)
		(end 91.388543 83.90565)
		(width 0.155)
		(layer "F.Cu")
		(net 442)
	)
	(segment
		(start 92.403889 82.084685)
		(end 92.313368 82.175206)
		(width 0.155)
		(layer "F.Cu")
		(net 442)
	)
	(segment
		(start 91.388544 84.227839)
		(end 91.388543 84.227839)
		(width 0.155)
		(layer "F.Cu")
		(net 442)
	)
	(segment
		(start 91.419908 83.874285)
		(end 91.419908 83.874286)
		(width 0.155)
		(layer "F.Cu")
		(net 442)
	)
	(segment
		(start 90.637132 84.701)
		(end 91.092599 84.701)
		(width 0.155)
		(layer "F.Cu")
		(net 442)
	)
	(segment
		(start 90.43 84.556)
		(end 90.531066 84.657066)
		(width 0.155)
		(layer "F.Cu")
		(net 442)
	)
	(segment
		(start 92.2255 82.387338)
		(end 92.2255 83.568099)
		(width 0.155)
		(layer "F.Cu")
		(net 442)
	)
	(segment
		(start 92.447823 81.030636)
		(end 92.447823 81.978619)
		(width 0.155)
		(layer "F.Cu")
		(net 442)
	)
	(segment
		(start 92.122988 83.815586)
		(end 92.064287 83.874287)
		(width 0.155)
		(layer "F.Cu")
		(net 442)
	)
	(segment
		(start 91.742098 83.874287)
		(end 91.742097 83.874286)
		(width 0.155)
		(layer "F.Cu")
		(net 442)
	)
	(segment
		(start 91.388543 84.550028)
		(end 91.340087 84.598487)
		(width 0.155)
		(layer "F.Cu")
		(net 442)
	)
	(via
		(at 90.43 84.556)
		(size 0.45)
		(drill 0.1)
		(layers "F.Cu" "B.Cu")
		(net 442)
	)
	(via
		(at 128.7 83.95)
		(size 0.45)
		(drill 0.1)
		(layers "F.Cu" "B.Cu")
		(net 442)
	)
	(arc
		(start 92.2255 83.568099)
		(mid 92.198858 83.702038)
		(end 92.122988 83.815586)
		(width 0.155)
		(layer "F.Cu")
		(net 442)
	)
	(arc
		(start 91.340087 84.598487)
		(mid 91.226539 84.674358)
		(end 91.092599 84.701)
		(width 0.155)
		(layer "F.Cu")
		(net 442)
	)
	(arc
		(start 91.388543 83.90565)
		(mid 91.321816 84.066745)
		(end 91.388544 84.227839)
		(width 0.155)
		(layer "F.Cu")
		(net 442)
	)
	(arc
		(start 92.313368 82.175206)
		(mid 92.248336 82.272533)
		(end 92.2255 82.387338)
		(width 0.155)
		(layer "F.Cu")
		(net 442)
	)
	(arc
		(start 90.531066 84.657066)
		(mid 90.579729 84.689582)
		(end 90.637132 84.701)
		(width 0.155)
		(layer "F.Cu")
		(net 442)
	)
	(arc
		(start 91.742097 83.874286)
		(mid 91.581003 83.807558)
		(end 91.419908 83.874285)
		(width 0.155)
		(layer "F.Cu")
		(net 442)
	)
	(arc
		(start 91.388543 84.227839)
		(mid 91.455271 84.388933)
		(end 91.388544 84.550028)
		(width 0.155)
		(layer "F.Cu")
		(net 442)
	)
	(arc
		(start 92.064287 83.874287)
		(mid 91.903192 83.941015)
		(end 91.742097 83.874287)
		(width 0.155)
		(layer "F.Cu")
		(net 442)
	)
	(arc
		(start 92.447823 81.978619)
		(mid 92.436405 82.036022)
		(end 92.403889 82.084685)
		(width 0.155)
		(layer "F.Cu")
		(net 442)
	)
	(segment
		(start 117.456693 101.251)
		(end 121.393307 101.251)
		(width 0.16)
		(layer "In3.Cu")
		(net 442)
	)
	(segment
		(start 123.153307 97.639)
		(end 122.925389 97.639)
		(width 0.16)
		(layer "In3.Cu")
		(net 442)
	)
	(segment
		(start 125.055389 86.821)
		(end 125.753307 86.821)
		(width 0.16)
		(layer "In3.Cu")
		(net 442)
	)
	(segment
		(start 90.637132 84.701)
		(end 103.254611 84.701)
		(width 0.16)
		(layer "In3.Cu")
		(net 442)
	)
	(segment
		(start 103.608165 84.847447)
		(end 112.702554 93.941836)
		(width 0.16)
		(layer "In3.Cu")
		(net 442)
	)
	(segment
		(start 122.357447 90.601835)
		(end 122.741836 90.217446)
		(width 0.16)
		(layer "In3.Cu")
		(net 442)
	)
	(segment
		(start 127.607889 84.0885)
		(end 128.499368 84.0885)
		(width 0.16)
		(layer "In3.Cu")
		(net 442)
	)
	(segment
		(start 122.211 96.924611)
		(end 122.211 90.955389)
		(width 0.16)
		(layer "In3.Cu")
		(net 442)
	)
	(segment
		(start 123.648487 97.989205)
		(end 123.400794 97.741512)
		(width 0.16)
		(layer "In3.Cu")
		(net 442)
	)
	(segment
		(start 126.000795 86.718487)
		(end 126.678488 86.040794)
		(width 0.16)
		(layer "In3.Cu")
		(net 442)
	)
	(segment
		(start 126.781 85.793307)
		(end 126.781 84.915389)
		(width 0.16)
		(layer "In3.Cu")
		(net 442)
	)
	(segment
		(start 112.951513 96.890795)
		(end 117.209206 101.148488)
		(width 0.16)
		(layer "In3.Cu")
		(net 442)
	)
	(segment
		(start 112.849 94.295389)
		(end 112.849 96.643307)
		(width 0.16)
		(layer "In3.Cu")
		(net 442)
	)
	(segment
		(start 122.571835 97.492553)
		(end 122.357446 97.278164)
		(width 0.16)
		(layer "In3.Cu")
		(net 442)
	)
	(segment
		(start 128.605434 84.044566)
		(end 128.7 83.95)
		(width 0.16)
		(layer "In3.Cu")
		(net 442)
	)
	(segment
		(start 123.751 98.893307)
		(end 123.751 98.236693)
		(width 0.16)
		(layer "In3.Cu")
		(net 442)
	)
	(segment
		(start 123.095389 90.071)
		(end 123.573307 90.071)
		(width 0.16)
		(layer "In3.Cu")
		(net 442)
	)
	(segment
		(start 126.927447 84.561835)
		(end 127.254336 84.234946)
		(width 0.16)
		(layer "In3.Cu")
		(net 442)
	)
	(segment
		(start 121.640795 101.148487)
		(end 123.648488 99.140794)
		(width 0.16)
		(layer "In3.Cu")
		(net 442)
	)
	(segment
		(start 123.820795 89.968487)
		(end 124.138488 89.650794)
		(width 0.16)
		(layer "In3.Cu")
		(net 442)
	)
	(segment
		(start 124.241 89.403307)
		(end 124.241 87.635389)
		(width 0.16)
		(layer "In3.Cu")
		(net 442)
	)
	(segment
		(start 90.43 84.556)
		(end 90.531066 84.657066)
		(width 0.16)
		(layer "In3.Cu")
		(net 442)
	)
	(segment
		(start 124.387447 87.281835)
		(end 124.701836 86.967446)
		(width 0.16)
		(layer "In3.Cu")
		(net 442)
	)
	(arc
		(start 90.531066 84.657066)
		(mid 90.579729 84.689582)
		(end 90.637132 84.701)
		(width 0.16)
		(layer "In3.Cu")
		(net 442)
	)
	(arc
		(start 123.648488 99.140794)
		(mid 123.724358 99.027246)
		(end 123.751 98.893307)
		(width 0.16)
		(layer "In3.Cu")
		(net 442)
	)
	(arc
		(start 123.751 98.236693)
		(mid 123.724358 98.102753)
		(end 123.648487 97.989205)
		(width 0.16)
		(layer "In3.Cu")
		(net 442)
	)
	(arc
		(start 112.849 96.643307)
		(mid 112.875642 96.777247)
		(end 112.951513 96.890795)
		(width 0.16)
		(layer "In3.Cu")
		(net 442)
	)
	(arc
		(start 117.209206 101.148488)
		(mid 117.322754 101.224358)
		(end 117.456693 101.251)
		(width 0.16)
		(layer "In3.Cu")
		(net 442)
	)
	(arc
		(start 123.400794 97.741512)
		(mid 123.287246 97.665642)
		(end 123.153307 97.639)
		(width 0.16)
		(layer "In3.Cu")
		(net 442)
	)
	(arc
		(start 122.211 90.955389)
		(mid 122.24906 90.764047)
		(end 122.357447 90.601835)
		(width 0.16)
		(layer "In3.Cu")
		(net 442)
	)
	(arc
		(start 124.138488 89.650794)
		(mid 124.214358 89.537246)
		(end 124.241 89.403307)
		(width 0.16)
		(layer "In3.Cu")
		(net 442)
	)
	(arc
		(start 128.499368 84.0885)
		(mid 128.556771 84.077082)
		(end 128.605434 84.044566)
		(width 0.16)
		(layer "In3.Cu")
		(net 442)
	)
	(arc
		(start 125.753307 86.821)
		(mid 125.887247 86.794358)
		(end 126.000795 86.718487)
		(width 0.16)
		(layer "In3.Cu")
		(net 442)
	)
	(arc
		(start 122.741836 90.217446)
		(mid 122.904048 90.10906)
		(end 123.095389 90.071)
		(width 0.16)
		(layer "In3.Cu")
		(net 442)
	)
	(arc
		(start 126.678488 86.040794)
		(mid 126.754358 85.927246)
		(end 126.781 85.793307)
		(width 0.16)
		(layer "In3.Cu")
		(net 442)
	)
	(arc
		(start 124.241 87.635389)
		(mid 124.27906 87.444047)
		(end 124.387447 87.281835)
		(width 0.16)
		(layer "In3.Cu")
		(net 442)
	)
	(arc
		(start 112.702554 93.941836)
		(mid 112.81094 94.104048)
		(end 112.849 94.295389)
		(width 0.16)
		(layer "In3.Cu")
		(net 442)
	)
	(arc
		(start 121.393307 101.251)
		(mid 121.527247 101.224358)
		(end 121.640795 101.148487)
		(width 0.16)
		(layer "In3.Cu")
		(net 442)
	)
	(arc
		(start 103.254611 84.701)
		(mid 103.445953 84.73906)
		(end 103.608165 84.847447)
		(width 0.16)
		(layer "In3.Cu")
		(net 442)
	)
	(arc
		(start 127.254336 84.234946)
		(mid 127.416548 84.12656)
		(end 127.607889 84.0885)
		(width 0.16)
		(layer "In3.Cu")
		(net 442)
	)
	(arc
		(start 126.781 84.915389)
		(mid 126.81906 84.724047)
		(end 126.927447 84.561835)
		(width 0.16)
		(layer "In3.Cu")
		(net 442)
	)
	(arc
		(start 124.701836 86.967446)
		(mid 124.864048 86.85906)
		(end 125.055389 86.821)
		(width 0.16)
		(layer "In3.Cu")
		(net 442)
	)
	(arc
		(start 123.573307 90.071)
		(mid 123.707247 90.044358)
		(end 123.820795 89.968487)
		(width 0.16)
		(layer "In3.Cu")
		(net 442)
	)
	(arc
		(start 122.925389 97.639)
		(mid 122.734047 97.60094)
		(end 122.571835 97.492553)
		(width 0.16)
		(layer "In3.Cu")
		(net 442)
	)
	(arc
		(start 122.357446 97.278164)
		(mid 122.24906 97.115952)
		(end 122.211 96.924611)
		(width 0.16)
		(layer "In3.Cu")
		(net 442)
	)
	(segment
		(start 128.7 83.95)
		(end 128.601434 84.048566)
		(width 0.155)
		(layer "B.Cu")
		(net 442)
	)
	(segment
		(start 128.495368 84.0925)
		(end 127.624632 84.0925)
		(width 0.155)
		(layer "B.Cu")
		(net 442)
	)
	(segment
		(start 127.518566 84.048566)
		(end 127.22 83.75)
		(width 0.155)
		(layer "B.Cu")
		(net 442)
	)
	(arc
		(start 127.624632 84.0925)
		(mid 127.567229 84.081082)
		(end 127.518566 84.048566)
		(width 0.155)
		(layer "B.Cu")
		(net 442)
	)
	(arc
		(start 128.601434 84.048566)
		(mid 128.552771 84.081082)
		(end 128.495368 84.0925)
		(width 0.155)
		(layer "B.Cu")
		(net 442)
	)
	(segment
		(start 89.311632 86.099794)
		(end 89.149794 86.261632)
		(width 0.155)
		(layer "F.Cu")
		(net 443)
	)
	(segment
		(start 88.034333 86.05789)
		(end 87.89211 86.05789)
		(width 0.155)
		(layer "F.Cu")
		(net 443)
	)
	(segment
		(start 88.937662 86.3495)
		(end 88.512339 86.3495)
		(width 0.155)
		(layer "F.Cu")
		(net 443)
	)
	(segment
		(start 88.300207 86.261632)
		(end 88.140399 86.101824)
		(width 0.155)
		(layer "F.Cu")
		(net 443)
	)
	(segment
		(start 91.347323 80.930136)
		(end 91.246823 81.030636)
		(width 0.155)
		(layer "F.Cu")
		(net 443)
	)
	(segment
		(start 89.3995 84.306901)
		(end 89.3995 85.887662)
		(width 0.155)
		(layer "F.Cu")
		(net 443)
	)
	(segment
		(start 91.100376 82.46105)
		(end 89.502012 84.059414)
		(width 0.155)
		(layer "F.Cu")
		(net 443)
	)
	(segment
		(start 91.246823 81.030636)
		(end 91.246823 82.107496)
		(width 0.155)
		(layer "F.Cu")
		(net 443)
	)
	(via
		(at 128.75 87.525)
		(size 0.45)
		(drill 0.1)
		(layers "F.Cu" "B.Cu")
		(net 443)
	)
	(via
		(at 87.89211 86.05789)
		(size 0.45)
		(drill 0.1)
		(layers "F.Cu" "B.Cu")
		(net 443)
	)
	(arc
		(start 89.149794 86.261632)
		(mid 89.052467 86.326664)
		(end 88.937662 86.3495)
		(width 0.155)
		(layer "F.Cu")
		(net 443)
	)
	(arc
		(start 88.512339 86.3495)
		(mid 88.397534 86.326664)
		(end 88.300207 86.261632)
		(width 0.155)
		(layer "F.Cu")
		(net 443)
	)
	(arc
		(start 89.3995 84.306901)
		(mid 89.426142 84.172962)
		(end 89.502012 84.059414)
		(width 0.155)
		(layer "F.Cu")
		(net 443)
	)
	(arc
		(start 89.311632 86.099794)
		(mid 89.376664 86.002467)
		(end 89.3995 85.887662)
		(width 0.155)
		(layer "F.Cu")
		(net 443)
	)
	(arc
		(start 88.034333 86.05789)
		(mid 88.091736 86.069308)
		(end 88.140399 86.101824)
		(width 0.155)
		(layer "F.Cu")
		(net 443)
	)
	(arc
		(start 91.100376 82.46105)
		(mid 91.208763 82.298838)
		(end 91.246823 82.107496)
		(width 0.155)
		(layer "F.Cu")
		(net 443)
	)
	(segment
		(start 88.825389 86.579)
		(end 91.623307 86.579)
		(width 0.16)
		(layer "In3.Cu")
		(net 443)
	)
	(segment
		(start 122.358165 102.702553)
		(end 125.222554 99.838164)
		(width 0.16)
		(layer "In3.Cu")
		(net 443)
	)
	(segment
		(start 127.451513 87.759205)
		(end 127.721706 87.489012)
		(width 0.16)
		(layer "In3.Cu")
		(net 443)
	)
	(segment
		(start 92.785389 87.389)
		(end 102.933307 87.389)
		(width 0.16)
		(layer "In3.Cu")
		(net 443)
	)
	(segment
		(start 125.369 99.484611)
		(end 125.369 97.685389)
		(width 0.16)
		(layer "In3.Cu")
		(net 443)
	)
	(segment
		(start 127.349 88.594611)
		(end 127.349 88.006693)
		(width 0.16)
		(layer "In3.Cu")
		(net 443)
	)
	(segment
		(start 128.655434 87.430434)
		(end 128.75 87.525)
		(width 0.16)
		(layer "In3.Cu")
		(net 443)
	)
	(segment
		(start 124.499 96.463307)
		(end 124.499 91.796693)
		(width 0.16)
		(layer "In3.Cu")
		(net 443)
	)
	(segment
		(start 124.601513 91.549205)
		(end 127.202554 88.948164)
		(width 0.16)
		(layer "In3.Cu")
		(net 443)
	)
	(segment
		(start 111.151 95.606693)
		(end 111.151 97.154611)
		(width 0.16)
		(layer "In3.Cu")
		(net 443)
	)
	(segment
		(start 87.89211 86.05789)
		(end 88.03504 86.05789)
		(width 0.16)
		(layer "In3.Cu")
		(net 443)
	)
	(segment
		(start 127.969193 87.3865)
		(end 128.549368 87.3865)
		(width 0.16)
		(layer "In3.Cu")
		(net 443)
	)
	(segment
		(start 88.141106 86.101824)
		(end 88.471836 86.432554)
		(width 0.16)
		(layer "In3.Cu")
		(net 443)
	)
	(segment
		(start 91.870795 86.681513)
		(end 92.431836 87.242554)
		(width 0.16)
		(layer "In3.Cu")
		(net 443)
	)
	(segment
		(start 103.180795 87.491513)
		(end 111.048488 95.359206)
		(width 0.16)
		(layer "In3.Cu")
		(net 443)
	)
	(segment
		(start 111.297447 97.508165)
		(end 116.491836 102.702554)
		(width 0.16)
		(layer "In3.Cu")
		(net 443)
	)
	(segment
		(start 125.222553 97.331835)
		(end 124.601512 96.710794)
		(width 0.16)
		(layer "In3.Cu")
		(net 443)
	)
	(segment
		(start 116.845389 102.849)
		(end 122.004611 102.849)
		(width 0.16)
		(layer "In3.Cu")
		(net 443)
	)
	(arc
		(start 124.499 96.463307)
		(mid 124.525642 96.597246)
		(end 124.601512 96.710794)
		(width 0.16)
		(layer "In3.Cu")
		(net 443)
	)
	(arc
		(start 125.369 97.685389)
		(mid 125.33094 97.494047)
		(end 125.222553 97.331835)
		(width 0.16)
		(layer "In3.Cu")
		(net 443)
	)
	(arc
		(start 111.151 97.154611)
		(mid 111.18906 97.345953)
		(end 111.297447 97.508165)
		(width 0.16)
		(layer "In3.Cu")
		(net 443)
	)
	(arc
		(start 91.623307 86.579)
		(mid 91.757247 86.605642)
		(end 91.870795 86.681513)
		(width 0.16)
		(layer "In3.Cu")
		(net 443)
	)
	(arc
		(start 111.151 95.606693)
		(mid 111.124358 95.472754)
		(end 111.048488 95.359206)
		(width 0.16)
		(layer "In3.Cu")
		(net 443)
	)
	(arc
		(start 102.933307 87.389)
		(mid 103.067247 87.415642)
		(end 103.180795 87.491513)
		(width 0.16)
		(layer "In3.Cu")
		(net 443)
	)
	(arc
		(start 88.825389 86.579)
		(mid 88.634048 86.54094)
		(end 88.471836 86.432554)
		(width 0.16)
		(layer "In3.Cu")
		(net 443)
	)
	(arc
		(start 122.358165 102.702553)
		(mid 122.195953 102.81094)
		(end 122.004611 102.849)
		(width 0.16)
		(layer "In3.Cu")
		(net 443)
	)
	(arc
		(start 127.721706 87.489012)
		(mid 127.835254 87.413142)
		(end 127.969193 87.3865)
		(width 0.16)
		(layer "In3.Cu")
		(net 443)
	)
	(arc
		(start 128.655434 87.430434)
		(mid 128.606771 87.397918)
		(end 128.549368 87.3865)
		(width 0.16)
		(layer "In3.Cu")
		(net 443)
	)
	(arc
		(start 116.491836 102.702554)
		(mid 116.654048 102.81094)
		(end 116.845389 102.849)
		(width 0.16)
		(layer "In3.Cu")
		(net 443)
	)
	(arc
		(start 88.03504 86.05789)
		(mid 88.092443 86.069308)
		(end 88.141106 86.101824)
		(width 0.16)
		(layer "In3.Cu")
		(net 443)
	)
	(arc
		(start 124.499 91.796693)
		(mid 124.525642 91.662753)
		(end 124.601513 91.549205)
		(width 0.16)
		(layer "In3.Cu")
		(net 443)
	)
	(arc
		(start 127.349 88.594611)
		(mid 127.31094 88.785952)
		(end 127.202554 88.948164)
		(width 0.16)
		(layer "In3.Cu")
		(net 443)
	)
	(arc
		(start 125.222554 99.838164)
		(mid 125.33094 99.675952)
		(end 125.369 99.484611)
		(width 0.16)
		(layer "In3.Cu")
		(net 443)
	)
	(arc
		(start 127.451513 87.759205)
		(mid 127.375642 87.872753)
		(end 127.349 88.006693)
		(width 0.16)
		(layer "In3.Cu")
		(net 443)
	)
	(arc
		(start 92.785389 87.389)
		(mid 92.594048 87.35094)
		(end 92.431836 87.242554)
		(width 0.16)
		(layer "In3.Cu")
		(net 443)
	)
	(segment
		(start 128.75 87.525)
		(end 128.651434 87.426434)
		(width 0.155)
		(layer "B.Cu")
		(net 443)
	)
	(segment
		(start 127.543566 87.426434)
		(end 127.22 87.75)
		(width 0.155)
		(layer "B.Cu")
		(net 443)
	)
	(segment
		(start 128.545368 87.3825)
		(end 127.649632 87.3825)
		(width 0.155)
		(layer "B.Cu")
		(net 443)
	)
	(arc
		(start 127.543566 87.426434)
		(mid 127.592229 87.393918)
		(end 127.649632 87.3825)
		(width 0.155)
		(layer "B.Cu")
		(net 443)
	)
	(arc
		(start 128.651434 87.426434)
		(mid 128.602771 87.393918)
		(end 128.545368 87.3825)
		(width 0.155)
		(layer "B.Cu")
		(net 443)
	)
	(segment
		(start 90.84531 82.293264)
		(end 89.246946 83.891628)
		(width 0.155)
		(layer "F.Cu")
		(net 444)
	)
	(segment
		(start 89.056566 85.932008)
		(end 88.982008 86.006566)
		(width 0.155)
		(layer "F.Cu")
		(net 444)
	)
	(segment
		(start 88.30789 85.784333)
		(end 88.30789 85.64211)
		(width 0.155)
		(layer "F.Cu")
		(net 444)
	)
	(segment
		(start 90.847323 80.930136)
		(end 90.947823 81.030636)
		(width 0.155)
		(layer "F.Cu")
		(net 444)
	)
	(segment
		(start 90.947823 81.030636)
		(end 90.947823 82.045776)
		(width 0.155)
		(layer "F.Cu")
		(net 444)
	)
	(segment
		(start 88.875942 86.0505)
		(end 88.574057 86.0505)
		(width 0.155)
		(layer "F.Cu")
		(net 444)
	)
	(segment
		(start 88.467991 86.006566)
		(end 88.351824 85.890399)
		(width 0.155)
		(layer "F.Cu")
		(net 444)
	)
	(segment
		(start 89.1005 84.245181)
		(end 89.1005 85.825942)
		(width 0.155)
		(layer "F.Cu")
		(net 444)
	)
	(via
		(at 88.30789 85.64211)
		(size 0.45)
		(drill 0.1)
		(layers "F.Cu" "B.Cu")
		(net 444)
	)
	(via
		(at 128.75 86.95)
		(size 0.45)
		(drill 0.1)
		(layers "F.Cu" "B.Cu")
		(net 444)
	)
	(arc
		(start 88.574057 86.0505)
		(mid 88.516654 86.039082)
		(end 88.467991 86.006566)
		(width 0.155)
		(layer "F.Cu")
		(net 444)
	)
	(arc
		(start 88.982008 86.006566)
		(mid 88.933345 86.039082)
		(end 88.875942 86.0505)
		(width 0.155)
		(layer "F.Cu")
		(net 444)
	)
	(arc
		(start 88.30789 85.784333)
		(mid 88.319308 85.841736)
		(end 88.351824 85.890399)
		(width 0.155)
		(layer "F.Cu")
		(net 444)
	)
	(arc
		(start 89.246946 83.891628)
		(mid 89.13856 84.05384)
		(end 89.1005 84.245181)
		(width 0.155)
		(layer "F.Cu")
		(net 444)
	)
	(arc
		(start 90.84531 82.293264)
		(mid 90.921181 82.179716)
		(end 90.947823 82.045776)
		(width 0.155)
		(layer "F.Cu")
		(net 444)
	)
	(arc
		(start 89.056566 85.932008)
		(mid 89.089082 85.883345)
		(end 89.1005 85.825942)
		(width 0.155)
		(layer "F.Cu")
		(net 444)
	)
	(segment
		(start 88.30789 85.78504)
		(end 88.30789 85.64211)
		(width 0.16)
		(layer "In3.Cu")
		(net 444)
	)
	(segment
		(start 127.554336 87.234946)
		(end 127.197447 87.591835)
		(width 0.16)
		(layer "In3.Cu")
		(net 444)
	)
	(segment
		(start 128.75 86.95)
		(end 128.655434 87.044566)
		(width 0.16)
		(layer "In3.Cu")
		(net 444)
	)
	(segment
		(start 124.201 94.759)
		(end 124.201 96.524611)
		(width 0.16)
		(layer "In3.Cu")
		(net 444)
	)
	(segment
		(start 91.684611 86.281)
		(end 88.886693 86.281)
		(width 0.16)
		(layer "In3.Cu")
		(net 444)
	)
	(segment
		(start 121.943307 102.551)
		(end 116.906693 102.551)
		(width 0.16)
		(layer "In3.Cu")
		(net 444)
	)
	(segment
		(start 92.599206 86.988488)
		(end 92.038165 86.427447)
		(width 0.16)
		(layer "In3.Cu")
		(net 444)
	)
	(segment
		(start 124.026 94.234)
		(end 124.023912 94.234)
		(width 0.16)
		(layer "In3.Cu")
		(net 444)
	)
	(segment
		(start 88.639206 86.178488)
		(end 88.351824 85.891106)
		(width 0.16)
		(layer "In3.Cu")
		(net 444)
	)
	(segment
		(start 124.347446 96.878164)
		(end 124.968487 97.499205)
		(width 0.16)
		(layer "In3.Cu")
		(net 444)
	)
	(segment
		(start 128.549368 87.0885)
		(end 127.907889 87.0885)
		(width 0.16)
		(layer "In3.Cu")
		(net 444)
	)
	(segment
		(start 124.201 91.735389)
		(end 124.201 94.059)
		(width 0.16)
		(layer "In3.Cu")
		(net 444)
	)
	(segment
		(start 126.948488 88.780794)
		(end 124.347447 91.381835)
		(width 0.16)
		(layer "In3.Cu")
		(net 444)
	)
	(segment
		(start 124.023912 94.584)
		(end 124.026 94.584)
		(width 0.16)
		(layer "In3.Cu")
		(net 444)
	)
	(segment
		(start 125.071 97.746693)
		(end 125.071 99.423307)
		(width 0.16)
		(layer "In3.Cu")
		(net 444)
	)
	(segment
		(start 124.968488 99.670794)
		(end 122.190795 102.448487)
		(width 0.16)
		(layer "In3.Cu")
		(net 444)
	)
	(segment
		(start 93.409 87.091)
		(end 92.846693 87.091)
		(width 0.16)
		(layer "In3.Cu")
		(net 444)
	)
	(segment
		(start 111.449 97.093307)
		(end 111.449 95.545389)
		(width 0.16)
		(layer "In3.Cu")
		(net 444)
	)
	(segment
		(start 116.659206 102.448488)
		(end 111.551513 97.340795)
		(width 0.16)
		(layer "In3.Cu")
		(net 444)
	)
	(segment
		(start 102.994611 87.091)
		(end 94.509 87.091)
		(width 0.16)
		(layer "In3.Cu")
		(net 444)
	)
	(segment
		(start 111.302554 95.191836)
		(end 103.348165 87.237447)
		(width 0.16)
		(layer "In3.Cu")
		(net 444)
	)
	(segment
		(start 94.009 86.591)
		(end 93.909 86.591)
		(width 0.16)
		(layer "In3.Cu")
		(net 444)
	)
	(segment
		(start 127.051 87.945389)
		(end 127.051 88.533307)
		(width 0.16)
		(layer "In3.Cu")
		(net 444)
	)
	(arc
		(start 111.551513 97.340795)
		(mid 111.475642 97.227247)
		(end 111.449 97.093307)
		(width 0.16)
		(layer "In3.Cu")
		(net 444)
	)
	(arc
		(start 124.347447 91.381835)
		(mid 124.23906 91.544047)
		(end 124.201 91.735389)
		(width 0.16)
		(layer "In3.Cu")
		(net 444)
	)
	(arc
		(start 127.197447 87.591835)
		(mid 127.08906 87.754047)
		(end 127.051 87.945389)
		(width 0.16)
		(layer "In3.Cu")
		(net 444)
	)
	(arc
		(start 124.201 96.524611)
		(mid 124.23906 96.715952)
		(end 124.347446 96.878164)
		(width 0.16)
		(layer "In3.Cu")
		(net 444)
	)
	(arc
		(start 88.351824 85.891106)
		(mid 88.319308 85.842443)
		(end 88.30789 85.78504)
		(width 0.16)
		(layer "In3.Cu")
		(net 444)
	)
	(arc
		(start 127.051 88.533307)
		(mid 127.024358 88.667246)
		(end 126.948488 88.780794)
		(width 0.16)
		(layer "In3.Cu")
		(net 444)
	)
	(arc
		(start 111.449 95.545389)
		(mid 111.41094 95.354048)
		(end 111.302554 95.191836)
		(width 0.16)
		(layer "In3.Cu")
		(net 444)
	)
	(arc
		(start 92.038165 86.427447)
		(mid 91.875953 86.31906)
		(end 91.684611 86.281)
		(width 0.16)
		(layer "In3.Cu")
		(net 444)
	)
	(arc
		(start 93.659 86.841)
		(mid 93.585777 87.017777)
		(end 93.409 87.091)
		(width 0.16)
		(layer "In3.Cu")
		(net 444)
	)
	(arc
		(start 127.907889 87.0885)
		(mid 127.716548 87.12656)
		(end 127.554336 87.234946)
		(width 0.16)
		(layer "In3.Cu")
		(net 444)
	)
	(arc
		(start 116.906693 102.551)
		(mid 116.772754 102.524358)
		(end 116.659206 102.448488)
		(width 0.16)
		(layer "In3.Cu")
		(net 444)
	)
	(arc
		(start 88.886693 86.281)
		(mid 88.752754 86.254358)
		(end 88.639206 86.178488)
		(width 0.16)
		(layer "In3.Cu")
		(net 444)
	)
	(arc
		(start 124.023912 94.234)
		(mid 123.900168 94.285256)
		(end 123.848912 94.409)
		(width 0.16)
		(layer "In3.Cu")
		(net 444)
	)
	(arc
		(start 93.909 86.591)
		(mid 93.732223 86.664223)
		(end 93.659 86.841)
		(width 0.16)
		(layer "In3.Cu")
		(net 444)
	)
	(arc
		(start 128.655434 87.044566)
		(mid 128.606771 87.077082)
		(end 128.549368 87.0885)
		(width 0.16)
		(layer "In3.Cu")
		(net 444)
	)
	(arc
		(start 103.348165 87.237447)
		(mid 103.185953 87.12906)
		(end 102.994611 87.091)
		(width 0.16)
		(layer "In3.Cu")
		(net 444)
	)
	(arc
		(start 124.201 94.059)
		(mid 124.149744 94.182744)
		(end 124.026 94.234)
		(width 0.16)
		(layer "In3.Cu")
		(net 444)
	)
	(arc
		(start 123.848912 94.409)
		(mid 123.900168 94.532744)
		(end 124.023912 94.584)
		(width 0.16)
		(layer "In3.Cu")
		(net 444)
	)
	(arc
		(start 125.071 99.423307)
		(mid 125.044358 99.557246)
		(end 124.968488 99.670794)
		(width 0.16)
		(layer "In3.Cu")
		(net 444)
	)
	(arc
		(start 94.259 86.841)
		(mid 94.185777 86.664223)
		(end 94.009 86.591)
		(width 0.16)
		(layer "In3.Cu")
		(net 444)
	)
	(arc
		(start 124.968487 97.499205)
		(mid 125.044358 97.612753)
		(end 125.071 97.746693)
		(width 0.16)
		(layer "In3.Cu")
		(net 444)
	)
	(arc
		(start 124.026 94.584)
		(mid 124.149744 94.635256)
		(end 124.201 94.759)
		(width 0.16)
		(layer "In3.Cu")
		(net 444)
	)
	(arc
		(start 92.846693 87.091)
		(mid 92.712754 87.064358)
		(end 92.599206 86.988488)
		(width 0.16)
		(layer "In3.Cu")
		(net 444)
	)
	(arc
		(start 94.509 87.091)
		(mid 94.332223 87.017777)
		(end 94.259 86.841)
		(width 0.16)
		(layer "In3.Cu")
		(net 444)
	)
	(arc
		(start 122.190795 102.448487)
		(mid 122.077247 102.524358)
		(end 121.943307 102.551)
		(width 0.16)
		(layer "In3.Cu")
		(net 444)
	)
	(segment
		(start 127.518566 87.048566)
		(end 127.22 86.75)
		(width 0.155)
		(layer "B.Cu")
		(net 444)
	)
	(segment
		(start 128.545368 87.0925)
		(end 127.624632 87.0925)
		(width 0.155)
		(layer "B.Cu")
		(net 444)
	)
	(segment
		(start 128.75 86.95)
		(end 128.651434 87.048566)
		(width 0.155)
		(layer "B.Cu")
		(net 444)
	)
	(arc
		(start 128.545368 87.0925)
		(mid 128.602771 87.081082)
		(end 128.651434 87.048566)
		(width 0.155)
		(layer "B.Cu")
		(net 444)
	)
	(arc
		(start 127.518566 87.048566)
		(mid 127.567229 87.081082)
		(end 127.624632 87.0925)
		(width 0.155)
		(layer "B.Cu")
		(net 444)
	)
	(segment
		(start 87.347323 80.930136)
		(end 87.246823 81.030636)
		(width 0.155)
		(layer "F.Cu")
		(net 445)
	)
	(segment
		(start 85.434333 85.55789)
		(end 85.29211 85.55789)
		(width 0.155)
		(layer "F.Cu")
		(net 445)
	)
	(segment
		(start 87.246823 81.030636)
		(end 87.246823 84.907496)
		(width 0.155)
		(layer "F.Cu")
		(net 445)
	)
	(segment
		(start 87.100376 85.26105)
		(end 86.658372 85.703054)
		(width 0.155)
		(layer "F.Cu")
		(net 445)
	)
	(segment
		(start 85.641628 85.703053)
		(end 85.540399 85.601824)
		(width 0.155)
		(layer "F.Cu")
		(net 445)
	)
	(segment
		(start 86.304819 85.8495)
		(end 85.995182 85.8495)
		(width 0.155)
		(layer "F.Cu")
		(net 445)
	)
	(via
		(at 85.29211 85.55789)
		(size 0.45)
		(drill 0.1)
		(layers "F.Cu" "B.Cu")
		(net 445)
	)
	(via
		(at 128.9 90.547)
		(size 0.45)
		(drill 0.1)
		(layers "F.Cu" "B.Cu")
		(net 445)
	)
	(arc
		(start 87.246823 84.907496)
		(mid 87.208763 85.098838)
		(end 87.100376 85.26105)
		(width 0.155)
		(layer "F.Cu")
		(net 445)
	)
	(arc
		(start 85.641628 85.703053)
		(mid 85.80384 85.81144)
		(end 85.995182 85.8495)
		(width 0.155)
		(layer "F.Cu")
		(net 445)
	)
	(arc
		(start 85.434333 85.55789)
		(mid 85.491736 85.569308)
		(end 85.540399 85.601824)
		(width 0.155)
		(layer "F.Cu")
		(net 445)
	)
	(arc
		(start 86.658372 85.703054)
		(mid 86.49616 85.81144)
		(end 86.304819 85.8495)
		(width 0.155)
		(layer "F.Cu")
		(net 445)
	)
	(segment
		(start 127.252553 100.258165)
		(end 120.808164 106.702554)
		(width 0.16)
		(layer "In3.Cu")
		(net 445)
	)
	(segment
		(start 120.454611 106.849)
		(end 117.745389 106.849)
		(width 0.16)
		(layer "In3.Cu")
		(net 445)
	)
	(segment
		(start 128.9 90.547)
		(end 128.795934 90.442934)
		(width 0.16)
		(layer "In3.Cu")
		(net 445)
	)
	(segment
		(start 109.601 98.704611)
		(end 109.601 96.056693)
		(width 0.16)
		(layer "In3.Cu")
		(net 445)
	)
	(segment
		(start 117.391835 106.702553)
		(end 109.747446 99.058164)
		(width 0.16)
		(layer "In3.Cu")
		(net 445)
	)
	(segment
		(start 127.909205 90.501513)
		(end 127.501512 90.909206)
		(width 0.16)
		(layer "In3.Cu")
		(net 445)
	)
	(segment
		(start 109.498487 95.809205)
		(end 102.640794 88.951512)
		(width 0.16)
		(layer "In3.Cu")
		(net 445)
	)
	(segment
		(start 102.393307 88.849)
		(end 88.995389 88.849)
		(width 0.16)
		(layer "In3.Cu")
		(net 445)
	)
	(segment
		(start 127.399 91.156693)
		(end 127.399 99.904611)
		(width 0.16)
		(layer "In3.Cu")
		(net 445)
	)
	(segment
		(start 128.689868 90.399)
		(end 128.156693 90.399)
		(width 0.16)
		(layer "In3.Cu")
		(net 445)
	)
	(segment
		(start 88.641835 88.702553)
		(end 85.541106 85.601824)
		(width 0.16)
		(layer "In3.Cu")
		(net 445)
	)
	(segment
		(start 85.43504 85.55789)
		(end 85.29211 85.55789)
		(width 0.16)
		(layer "In3.Cu")
		(net 445)
	)
	(arc
		(start 85.541106 85.601824)
		(mid 85.492443 85.569308)
		(end 85.43504 85.55789)
		(width 0.16)
		(layer "In3.Cu")
		(net 445)
	)
	(arc
		(start 127.909205 90.501513)
		(mid 128.022753 90.425642)
		(end 128.156693 90.399)
		(width 0.16)
		(layer "In3.Cu")
		(net 445)
	)
	(arc
		(start 102.640794 88.951512)
		(mid 102.527246 88.875642)
		(end 102.393307 88.849)
		(width 0.16)
		(layer "In3.Cu")
		(net 445)
	)
	(arc
		(start 120.808164 106.702554)
		(mid 120.645952 106.81094)
		(end 120.454611 106.849)
		(width 0.16)
		(layer "In3.Cu")
		(net 445)
	)
	(arc
		(start 109.601 96.056693)
		(mid 109.574358 95.922753)
		(end 109.498487 95.809205)
		(width 0.16)
		(layer "In3.Cu")
		(net 445)
	)
	(arc
		(start 128.795934 90.442934)
		(mid 128.747271 90.410418)
		(end 128.689868 90.399)
		(width 0.16)
		(layer "In3.Cu")
		(net 445)
	)
	(arc
		(start 109.601 98.704611)
		(mid 109.63906 98.895952)
		(end 109.747446 99.058164)
		(width 0.16)
		(layer "In3.Cu")
		(net 445)
	)
	(arc
		(start 127.501512 90.909206)
		(mid 127.425642 91.022754)
		(end 127.399 91.156693)
		(width 0.16)
		(layer "In3.Cu")
		(net 445)
	)
	(arc
		(start 88.995389 88.849)
		(mid 88.804047 88.81094)
		(end 88.641835 88.702553)
		(width 0.16)
		(layer "In3.Cu")
		(net 445)
	)
	(arc
		(start 117.745389 106.849)
		(mid 117.554047 106.81094)
		(end 117.391835 106.702553)
		(width 0.16)
		(layer "In3.Cu")
		(net 445)
	)
	(arc
		(start 127.252553 100.258165)
		(mid 127.36094 100.095953)
		(end 127.399 99.904611)
		(width 0.16)
		(layer "In3.Cu")
		(net 445)
	)
	(segment
		(start 127.632632 90.3995)
		(end 128.690368 90.3995)
		(width 0.155)
		(layer "B.Cu")
		(net 445)
	)
	(segment
		(start 127.22 90.75)
		(end 127.526566 90.443434)
		(width 0.155)
		(layer "B.Cu")
		(net 445)
	)
	(segment
		(start 128.796434 90.443434)
		(end 128.9 90.547)
		(width 0.155)
		(layer "B.Cu")
		(net 445)
	)
	(arc
		(start 127.632632 90.3995)
		(mid 127.575229 90.410918)
		(end 127.526566 90.443434)
		(width 0.155)
		(layer "B.Cu")
		(net 445)
	)
	(arc
		(start 128.690368 90.3995)
		(mid 128.747771 90.410918)
		(end 128.796434 90.443434)
		(width 0.155)
		(layer "B.Cu")
		(net 445)
	)
	(segment
		(start 85.70789 85.284333)
		(end 85.70789 85.14211)
		(width 0.155)
		(layer "F.Cu")
		(net 446)
	)
	(segment
		(start 86.243099 85.5505)
		(end 86.0569 85.5505)
		(width 0.155)
		(layer "F.Cu")
		(net 446)
	)
	(segment
		(start 86.847323 80.930136)
		(end 86.947823 81.030636)
		(width 0.155)
		(layer "F.Cu")
		(net 446)
	)
	(segment
		(start 86.84531 85.093264)
		(end 86.490586 85.447988)
		(width 0.155)
		(layer "F.Cu")
		(net 446)
	)
	(segment
		(start 86.947823 81.030636)
		(end 86.947823 84.845776)
		(width 0.155)
		(layer "F.Cu")
		(net 446)
	)
	(segment
		(start 85.809412 85.447987)
		(end 85.751824 85.390399)
		(width 0.155)
		(layer "F.Cu")
		(net 446)
	)
	(via
		(at 85.70789 85.14211)
		(size 0.45)
		(drill 0.1)
		(layers "F.Cu" "B.Cu")
		(net 446)
	)
	(via
		(at 128.9 89.953)
		(size 0.45)
		(drill 0.1)
		(layers "F.Cu" "B.Cu")
		(net 446)
	)
	(arc
		(start 86.84531 85.093264)
		(mid 86.921181 84.979716)
		(end 86.947823 84.845776)
		(width 0.155)
		(layer "F.Cu")
		(net 446)
	)
	(arc
		(start 85.70789 85.284333)
		(mid 85.719308 85.341736)
		(end 85.751824 85.390399)
		(width 0.155)
		(layer "F.Cu")
		(net 446)
	)
	(arc
		(start 86.0569 85.5505)
		(mid 85.92296 85.523858)
		(end 85.809412 85.447987)
		(width 0.155)
		(layer "F.Cu")
		(net 446)
	)
	(arc
		(start 86.243099 85.5505)
		(mid 86.377038 85.523858)
		(end 86.490586 85.447988)
		(width 0.155)
		(layer "F.Cu")
		(net 446)
	)
	(segment
		(start 116.111945 104.359525)
		(end 115.932515 104.538954)
		(width 0.16)
		(layer "In3.Cu")
		(net 446)
	)
	(segment
		(start 88.809206 88.448488)
		(end 85.751824 85.391106)
		(width 0.16)
		(layer "In3.Cu")
		(net 446)
	)
	(segment
		(start 127.741836 90.247446)
		(end 127.247447 90.741835)
		(width 0.16)
		(layer "In3.Cu")
		(net 446)
	)
	(segment
		(start 128.9 89.953)
		(end 128.795934 90.057066)
		(width 0.16)
		(layer "In3.Cu")
		(net 446)
	)
	(segment
		(start 117.559206 106.448488)
		(end 116.215359 105.104641)
		(width 0.16)
		(layer "In3.Cu")
		(net 446)
	)
	(segment
		(start 85.70789 85.28504)
		(end 85.70789 85.14211)
		(width 0.16)
		(layer "In3.Cu")
		(net 446)
	)
	(segment
		(start 116.215359 104.821798)
		(end 116.394788 104.642368)
		(width 0.16)
		(layer "In3.Cu")
		(net 446)
	)
	(segment
		(start 128.689868 90.101)
		(end 128.095389 90.101)
		(width 0.16)
		(layer "In3.Cu")
		(net 446)
	)
	(segment
		(start 127.101 91.095389)
		(end 127.101 99.843307)
		(width 0.16)
		(layer "In3.Cu")
		(net 446)
	)
	(segment
		(start 126.998488 100.090794)
		(end 120.640795 106.448487)
		(width 0.16)
		(layer "In3.Cu")
		(net 446)
	)
	(segment
		(start 120.393307 106.551)
		(end 117.806693 106.551)
		(width 0.16)
		(layer "In3.Cu")
		(net 446)
	)
	(segment
		(start 116.111945 104.359524)
		(end 116.111945 104.359525)
		(width 0.16)
		(layer "In3.Cu")
		(net 446)
	)
	(segment
		(start 115.649672 104.538954)
		(end 110.001513 98.890795)
		(width 0.16)
		(layer "In3.Cu")
		(net 446)
	)
	(segment
		(start 116.215358 104.821798)
		(end 116.215359 104.821798)
		(width 0.16)
		(layer "In3.Cu")
		(net 446)
	)
	(segment
		(start 102.454611 88.551)
		(end 89.056693 88.551)
		(width 0.16)
		(layer "In3.Cu")
		(net 446)
	)
	(segment
		(start 109.752554 95.641836)
		(end 102.808165 88.697447)
		(width 0.16)
		(layer "In3.Cu")
		(net 446)
	)
	(segment
		(start 109.899 98.643307)
		(end 109.899 95.995389)
		(width 0.16)
		(layer "In3.Cu")
		(net 446)
	)
	(segment
		(start 116.394789 104.359525)
		(end 116.394788 104.359525)
		(width 0.16)
		(layer "In3.Cu")
		(net 446)
	)
	(segment
		(start 115.649672 104.538955)
		(end 115.649672 104.538954)
		(width 0.16)
		(layer "In3.Cu")
		(net 446)
	)
	(arc
		(start 110.001513 98.890795)
		(mid 109.925642 98.777247)
		(end 109.899 98.643307)
		(width 0.16)
		(layer "In3.Cu")
		(net 446)
	)
	(arc
		(start 115.932515 104.538954)
		(mid 115.791094 104.597533)
		(end 115.649672 104.538955)
		(width 0.16)
		(layer "In3.Cu")
		(net 446)
	)
	(arc
		(start 128.795934 90.057066)
		(mid 128.747271 90.089582)
		(end 128.689868 90.101)
		(width 0.16)
		(layer "In3.Cu")
		(net 446)
	)
	(arc
		(start 109.899 95.995389)
		(mid 109.86094 95.804048)
		(end 109.752554 95.641836)
		(width 0.16)
		(layer "In3.Cu")
		(net 446)
	)
	(arc
		(start 127.101 99.843307)
		(mid 127.074358 99.977246)
		(end 126.998488 100.090794)
		(width 0.16)
		(layer "In3.Cu")
		(net 446)
	)
	(arc
		(start 116.394788 104.642368)
		(mid 116.453367 104.500947)
		(end 116.394789 104.359525)
		(width 0.16)
		(layer "In3.Cu")
		(net 446)
	)
	(arc
		(start 120.640795 106.448487)
		(mid 120.527247 106.524358)
		(end 120.393307 106.551)
		(width 0.16)
		(layer "In3.Cu")
		(net 446)
	)
	(arc
		(start 116.215359 105.104641)
		(mid 116.15678 104.96322)
		(end 116.215358 104.821798)
		(width 0.16)
		(layer "In3.Cu")
		(net 446)
	)
	(arc
		(start 128.095389 90.101)
		(mid 127.904048 90.13906)
		(end 127.741836 90.247446)
		(width 0.16)
		(layer "In3.Cu")
		(net 446)
	)
	(arc
		(start 116.394788 104.359525)
		(mid 116.253367 104.300946)
		(end 116.111945 104.359524)
		(width 0.16)
		(layer "In3.Cu")
		(net 446)
	)
	(arc
		(start 85.751824 85.391106)
		(mid 85.719308 85.342443)
		(end 85.70789 85.28504)
		(width 0.16)
		(layer "In3.Cu")
		(net 446)
	)
	(arc
		(start 127.247447 90.741835)
		(mid 127.13906 90.904047)
		(end 127.101 91.095389)
		(width 0.16)
		(layer "In3.Cu")
		(net 446)
	)
	(arc
		(start 89.056693 88.551)
		(mid 88.922754 88.524358)
		(end 88.809206 88.448488)
		(width 0.16)
		(layer "In3.Cu")
		(net 446)
	)
	(arc
		(start 117.806693 106.551)
		(mid 117.672754 106.524358)
		(end 117.559206 106.448488)
		(width 0.16)
		(layer "In3.Cu")
		(net 446)
	)
	(arc
		(start 102.808165 88.697447)
		(mid 102.645953 88.58906)
		(end 102.454611 88.551)
		(width 0.16)
		(layer "In3.Cu")
		(net 446)
	)
	(segment
		(start 128.796434 90.056566)
		(end 128.9 89.953)
		(width 0.155)
		(layer "B.Cu")
		(net 446)
	)
	(segment
		(start 127.632632 90.1005)
		(end 128.690368 90.1005)
		(width 0.155)
		(layer "B.Cu")
		(net 446)
	)
	(segment
		(start 127.22 89.75)
		(end 127.526566 90.056566)
		(width 0.155)
		(layer "B.Cu")
		(net 446)
	)
	(arc
		(start 127.632632 90.1005)
		(mid 127.575229 90.089082)
		(end 127.526566 90.056566)
		(width 0.155)
		(layer "B.Cu")
		(net 446)
	)
	(arc
		(start 128.796434 90.056566)
		(mid 128.747771 90.089082)
		(end 128.690368 90.1005)
		(width 0.155)
		(layer "B.Cu")
		(net 446)
	)
	(segment
		(start 84.4495 84.654819)
		(end 84.4495 83.156901)
		(width 0.155)
		(layer "F.Cu")
		(net 447)
	)
	(segment
		(start 85.746823 81.507496)
		(end 85.746823 81.030636)
		(width 0.155)
		(layer "F.Cu")
		(net 447)
	)
	(segment
		(start 85.746823 81.030636)
		(end 85.847323 80.930136)
		(width 0.155)
		(layer "F.Cu")
		(net 447)
	)
	(segment
		(start 82.902013 86.409413)
		(end 84.303054 85.008372)
		(width 0.155)
		(layer "F.Cu")
		(net 447)
	)
	(segment
		(start 82.7995 86.893368)
		(end 82.7995 86.656901)
		(width 0.155)
		(layer "F.Cu")
		(net 447)
	)
	(segment
		(start 84.552013 82.909413)
		(end 85.600377 81.861049)
		(width 0.155)
		(layer "F.Cu")
		(net 447)
	)
	(segment
		(start 82.944 87.1)
		(end 82.843434 86.999434)
		(width 0.155)
		(layer "F.Cu")
		(net 447)
	)
	(via
		(at 128.4 93.547)
		(size 0.45)
		(drill 0.1)
		(layers "F.Cu" "B.Cu")
		(net 447)
	)
	(via
		(at 82.944 87.1)
		(size 0.45)
		(drill 0.1)
		(layers "F.Cu" "B.Cu")
		(net 447)
	)
	(arc
		(start 85.746823 81.507496)
		(mid 85.708763 81.698837)
		(end 85.600377 81.861049)
		(width 0.155)
		(layer "F.Cu")
		(net 447)
	)
	(arc
		(start 84.4495 83.156901)
		(mid 84.476142 83.022961)
		(end 84.552013 82.909413)
		(width 0.155)
		(layer "F.Cu")
		(net 447)
	)
	(arc
		(start 84.4495 84.654819)
		(mid 84.41144 84.84616)
		(end 84.303054 85.008372)
		(width 0.155)
		(layer "F.Cu")
		(net 447)
	)
	(arc
		(start 82.902013 86.409413)
		(mid 82.826142 86.522961)
		(end 82.7995 86.656901)
		(width 0.155)
		(layer "F.Cu")
		(net 447)
	)
	(arc
		(start 82.7995 86.893368)
		(mid 82.810918 86.950771)
		(end 82.843434 86.999434)
		(width 0.155)
		(layer "F.Cu")
		(net 447)
	)
	(segment
		(start 90.556 93.076)
		(end 90.556 93.070363)
		(width 0.16)
		(layer "In3.Cu")
		(net 447)
	)
	(segment
		(start 128.4 93.547)
		(end 128.504066 93.442934)
		(width 0.16)
		(layer "In3.Cu")
		(net 447)
	)
	(segment
		(start 129.895325 94.206043)
		(end 129.895324 94.206042)
		(width 0.16)
		(layer "In3.Cu")
		(net 447)
	)
	(segment
		(start 82.842934 87.201066)
		(end 82.944 87.1)
		(width 0.16)
		(layer "In3.Cu")
		(net 447)
	)
	(segment
		(start 129.48991 94.328615)
		(end 129.612482 94.206042)
		(width 0.16)
		(layer "In3.Cu")
		(net 447)
	)
	(segment
		(start 90.006 93.070363)
		(end 90.006 93.076)
		(width 0.16)
		(layer "In3.Cu")
		(net 447)
	)
	(segment
		(start 106.049 99.093307)
		(end 106.049 97.245389)
		(width 0.16)
		(layer "In3.Cu")
		(net 447)
	)
	(segment
		(start 88.359206 93.248488)
		(end 82.901513 87.790795)
		(width 0.16)
		(layer "In3.Cu")
		(net 447)
	)
	(segment
		(start 129.32964 93.923202)
		(end 129.329641 93.923201)
		(width 0.16)
		(layer "In3.Cu")
		(net 447)
	)
	(segment
		(start 129.207069 94.328616)
		(end 129.207068 94.328615)
		(width 0.16)
		(layer "In3.Cu")
		(net 447)
	)
	(segment
		(start 102.154611 93.351)
		(end 90.831 93.351)
		(width 0.16)
		(layer "In3.Cu")
		(net 447)
	)
	(segment
		(start 129.489911 94.328614)
		(end 129.48991 94.328615)
		(width 0.16)
		(layer "In3.Cu")
		(net 447)
	)
	(segment
		(start 105.902554 96.891836)
		(end 102.508165 93.497447)
		(width 0.16)
		(layer "In3.Cu")
		(net 447)
	)
	(segment
		(start 89.731 93.351)
		(end 88.606693 93.351)
		(width 0.16)
		(layer "In3.Cu")
		(net 447)
	)
	(segment
		(start 130.701 95.156693)
		(end 130.701 100.443307)
		(width 0.16)
		(layer "In3.Cu")
		(net 447)
	)
	(segment
		(start 121.843307 109.301)
		(end 116.256693 109.301)
		(width 0.16)
		(layer "In3.Cu")
		(net 447)
	)
	(segment
		(start 82.799 87.543307)
		(end 82.799 87.307132)
		(width 0.16)
		(layer "In3.Cu")
		(net 447)
	)
	(segment
		(start 129.329641 93.923201)
		(end 129.207068 94.045773)
		(width 0.16)
		(layer "In3.Cu")
		(net 447)
	)
	(segment
		(start 128.610132 93.399)
		(end 128.943307 93.399)
		(width 0.16)
		(layer "In3.Cu")
		(net 447)
	)
	(segment
		(start 129.190794 93.501512)
		(end 129.329641 93.640359)
		(width 0.16)
		(layer "In3.Cu")
		(net 447)
	)
	(segment
		(start 130.598488 100.690794)
		(end 122.090795 109.198487)
		(width 0.16)
		(layer "In3.Cu")
		(net 447)
	)
	(segment
		(start 116.009206 109.198488)
		(end 106.151513 99.340795)
		(width 0.16)
		(layer "In3.Cu")
		(net 447)
	)
	(segment
		(start 129.895324 94.206042)
		(end 130.598487 94.909205)
		(width 0.16)
		(layer "In3.Cu")
		(net 447)
	)
	(arc
		(start 130.598487 94.909205)
		(mid 130.674358 95.022753)
		(end 130.701 95.156693)
		(width 0.16)
		(layer "In3.Cu")
		(net 447)
	)
	(arc
		(start 106.151513 99.340795)
		(mid 106.075642 99.227247)
		(end 106.049 99.093307)
		(width 0.16)
		(layer "In3.Cu")
		(net 447)
	)
	(arc
		(start 129.329641 93.640359)
		(mid 129.388219 93.781781)
		(end 129.32964 93.923202)
		(width 0.16)
		(layer "In3.Cu")
		(net 447)
	)
	(arc
		(start 90.006 93.076)
		(mid 89.925454 93.270454)
		(end 89.731 93.351)
		(width 0.16)
		(layer "In3.Cu")
		(net 447)
	)
	(arc
		(start 128.504066 93.442934)
		(mid 128.552729 93.410418)
		(end 128.610132 93.399)
		(width 0.16)
		(layer "In3.Cu")
		(net 447)
	)
	(arc
		(start 122.090795 109.198487)
		(mid 121.977247 109.274358)
		(end 121.843307 109.301)
		(width 0.16)
		(layer "In3.Cu")
		(net 447)
	)
	(arc
		(start 128.943307 93.399)
		(mid 129.077246 93.425642)
		(end 129.190794 93.501512)
		(width 0.16)
		(layer "In3.Cu")
		(net 447)
	)
	(arc
		(start 90.556 93.070363)
		(mid 90.475454 92.875909)
		(end 90.281 92.795363)
		(width 0.16)
		(layer "In3.Cu")
		(net 447)
	)
	(arc
		(start 90.831 93.351)
		(mid 90.636546 93.270454)
		(end 90.556 93.076)
		(width 0.16)
		(layer "In3.Cu")
		(net 447)
	)
	(arc
		(start 129.612482 94.206042)
		(mid 129.753904 94.147464)
		(end 129.895325 94.206043)
		(width 0.16)
		(layer "In3.Cu")
		(net 447)
	)
	(arc
		(start 82.799 87.307132)
		(mid 82.810418 87.249729)
		(end 82.842934 87.201066)
		(width 0.16)
		(layer "In3.Cu")
		(net 447)
	)
	(arc
		(start 106.049 97.245389)
		(mid 106.01094 97.054048)
		(end 105.902554 96.891836)
		(width 0.16)
		(layer "In3.Cu")
		(net 447)
	)
	(arc
		(start 88.606693 93.351)
		(mid 88.472754 93.324358)
		(end 88.359206 93.248488)
		(width 0.16)
		(layer "In3.Cu")
		(net 447)
	)
	(arc
		(start 102.508165 93.497447)
		(mid 102.345953 93.38906)
		(end 102.154611 93.351)
		(width 0.16)
		(layer "In3.Cu")
		(net 447)
	)
	(arc
		(start 82.901513 87.790795)
		(mid 82.825642 87.677247)
		(end 82.799 87.543307)
		(width 0.16)
		(layer "In3.Cu")
		(net 447)
	)
	(arc
		(start 116.256693 109.301)
		(mid 116.122754 109.274358)
		(end 116.009206 109.198488)
		(width 0.16)
		(layer "In3.Cu")
		(net 447)
	)
	(arc
		(start 130.701 100.443307)
		(mid 130.674358 100.577246)
		(end 130.598488 100.690794)
		(width 0.16)
		(layer "In3.Cu")
		(net 447)
	)
	(arc
		(start 129.207068 94.045773)
		(mid 129.14849 94.187195)
		(end 129.207069 94.328616)
		(width 0.16)
		(layer "In3.Cu")
		(net 447)
	)
	(arc
		(start 90.281 92.795363)
		(mid 90.086546 92.875909)
		(end 90.006 93.070363)
		(width 0.16)
		(layer "In3.Cu")
		(net 447)
	)
	(arc
		(start 129.207068 94.328615)
		(mid 129.34849 94.387193)
		(end 129.489911 94.328614)
		(width 0.16)
		(layer "In3.Cu")
		(net 447)
	)
	(segment
		(start 127.647632 93.3995)
		(end 128.190368 93.3995)
		(width 0.155)
		(layer "B.Cu")
		(net 447)
	)
	(segment
		(start 127.235 93.75)
		(end 127.541566 93.443434)
		(width 0.155)
		(layer "B.Cu")
		(net 447)
	)
	(segment
		(start 128.296434 93.443434)
		(end 128.4 93.547)
		(width 0.155)
		(layer "B.Cu")
		(net 447)
	)
	(arc
		(start 127.647632 93.3995)
		(mid 127.590229 93.410918)
		(end 127.541566 93.443434)
		(width 0.155)
		(layer "B.Cu")
		(net 447)
	)
	(arc
		(start 128.190368 93.3995)
		(mid 128.247771 93.410918)
		(end 128.296434 93.443434)
		(width 0.155)
		(layer "B.Cu")
		(net 447)
	)
	(segment
		(start 82.646947 86.241627)
		(end 84.047988 84.840586)
		(width 0.155)
		(layer "F.Cu")
		(net 448)
	)
	(segment
		(start 85.447823 81.030636)
		(end 85.347323 80.930136)
		(width 0.155)
		(layer "F.Cu")
		(net 448)
	)
	(segment
		(start 84.1505 84.593099)
		(end 84.1505 83.095181)
		(width 0.155)
		(layer "F.Cu")
		(net 448)
	)
	(segment
		(start 82.5005 86.893368)
		(end 82.5005 86.595181)
		(width 0.155)
		(layer "F.Cu")
		(net 448)
	)
	(segment
		(start 85.447823 81.445776)
		(end 85.447823 81.030636)
		(width 0.155)
		(layer "F.Cu")
		(net 448)
	)
	(segment
		(start 82.356 87.1)
		(end 82.456566 86.999434)
		(width 0.155)
		(layer "F.Cu")
		(net 448)
	)
	(segment
		(start 84.296947 82.741627)
		(end 85.345311 81.693263)
		(width 0.155)
		(layer "F.Cu")
		(net 448)
	)
	(via
		(at 82.356 87.1)
		(size 0.45)
		(drill 0.1)
		(layers "F.Cu" "B.Cu")
		(net 448)
	)
	(via
		(at 128.4 92.953)
		(size 0.45)
		(drill 0.1)
		(layers "F.Cu" "B.Cu")
		(net 448)
	)
	(arc
		(start 82.5005 86.893368)
		(mid 82.489082 86.950771)
		(end 82.456566 86.999434)
		(width 0.155)
		(layer "F.Cu")
		(net 448)
	)
	(arc
		(start 82.646947 86.241627)
		(mid 82.53856 86.403839)
		(end 82.5005 86.595181)
		(width 0.155)
		(layer "F.Cu")
		(net 448)
	)
	(arc
		(start 85.447823 81.445776)
		(mid 85.421181 81.579715)
		(end 85.345311 81.693263)
		(width 0.155)
		(layer "F.Cu")
		(net 448)
	)
	(arc
		(start 84.047988 84.840586)
		(mid 84.123858 84.727038)
		(end 84.1505 84.593099)
		(width 0.155)
		(layer "F.Cu")
		(net 448)
	)
	(arc
		(start 84.1505 83.095181)
		(mid 84.18856 82.903839)
		(end 84.296947 82.741627)
		(width 0.155)
		(layer "F.Cu")
		(net 448)
	)
	(segment
		(start 105.751 99.154611)
		(end 105.751 97.306693)
		(width 0.16)
		(layer "In3.Cu")
		(net 448)
	)
	(segment
		(start 130.852553 100.858165)
		(end 122.258164 109.452554)
		(width 0.16)
		(layer "In3.Cu")
		(net 448)
	)
	(segment
		(start 115.841835 109.452553)
		(end 105.897446 99.508164)
		(width 0.16)
		(layer "In3.Cu")
		(net 448)
	)
	(segment
		(start 82.457066 87.201066)
		(end 82.356 87.1)
		(width 0.16)
		(layer "In3.Cu")
		(net 448)
	)
	(segment
		(start 121.904611 109.599)
		(end 116.195389 109.599)
		(width 0.16)
		(layer "In3.Cu")
		(net 448)
	)
	(segment
		(start 102.093307 93.649)
		(end 88.545389 93.649)
		(width 0.16)
		(layer "In3.Cu")
		(net 448)
	)
	(segment
		(start 88.191835 93.502553)
		(end 82.647446 87.958164)
		(width 0.16)
		(layer "In3.Cu")
		(net 448)
	)
	(segment
		(start 128.610132 93.101)
		(end 129.004611 93.101)
		(width 0.16)
		(layer "In3.Cu")
		(net 448)
	)
	(segment
		(start 128.4 92.953)
		(end 128.504066 93.057066)
		(width 0.16)
		(layer "In3.Cu")
		(net 448)
	)
	(segment
		(start 82.501 87.604611)
		(end 82.501 87.307132)
		(width 0.16)
		(layer "In3.Cu")
		(net 448)
	)
	(segment
		(start 129.358165 93.247447)
		(end 130.852554 94.741836)
		(width 0.16)
		(layer "In3.Cu")
		(net 448)
	)
	(segment
		(start 105.648487 97.059205)
		(end 102.340794 93.751512)
		(width 0.16)
		(layer "In3.Cu")
		(net 448)
	)
	(segment
		(start 130.999 95.095389)
		(end 130.999 100.504611)
		(width 0.16)
		(layer "In3.Cu")
		(net 448)
	)
	(arc
		(start 88.545389 93.649)
		(mid 88.354047 93.61094)
		(end 88.191835 93.502553)
		(width 0.16)
		(layer "In3.Cu")
		(net 448)
	)
	(arc
		(start 105.751 99.154611)
		(mid 105.78906 99.345952)
		(end 105.897446 99.508164)
		(width 0.16)
		(layer "In3.Cu")
		(net 448)
	)
	(arc
		(start 130.852554 94.741836)
		(mid 130.96094 94.904048)
		(end 130.999 95.095389)
		(width 0.16)
		(layer "In3.Cu")
		(net 448)
	)
	(arc
		(start 129.004611 93.101)
		(mid 129.195953 93.13906)
		(end 129.358165 93.247447)
		(width 0.16)
		(layer "In3.Cu")
		(net 448)
	)
	(arc
		(start 82.457066 87.201066)
		(mid 82.489582 87.249729)
		(end 82.501 87.307132)
		(width 0.16)
		(layer "In3.Cu")
		(net 448)
	)
	(arc
		(start 105.751 97.306693)
		(mid 105.724358 97.172753)
		(end 105.648487 97.059205)
		(width 0.16)
		(layer "In3.Cu")
		(net 448)
	)
	(arc
		(start 128.610132 93.101)
		(mid 128.552729 93.089582)
		(end 128.504066 93.057066)
		(width 0.16)
		(layer "In3.Cu")
		(net 448)
	)
	(arc
		(start 115.841835 109.452553)
		(mid 116.004047 109.56094)
		(end 116.195389 109.599)
		(width 0.16)
		(layer "In3.Cu")
		(net 448)
	)
	(arc
		(start 82.647446 87.958164)
		(mid 82.53906 87.795952)
		(end 82.501 87.604611)
		(width 0.16)
		(layer "In3.Cu")
		(net 448)
	)
	(arc
		(start 122.258164 109.452554)
		(mid 122.095952 109.56094)
		(end 121.904611 109.599)
		(width 0.16)
		(layer "In3.Cu")
		(net 448)
	)
	(arc
		(start 102.093307 93.649)
		(mid 102.227246 93.675642)
		(end 102.340794 93.751512)
		(width 0.16)
		(layer "In3.Cu")
		(net 448)
	)
	(arc
		(start 130.852553 100.858165)
		(mid 130.96094 100.695953)
		(end 130.999 100.504611)
		(width 0.16)
		(layer "In3.Cu")
		(net 448)
	)
	(segment
		(start 128.296434 93.056566)
		(end 128.4 92.953)
		(width 0.155)
		(layer "B.Cu")
		(net 448)
	)
	(segment
		(start 127.235 92.75)
		(end 127.541566 93.056566)
		(width 0.155)
		(layer "B.Cu")
		(net 448)
	)
	(segment
		(start 127.647632 93.1005)
		(end 128.190368 93.1005)
		(width 0.155)
		(layer "B.Cu")
		(net 448)
	)
	(arc
		(start 127.541566 93.056566)
		(mid 127.590229 93.089082)
		(end 127.647632 93.1005)
		(width 0.155)
		(layer "B.Cu")
		(net 448)
	)
	(arc
		(start 128.296434 93.056566)
		(mid 128.247771 93.089082)
		(end 128.190368 93.1005)
		(width 0.155)
		(layer "B.Cu")
		(net 448)
	)
	(segment
		(start 82.347323 80.205136)
		(end 82.347323 78.892635)
		(width 0.155)
		(layer "F.Cu")
		(net 449)
	)
	(segment
		(start 84.355 99.35)
		(end 84.139961 99.35)
		(width 0.16)
		(layer "F.Cu")
		(net 449)
	)
	(segment
		(start 84.139961 99.35)
		(end 83.902 99.587961)
		(width 0.16)
		(layer "F.Cu")
		(net 449)
	)
	(segment
		(start 82.447823 78.792135)
		(end 82.447823 78.599249)
		(width 0.155)
		(layer "F.Cu")
		(net 449)
	)
	(segment
		(start 82.733 105.252)
		(end 82.385 105.6)
		(width 0.16)
		(layer "F.Cu")
		(net 449)
	)
	(segment
		(start 76.3975 77.6995)
		(end 76.25 77.847)
		(width 0.155)
		(layer "F.Cu")
		(net 449)
	)
	(segment
		(start 83.902 104.562962)
		(end 83.212962 105.252)
		(width 0.16)
		(layer "F.Cu")
		(net 449)
	)
	(segment
		(start 83.902 99.587961)
		(end 83.902 104.562962)
		(width 0.16)
		(layer "F.Cu")
		(net 449)
	)
	(segment
		(start 82.447823 78.599249)
		(end 81.548074 77.6995)
		(width 0.155)
		(layer "F.Cu")
		(net 449)
	)
	(segment
		(start 81.548074 77.6995)
		(end 76.3975 77.6995)
		(width 0.155)
		(layer "F.Cu")
		(net 449)
	)
	(segment
		(start 82.347323 78.892635)
		(end 82.447823 78.792135)
		(width 0.155)
		(layer "F.Cu")
		(net 449)
	)
	(segment
		(start 83.212962 105.252)
		(end 82.733 105.252)
		(width 0.16)
		(layer "F.Cu")
		(net 449)
	)
	(via
		(at 76.25 77.847)
		(size 0.45)
		(drill 0.1)
		(layers "F.Cu" "B.Cu")
		(net 449)
	)
	(via
		(at 84.355 99.35)
		(size 0.45)
		(drill 0.1)
		(layers "F.Cu" "B.Cu")
		(net 449)
	)
	(segment
		(start 84.355 99.160718)
		(end 84.355 99.35)
		(width 0.16)
		(layer "In3.Cu")
		(net 449)
	)
	(segment
		(start 75.411718 77.699)
		(end 75.099 78.011718)
		(width 0.16)
		(layer "In3.Cu")
		(net 449)
	)
	(segment
		(start 75.099 82.488282)
		(end 85.849 93.238282)
		(width 0.16)
		(layer "In3.Cu")
		(net 449)
	)
	(segment
		(start 75.099 79.179)
		(end 75.099 82.488282)
		(width 0.16)
		(layer "In3.Cu")
		(net 449)
	)
	(segment
		(start 75.099 78.011718)
		(end 75.099 78.379)
		(width 0.16)
		(layer "In3.Cu")
		(net 449)
	)
	(segment
		(start 85.849 97.666718)
		(end 84.355 99.160718)
		(width 0.16)
		(layer "In3.Cu")
		(net 449)
	)
	(segment
		(start 85.849 93.238282)
		(end 85.849 97.666718)
		(width 0.16)
		(layer "In3.Cu")
		(net 449)
	)
	(segment
		(start 75.300518 78.979)
		(end 75.299 78.979)
		(width 0.16)
		(layer "In3.Cu")
		(net 449)
	)
	(segment
		(start 75.299 78.579)
		(end 75.300518 78.579)
		(width 0.16)
		(layer "In3.Cu")
		(net 449)
	)
	(segment
		(start 76.25 77.847)
		(end 76.102 77.699)
		(width 0.16)
		(layer "In3.Cu")
		(net 449)
	)
	(segment
		(start 76.102 77.699)
		(end 75.411718 77.699)
		(width 0.16)
		(layer "In3.Cu")
		(net 449)
	)
	(arc
		(start 75.300518 78.579)
		(mid 75.441939 78.637579)
		(end 75.500518 78.779)
		(width 0.16)
		(layer "In3.Cu")
		(net 449)
	)
	(arc
		(start 75.099 78.379)
		(mid 75.157579 78.520421)
		(end 75.299 78.579)
		(width 0.16)
		(layer "In3.Cu")
		(net 449)
	)
	(arc
		(start 75.500518 78.779)
		(mid 75.441939 78.920421)
		(end 75.300518 78.979)
		(width 0.16)
		(layer "In3.Cu")
		(net 449)
	)
	(arc
		(start 75.299 78.979)
		(mid 75.157579 79.037579)
		(end 75.099 79.179)
		(width 0.16)
		(layer "In3.Cu")
		(net 449)
	)
	(segment
		(start 128.1505 95.454818)
		(end 128.1505 95.053077)
		(width 0.155)
		(layer "F.Cu")
		(net 450)
	)
	(segment
		(start 81.246823 81.030636)
		(end 81.246823 82.940423)
		(width 0.155)
		(layer "F.Cu")
		(net 450)
	)
	(segment
		(start 82.690667 84.46711)
		(end 82.83289 84.46711)
		(width 0.155)
		(layer "F.Cu")
		(net 450)
	)
	(segment
		(start 128.1505 95.053077)
		(end 127.946923 94.8495)
		(width 0.155)
		(layer "F.Cu")
		(net 450)
	)
	(segment
		(start 128.39211 96.10789)
		(end 128.39211 95.903535)
		(width 0.155)
		(layer "F.Cu")
		(net 450)
	)
	(segment
		(start 127.9055 94.8495)
		(end 127.555 95.2)
		(width 0.155)
		(layer "F.Cu")
		(net 450)
	)
	(segment
		(start 81.347323 80.930136)
		(end 81.246823 81.030636)
		(width 0.155)
		(layer "F.Cu")
		(net 450)
	)
	(segment
		(start 81.349336 83.187911)
		(end 82.584601 84.423176)
		(width 0.155)
		(layer "F.Cu")
		(net 450)
	)
	(segment
		(start 127.555 95.2)
		(end 127.53 95.2)
		(width 0.155)
		(layer "F.Cu")
		(net 450)
	)
	(segment
		(start 128.39211 95.903535)
		(end 128.296947 95.808372)
		(width 0.155)
		(layer "F.Cu")
		(net 450)
	)
	(segment
		(start 127.946923 94.8495)
		(end 127.9055 94.8495)
		(width 0.155)
		(layer "F.Cu")
		(net 450)
	)
	(via
		(at 82.83289 84.46711)
		(size 0.45)
		(drill 0.1)
		(layers "F.Cu" "B.Cu")
		(net 450)
	)
	(via
		(at 128.39211 96.10789)
		(size 0.45)
		(drill 0.1)
		(layers "F.Cu" "B.Cu")
		(net 450)
	)
	(arc
		(start 81.349336 83.187911)
		(mid 81.273465 83.074363)
		(end 81.246823 82.940423)
		(width 0.155)
		(layer "F.Cu")
		(net 450)
	)
	(arc
		(start 82.690667 84.46711)
		(mid 82.633264 84.455692)
		(end 82.584601 84.423176)
		(width 0.155)
		(layer "F.Cu")
		(net 450)
	)
	(arc
		(start 128.296947 95.808372)
		(mid 128.18856 95.64616)
		(end 128.1505 95.454818)
		(width 0.155)
		(layer "F.Cu")
		(net 450)
	)
	(segment
		(start 121.293307 107.851)
		(end 117.106693 107.851)
		(width 0.16)
		(layer "In3.Cu")
		(net 450)
	)
	(segment
		(start 116.859205 107.748487)
		(end 108.501512 99.390794)
		(width 0.16)
		(layer "In3.Cu")
		(net 450)
	)
	(segment
		(start 128.597172 96.10789)
		(end 129.198488 96.709206)
		(width 0.16)
		(layer "In3.Cu")
		(net 450)
	)
	(segment
		(start 102.754611 90.851)
		(end 95.909 90.851)
		(width 0.16)
		(layer "In3.Cu")
		(net 450)
	)
	(segment
		(start 129.301 98.929)
		(end 129.301 99.843307)
		(width 0.16)
		(layer "In3.Cu")
		(net 450)
	)
	(segment
		(start 129.301 96.956693)
		(end 129.301 98.079)
		(width 0.16)
		(layer "In3.Cu")
		(net 450)
	)
	(segment
		(start 108.399 99.143307)
		(end 108.399 96.495389)
		(width 0.16)
		(layer "In3.Cu")
		(net 450)
	)
	(segment
		(start 108.252553 96.141835)
		(end 103.108164 90.997446)
		(width 0.16)
		(layer "In3.Cu")
		(net 450)
	)
	(segment
		(start 94.909 90.851)
		(end 89.156693 90.851)
		(width 0.16)
		(layer "In3.Cu")
		(net 450)
	)
	(segment
		(start 88.909205 90.748487)
		(end 82.876824 84.716106)
		(width 0.16)
		(layer "In3.Cu")
		(net 450)
	)
	(segment
		(start 128.597172 96.10789)
		(end 128.39211 96.10789)
		(width 0.16)
		(layer "In3.Cu")
		(net 450)
	)
	(segment
		(start 129.198487 100.090795)
		(end 121.540794 107.748488)
		(width 0.16)
		(layer "In3.Cu")
		(net 450)
	)
	(segment
		(start 129.301 98.879)
		(end 129.301 98.929)
		(width 0.16)
		(layer "In3.Cu")
		(net 450)
	)
	(segment
		(start 129.101 98.279)
		(end 128.891807 98.279)
		(width 0.16)
		(layer "In3.Cu")
		(net 450)
	)
	(segment
		(start 82.83289 84.61004)
		(end 82.83289 84.46711)
		(width 0.16)
		(layer "In3.Cu")
		(net 450)
	)
	(segment
		(start 128.891807 98.679)
		(end 129.101 98.679)
		(width 0.16)
		(layer "In3.Cu")
		(net 450)
	)
	(arc
		(start 95.909 90.851)
		(mid 95.732223 90.777777)
		(end 95.659 90.601)
		(width 0.16)
		(layer "In3.Cu")
		(net 450)
	)
	(arc
		(start 108.399 96.495389)
		(mid 108.36094 96.304047)
		(end 108.252553 96.141835)
		(width 0.16)
		(layer "In3.Cu")
		(net 450)
	)
	(arc
		(start 129.301 99.843307)
		(mid 129.274358 99.977247)
		(end 129.198487 100.090795)
		(width 0.16)
		(layer "In3.Cu")
		(net 450)
	)
	(arc
		(start 82.876824 84.716106)
		(mid 82.844308 84.667443)
		(end 82.83289 84.61004)
		(width 0.16)
		(layer "In3.Cu")
		(net 450)
	)
	(arc
		(start 121.540794 107.748488)
		(mid 121.427246 107.824358)
		(end 121.293307 107.851)
		(width 0.16)
		(layer "In3.Cu")
		(net 450)
	)
	(arc
		(start 103.108164 90.997446)
		(mid 102.945952 90.88906)
		(end 102.754611 90.851)
		(width 0.16)
		(layer "In3.Cu")
		(net 450)
	)
	(arc
		(start 129.301 98.079)
		(mid 129.242421 98.220421)
		(end 129.101 98.279)
		(width 0.16)
		(layer "In3.Cu")
		(net 450)
	)
	(arc
		(start 89.156693 90.851)
		(mid 89.022753 90.824358)
		(end 88.909205 90.748487)
		(width 0.16)
		(layer "In3.Cu")
		(net 450)
	)
	(arc
		(start 129.198488 96.709206)
		(mid 129.274358 96.822754)
		(end 129.301 96.956693)
		(width 0.16)
		(layer "In3.Cu")
		(net 450)
	)
	(arc
		(start 95.659 90.601)
		(mid 95.585777 90.424223)
		(end 95.409 90.351)
		(width 0.16)
		(layer "In3.Cu")
		(net 450)
	)
	(arc
		(start 128.691807 98.479)
		(mid 128.750386 98.620421)
		(end 128.891807 98.679)
		(width 0.16)
		(layer "In3.Cu")
		(net 450)
	)
	(arc
		(start 128.891807 98.279)
		(mid 128.750386 98.337579)
		(end 128.691807 98.479)
		(width 0.16)
		(layer "In3.Cu")
		(net 450)
	)
	(arc
		(start 129.101 98.679)
		(mid 129.242421 98.737579)
		(end 129.301 98.879)
		(width 0.16)
		(layer "In3.Cu")
		(net 450)
	)
	(arc
		(start 108.501512 99.390794)
		(mid 108.425642 99.277246)
		(end 108.399 99.143307)
		(width 0.16)
		(layer "In3.Cu")
		(net 450)
	)
	(arc
		(start 95.159 90.601)
		(mid 95.085777 90.777777)
		(end 94.909 90.851)
		(width 0.16)
		(layer "In3.Cu")
		(net 450)
	)
	(arc
		(start 95.409 90.351)
		(mid 95.232223 90.424223)
		(end 95.159 90.601)
		(width 0.16)
		(layer "In3.Cu")
		(net 450)
	)
	(arc
		(start 117.106693 107.851)
		(mid 116.972753 107.824358)
		(end 116.859205 107.748487)
		(width 0.16)
		(layer "In3.Cu")
		(net 450)
	)
	(segment
		(start 128.603535 95.69211)
		(end 128.552013 95.640588)
		(width 0.155)
		(layer "F.Cu")
		(net 451)
	)
	(segment
		(start 81.09427 83.355695)
		(end 82.373176 84.634601)
		(width 0.155)
		(layer "F.Cu")
		(net 451)
	)
	(segment
		(start 80.947823 81.030636)
		(end 80.947823 83.002141)
		(width 0.155)
		(layer "F.Cu")
		(net 451)
	)
	(segment
		(start 127.555 94.2)
		(end 127.53 94.2)
		(width 0.155)
		(layer "F.Cu")
		(net 451)
	)
	(segment
		(start 82.41711 84.740667)
		(end 82.41711 84.88289)
		(width 0.155)
		(layer "F.Cu")
		(net 451)
	)
	(segment
		(start 128.4495 95.3931)
		(end 128.4495 94.929225)
		(width 0.155)
		(layer "F.Cu")
		(net 451)
	)
	(segment
		(start 128.80789 95.69211)
		(end 128.603535 95.69211)
		(width 0.155)
		(layer "F.Cu")
		(net 451)
	)
	(segment
		(start 127.9055 94.5505)
		(end 127.555 94.2)
		(width 0.155)
		(layer "F.Cu")
		(net 451)
	)
	(segment
		(start 128.4495 94.929225)
		(end 128.070775 94.5505)
		(width 0.155)
		(layer "F.Cu")
		(net 451)
	)
	(segment
		(start 80.847323 80.930136)
		(end 80.947823 81.030636)
		(width 0.155)
		(layer "F.Cu")
		(net 451)
	)
	(segment
		(start 128.070775 94.5505)
		(end 127.9055 94.5505)
		(width 0.155)
		(layer "F.Cu")
		(net 451)
	)
	(via
		(at 128.80789 95.69211)
		(size 0.45)
		(drill 0.1)
		(layers "F.Cu" "B.Cu")
		(net 451)
	)
	(via
		(at 82.41711 84.88289)
		(size 0.45)
		(drill 0.1)
		(layers "F.Cu" "B.Cu")
		(net 451)
	)
	(arc
		(start 81.09427 83.355695)
		(mid 80.985883 83.193483)
		(end 80.947823 83.002141)
		(width 0.155)
		(layer "F.Cu")
		(net 451)
	)
	(arc
		(start 82.373176 84.634601)
		(mid 82.405692 84.683264)
		(end 82.41711 84.740667)
		(width 0.155)
		(layer "F.Cu")
		(net 451)
	)
	(arc
		(start 128.552013 95.640588)
		(mid 128.476142 95.52704)
		(end 128.4495 95.3931)
		(width 0.155)
		(layer "F.Cu")
		(net 451)
	)
	(segment
		(start 129.599 99.904611)
		(end 129.599 96.895389)
		(width 0.16)
		(layer "In3.Cu")
		(net 451)
	)
	(segment
		(start 82.56004 84.88289)
		(end 82.41711 84.88289)
		(width 0.16)
		(layer "In3.Cu")
		(net 451)
	)
	(segment
		(start 128.80789 95.897172)
		(end 129.452554 96.541836)
		(width 0.16)
		(layer "In3.Cu")
		(net 451)
	)
	(segment
		(start 88.741835 91.002553)
		(end 82.666106 84.926824)
		(width 0.16)
		(layer "In3.Cu")
		(net 451)
	)
	(segment
		(start 129.452553 100.258165)
		(end 121.708164 108.002554)
		(width 0.16)
		(layer "In3.Cu")
		(net 451)
	)
	(segment
		(start 121.354611 108.149)
		(end 117.045389 108.149)
		(width 0.16)
		(layer "In3.Cu")
		(net 451)
	)
	(segment
		(start 116.691835 108.002553)
		(end 108.247446 99.558164)
		(width 0.16)
		(layer "In3.Cu")
		(net 451)
	)
	(segment
		(start 107.998487 96.309205)
		(end 102.940794 91.251512)
		(width 0.16)
		(layer "In3.Cu")
		(net 451)
	)
	(segment
		(start 102.693307 91.149)
		(end 89.095389 91.149)
		(width 0.16)
		(layer "In3.Cu")
		(net 451)
	)
	(segment
		(start 108.101 99.204611)
		(end 108.101 96.556693)
		(width 0.16)
		(layer "In3.Cu")
		(net 451)
	)
	(segment
		(start 128.80789 95.897172)
		(end 128.80789 95.69211)
		(width 0.16)
		(layer "In3.Cu")
		(net 451)
	)
	(arc
		(start 129.599 96.895389)
		(mid 129.56094 96.704048)
		(end 129.452554 96.541836)
		(width 0.16)
		(layer "In3.Cu")
		(net 451)
	)
	(arc
		(start 107.998487 96.309205)
		(mid 108.074358 96.422753)
		(end 108.101 96.556693)
		(width 0.16)
		(layer "In3.Cu")
		(net 451)
	)
	(arc
		(start 102.940794 91.251512)
		(mid 102.827246 91.175642)
		(end 102.693307 91.149)
		(width 0.16)
		(layer "In3.Cu")
		(net 451)
	)
	(arc
		(start 108.247446 99.558164)
		(mid 108.13906 99.395952)
		(end 108.101 99.204611)
		(width 0.16)
		(layer "In3.Cu")
		(net 451)
	)
	(arc
		(start 121.708164 108.002554)
		(mid 121.545952 108.11094)
		(end 121.354611 108.149)
		(width 0.16)
		(layer "In3.Cu")
		(net 451)
	)
	(arc
		(start 88.741835 91.002553)
		(mid 88.904047 91.11094)
		(end 89.095389 91.149)
		(width 0.16)
		(layer "In3.Cu")
		(net 451)
	)
	(arc
		(start 117.045389 108.149)
		(mid 116.854047 108.11094)
		(end 116.691835 108.002553)
		(width 0.16)
		(layer "In3.Cu")
		(net 451)
	)
	(arc
		(start 129.599 99.904611)
		(mid 129.56094 100.095953)
		(end 129.452553 100.258165)
		(width 0.16)
		(layer "In3.Cu")
		(net 451)
	)
	(arc
		(start 82.56004 84.88289)
		(mid 82.617443 84.894308)
		(end 82.666106 84.926824)
		(width 0.16)
		(layer "In3.Cu")
		(net 451)
	)
	(segment
		(start 79.847323 79.052677)
		(end 80 78.9)
		(width 0.15)
		(layer "F.Cu")
		(net 452)
	)
	(segment
		(start 79.847323 80.205136)
		(end 79.847323 79.052677)
		(width 0.15)
		(layer "F.Cu")
		(net 452)
	)
	(segment
		(start 80 78.9)
		(end 80.4 78.9)
		(width 0.15)
		(layer "F.Cu")
		(net 452)
	)
	(via
		(at 80.4 78.9)
		(size 0.45)
		(drill 0.1)
		(layers "F.Cu" "B.Cu")
		(net 452)
	)
	(segment
		(start 79.18 78.9)
		(end 77.69 77.41)
		(width 0.15)
		(layer "B.Cu")
		(net 452)
	)
	(segment
		(start 80.4 78.9)
		(end 79.18 78.9)
		(width 0.15)
		(layer "B.Cu")
		(net 452)
	)
	(segment
		(start 77.69 77.41)
		(end 77.69 75.395)
		(width 0.15)
		(layer "B.Cu")
		(net 452)
	)
	(segment
		(start 79.6 69.9)
		(end 79.597323 69.902677)
		(width 0.15)
		(layer "F.Cu")
		(net 453)
	)
	(segment
		(start 79.15 69.45)
		(end 79.6 69.9)
		(width 0.15)
		(layer "F.Cu")
		(net 453)
	)
	(segment
		(start 127 100.08)
		(end 127.53 99.55)
		(width 0.15)
		(layer "F.Cu")
		(net 453)
	)
	(segment
		(start 127.55 105.8)
		(end 127 105.25)
		(width 0.15)
		(layer "F.Cu")
		(net 453)
	)
	(segment
		(start 79.597323 69.902677)
		(end 79.597323 72.005136)
		(width 0.15)
		(layer "F.Cu")
		(net 453)
	)
	(segment
		(start 78.05 69.45)
		(end 79.15 69.45)
		(width 0.15)
		(layer "F.Cu")
		(net 453)
	)
	(segment
		(start 127 105.25)
		(end 127 100.08)
		(width 0.15)
		(layer "F.Cu")
		(net 453)
	)
	(via
		(at 78.05 69.45)
		(size 0.45)
		(drill 0.1)
		(layers "F.Cu" "B.Cu")
		(net 453)
	)
	(via
		(at 127.55 105.8)
		(size 0.45)
		(drill 0.1)
		(layers "F.Cu" "B.Cu")
		(net 453)
	)
	(segment
		(start 122.846446 108.5)
		(end 124.35 108.5)
		(width 0.125)
		(layer "In5.Cu")
		(net 453)
	)
	(segment
		(start 93.38 83.18)
		(end 93.38 96.88)
		(width 0.125)
		(layer "In5.Cu")
		(net 453)
	)
	(segment
		(start 124.35 108.5)
		(end 127.05 105.8)
		(width 0.125)
		(layer "In5.Cu")
		(net 453)
	)
	(segment
		(start 93.89 103.09)
		(end 99.75 108.95)
		(width 0.125)
		(layer "In5.Cu")
		(net 453)
	)
	(segment
		(start 99.75 108.95)
		(end 122.396446 108.95)
		(width 0.125)
		(layer "In5.Cu")
		(net 453)
	)
	(segment
		(start 76.2 79)
		(end 78.5 79)
		(width 0.125)
		(layer "In5.Cu")
		(net 453)
	)
	(segment
		(start 78.5 79)
		(end 81.65 82.15)
		(width 0.125)
		(layer "In5.Cu")
		(net 453)
	)
	(segment
		(start 127.05 105.8)
		(end 127.55 105.8)
		(width 0.125)
		(layer "In5.Cu")
		(net 453)
	)
	(segment
		(start 93.89 97.39)
		(end 93.89 103.09)
		(width 0.125)
		(layer "In5.Cu")
		(net 453)
	)
	(segment
		(start 81.65 82.15)
		(end 92.35 82.15)
		(width 0.125)
		(layer "In5.Cu")
		(net 453)
	)
	(segment
		(start 77.2 69.85)
		(end 77.2 70.65)
		(width 0.125)
		(layer "In5.Cu")
		(net 453)
	)
	(segment
		(start 93.38 96.88)
		(end 93.89 97.39)
		(width 0.125)
		(layer "In5.Cu")
		(net 453)
	)
	(segment
		(start 78.05 69.45)
		(end 77.6 69.45)
		(width 0.125)
		(layer "In5.Cu")
		(net 453)
	)
	(segment
		(start 122.396446 108.95)
		(end 122.846446 108.5)
		(width 0.125)
		(layer "In5.Cu")
		(net 453)
	)
	(segment
		(start 77.6 69.45)
		(end 77.2 69.85)
		(width 0.125)
		(layer "In5.Cu")
		(net 453)
	)
	(segment
		(start 76.07 71.78)
		(end 76.07 73.65)
		(width 0.125)
		(layer "In5.Cu")
		(net 453)
	)
	(segment
		(start 75.4 78.2)
		(end 76.2 79)
		(width 0.125)
		(layer "In5.Cu")
		(net 453)
	)
	(segment
		(start 77.2 70.65)
		(end 76.07 71.78)
		(width 0.125)
		(layer "In5.Cu")
		(net 453)
	)
	(segment
		(start 75.4 74.32)
		(end 75.4 78.2)
		(width 0.125)
		(layer "In5.Cu")
		(net 453)
	)
	(segment
		(start 92.35 82.15)
		(end 93.38 83.18)
		(width 0.125)
		(layer "In5.Cu")
		(net 453)
	)
	(segment
		(start 76.07 73.65)
		(end 75.4 74.32)
		(width 0.125)
		(layer "In5.Cu")
		(net 453)
	)
	(segment
		(start 117.4 106)
		(end 118.25 106.85)
		(width 0.125)
		(layer "B.Cu")
		(net 453)
	)
	(segment
		(start 111.6 93.4)
		(end 112.55 94.35)
		(width 0.125)
		(layer "B.Cu")
		(net 453)
	)
	(segment
		(start 112.55 94.35)
		(end 112.55 99.55)
		(width 0.125)
		(layer "B.Cu")
		(net 453)
	)
	(segment
		(start 112.55 99.55)
		(end 113.35 100.35)
		(width 0.125)
		(layer "B.Cu")
		(net 453)
	)
	(segment
		(start 126.3 106.85)
		(end 127.35 105.8)
		(width 0.125)
		(layer "B.Cu")
		(net 453)
	)
	(segment
		(start 117.4 100.8)
		(end 117.4 106)
		(width 0.125)
		(layer "B.Cu")
		(net 453)
	)
	(segment
		(start 127.55 105.65)
		(end 128.95 104.25)
		(width 0.15)
		(layer "B.Cu")
		(net 453)
	)
	(segment
		(start 116.95 100.35)
		(end 117.4 100.8)
		(width 0.125)
		(layer "B.Cu")
		(net 453)
	)
	(segment
		(start 113.35 100.35)
		(end 116.95 100.35)
		(width 0.125)
		(layer "B.Cu")
		(net 453)
	)
	(segment
		(start 118.25 106.85)
		(end 126.3 106.85)
		(width 0.125)
		(layer "B.Cu")
		(net 453)
	)
	(segment
		(start 127.35 105.8)
		(end 127.55 105.8)
		(width 0.125)
		(layer "B.Cu")
		(net 453)
	)
	(segment
		(start 111.6 92.485)
		(end 111.6 93.4)
		(width 0.125)
		(layer "B.Cu")
		(net 453)
	)
	(segment
		(start 127.55 105.8)
		(end 127.55 105.65)
		(width 0.15)
		(layer "B.Cu")
		(net 453)
	)
	(segment
		(start 128.95 104.25)
		(end 129.415 104.25)
		(width 0.15)
		(layer "B.Cu")
		(net 453)
	)
	(segment
		(start 79.84 81.52)
		(end 79.62 81.52)
		(width 0.15)
		(layer "F.Cu")
		(net 454)
	)
	(segment
		(start 79.62 81.52)
		(end 79.347323 81.247323)
		(width 0.15)
		(layer "F.Cu")
		(net 454)
	)
	(segment
		(start 79.347323 81.247323)
		(end 79.347323 80.205136)
		(width 0.15)
		(layer "F.Cu")
		(net 454)
	)
	(via
		(at 79.84 81.52)
		(size 0.45)
		(drill 0.1)
		(layers "F.Cu" "B.Cu")
		(net 454)
	)
	(via
		(at 93.324659 97.407315)
		(size 0.45)
		(drill 0.1)
		(layers "F.Cu" "B.Cu")
		(net 454)
	)
	(via
		(at 108.55 88.625)
		(size 0.45)
		(drill 0.1)
		(layers "F.Cu" "B.Cu")
		(net 454)
	)
	(via
		(at 108.9 92.15)
		(size 0.45)
		(drill 0.1)
		(layers "F.Cu" "B.Cu")
		(net 454)
	)
	(segment
		(start 93.324659 97.407315)
		(end 93.1 97.182656)
		(width 0.125)
		(layer "In5.Cu")
		(net 454)
	)
	(segment
		(start 92.2 82.4)
		(end 80.675 82.4)
		(width 0.125)
		(layer "In5.Cu")
		(net 454)
	)
	(segment
		(start 107.95 91.2)
		(end 107.95 89.225)
		(width 0.15)
		(layer "In5.Cu")
		(net 454)
	)
	(segment
		(start 93.1 97.182656)
		(end 93.1 83.3)
		(width 0.125)
		(layer "In5.Cu")
		(net 454)
	)
	(segment
		(start 93.1 83.3)
		(end 92.2 82.4)
		(width 0.125)
		(layer "In5.Cu")
		(net 454)
	)
	(segment
		(start 80.675 82.4)
		(end 79.84 81.565)
		(width 0.125)
		(layer "In5.Cu")
		(net 454)
	)
	(segment
		(start 107.95 89.225)
		(end 108.55 88.625)
		(width 0.15)
		(layer "In5.Cu")
		(net 454)
	)
	(segment
		(start 79.84 81.565)
		(end 79.84 81.52)
		(width 0.125)
		(layer "In5.Cu")
		(net 454)
	)
	(segment
		(start 108.9 92.15)
		(end 107.95 91.2)
		(width 0.15)
		(layer "In5.Cu")
		(net 454)
	)
	(segment
		(start 93.324659 96.850341)
		(end 94.25 95.925)
		(width 0.15)
		(layer "B.Cu")
		(net 454)
	)
	(segment
		(start 105.72 86.87)
		(end 106.07 86.52)
		(width 0.15)
		(layer "B.Cu")
		(net 454)
	)
	(segment
		(start 106.07 86.52)
		(end 106.07 86.18)
		(width 0.15)
		(layer "B.Cu")
		(net 454)
	)
	(segment
		(start 108.55 88.625)
		(end 108.55 87.325)
		(width 0.15)
		(layer "B.Cu")
		(net 454)
	)
	(segment
		(start 94.25 95.925)
		(end 103.025 95.925)
		(width 0.15)
		(layer "B.Cu")
		(net 454)
	)
	(segment
		(start 105.72 88.78)
		(end 105.72 86.87)
		(width 0.15)
		(layer "B.Cu")
		(net 454)
	)
	(segment
		(start 108.28 85.42)
		(end 107.8 85.9)
		(width 0.15)
		(layer "B.Cu")
		(net 454)
	)
	(segment
		(start 108.9 92.15)
		(end 109.72 92.97)
		(width 0.15)
		(layer "B.Cu")
		(net 454)
	)
	(segment
		(start 93.324659 97.407315)
		(end 93.324659 96.850341)
		(width 0.15)
		(layer "B.Cu")
		(net 454)
	)
	(segment
		(start 108.515 85.42)
		(end 108.28 85.42)
		(width 0.15)
		(layer "B.Cu")
		(net 454)
	)
	(segment
		(start 106.99 85.69)
		(end 107.2 85.9)
		(width 0.15)
		(layer "B.Cu")
		(net 454)
	)
	(segment
		(start 108.295 87.07)
		(end 107.8 87.07)
		(width 0.15)
		(layer "B.Cu")
		(net 454)
	)
	(segment
		(start 106.07 86.18)
		(end 106.56 85.69)
		(width 0.15)
		(layer "B.Cu")
		(net 454)
	)
	(segment
		(start 109.72 92.97)
		(end 110.2 92.97)
		(width 0.15)
		(layer "B.Cu")
		(net 454)
	)
	(segment
		(start 106.56 85.69)
		(end 106.99 85.69)
		(width 0.15)
		(layer "B.Cu")
		(net 454)
	)
	(segment
		(start 107.8 85.9)
		(end 107.8 87.07)
		(width 0.15)
		(layer "B.Cu")
		(net 454)
	)
	(segment
		(start 103.025 95.925)
		(end 104.3 94.65)
		(width 0.15)
		(layer "B.Cu")
		(net 454)
	)
	(segment
		(start 108.55 87.325)
		(end 108.295 87.07)
		(width 0.15)
		(layer "B.Cu")
		(net 454)
	)
	(segment
		(start 104.3 90.2)
		(end 105.72 88.78)
		(width 0.15)
		(layer "B.Cu")
		(net 454)
	)
	(segment
		(start 107.2 85.9)
		(end 107.8 85.9)
		(width 0.15)
		(layer "B.Cu")
		(net 454)
	)
	(segment
		(start 104.3 94.65)
		(end 104.3 90.2)
		(width 0.15)
		(layer "B.Cu")
		(net 454)
	)
	(segment
		(start 79.097323 70.497323)
		(end 79.097323 72.005136)
		(width 0.15)
		(layer "F.Cu")
		(net 455)
	)
	(segment
		(start 77.65 70)
		(end 78.6 70)
		(width 0.15)
		(layer "F.Cu")
		(net 455)
	)
	(segment
		(start 78.6 70)
		(end 79.097323 70.497323)
		(width 0.15)
		(layer "F.Cu")
		(net 455)
	)
	(via
		(at 93.95 96.85)
		(size 0.45)
		(drill 0.1)
		(layers "F.Cu" "B.Cu")
		(net 455)
	)
	(via
		(at 77.65 70)
		(size 0.45)
		(drill 0.1)
		(layers "F.Cu" "B.Cu")
		(net 455)
	)
	(segment
		(start 76.41 71.89)
		(end 76.41 73.71)
		(width 0.125)
		(layer "In5.Cu")
		(net 455)
	)
	(segment
		(start 76.41 73.71)
		(end 75.7 74.42)
		(width 0.125)
		(layer "In5.Cu")
		(net 455)
	)
	(segment
		(start 93.65 96.55)
		(end 93.95 96.85)
		(width 0.125)
		(layer "In5.Cu")
		(net 455)
	)
	(segment
		(start 93.65 83.05)
		(end 93.65 96.55)
		(width 0.125)
		(layer "In5.Cu")
		(net 455)
	)
	(segment
		(start 81.75 81.85)
		(end 92.45 81.85)
		(width 0.125)
		(layer "In5.Cu")
		(net 455)
	)
	(segment
		(start 92.45 81.85)
		(end 93.65 83.05)
		(width 0.125)
		(layer "In5.Cu")
		(net 455)
	)
	(segment
		(start 75.7 74.42)
		(end 75.7 78.12)
		(width 0.125)
		(layer "In5.Cu")
		(net 455)
	)
	(segment
		(start 75.7 78.12)
		(end 76.29 78.71)
		(width 0.125)
		(layer "In5.Cu")
		(net 455)
	)
	(segment
		(start 76.29 78.71)
		(end 78.61 78.71)
		(width 0.125)
		(layer "In5.Cu")
		(net 455)
	)
	(segment
		(start 77.65 70.65)
		(end 76.41 71.89)
		(width 0.125)
		(layer "In5.Cu")
		(net 455)
	)
	(segment
		(start 78.61 78.71)
		(end 81.75 81.85)
		(width 0.125)
		(layer "In5.Cu")
		(net 455)
	)
	(segment
		(start 77.65 70)
		(end 77.65 70.65)
		(width 0.125)
		(layer "In5.Cu")
		(net 455)
	)
	(segment
		(start 93.95 96.85)
		(end 94.6 96.2)
		(width 0.15)
		(layer "B.Cu")
		(net 455)
	)
	(segment
		(start 103.35 96.2)
		(end 104.7 94.85)
		(width 0.15)
		(layer "B.Cu")
		(net 455)
	)
	(segment
		(start 107.8 88.97)
		(end 107.3 88.97)
		(width 0.15)
		(layer "B.Cu")
		(net 455)
	)
	(segment
		(start 106.935 89.335)
		(end 106.4 89.335)
		(width 0.15)
		(layer "B.Cu")
		(net 455)
	)
	(segment
		(start 105.885 89.335)
		(end 106.4 89.335)
		(width 0.15)
		(layer "B.Cu")
		(net 455)
	)
	(segment
		(start 107.3 88.97)
		(end 106.935 89.335)
		(width 0.15)
		(layer "B.Cu")
		(net 455)
	)
	(segment
		(start 94.6 96.2)
		(end 103.35 96.2)
		(width 0.15)
		(layer "B.Cu")
		(net 455)
	)
	(segment
		(start 104.7 90.52)
		(end 105.885 89.335)
		(width 0.15)
		(layer "B.Cu")
		(net 455)
	)
	(segment
		(start 104.7 94.85)
		(end 104.7 90.52)
		(width 0.15)
		(layer "B.Cu")
		(net 455)
	)
	(segment
		(start 113.383858 96.6)
		(end 113.52 96.6)
		(width 0.15)
		(layer "F.Cu")
		(net 456)
	)
	(segment
		(start 113.52 96.6)
		(end 113.92 97)
		(width 0.15)
		(layer "F.Cu")
		(net 456)
	)
	(via
		(at 113.383858 96.6)
		(size 0.45)
		(drill 0.1)
		(layers "F.Cu" "B.Cu")
		(net 456)
	)
	(via
		(at 107.2 84.75)
		(size 0.45)
		(drill 0.1)
		(layers "F.Cu" "B.Cu")
		(net 456)
	)
	(segment
		(start 107.05 85.85)
		(end 107.05 85.2)
		(width 0.15)
		(layer "In5.Cu")
		(net 456)
	)
	(segment
		(start 113.383858 96.6)
		(end 112.725 96.6)
		(width 0.15)
		(layer "In5.Cu")
		(net 456)
	)
	(segment
		(start 109.0375 93.6625)
		(end 108.85 93.85)
		(width 0.15)
		(layer "In5.Cu")
		(net 456)
	)
	(segment
		(start 107.2 85.05)
		(end 107.2 84.75)
		(width 0.15)
		(layer "In5.Cu")
		(net 456)
	)
	(segment
		(start 107.05 85.2)
		(end 107.2 85.05)
		(width 0.15)
		(layer "In5.Cu")
		(net 456)
	)
	(segment
		(start 112.725 96.6)
		(end 109.7875 93.6625)
		(width 0.15)
		(layer "In5.Cu")
		(net 456)
	)
	(segment
		(start 107.47 88.655)
		(end 107.47 86.27)
		(width 0.15)
		(layer "In5.Cu")
		(net 456)
	)
	(segment
		(start 107.47 86.27)
		(end 107.05 85.85)
		(width 0.15)
		(layer "In5.Cu")
		(net 456)
	)
	(segment
		(start 109.7875 93.6625)
		(end 109.0375 93.6625)
		(width 0.15)
		(layer "In5.Cu")
		(net 456)
	)
	(segment
		(start 106.875 89.25)
		(end 107.47 88.655)
		(width 0.15)
		(layer "In5.Cu")
		(net 456)
	)
	(segment
		(start 108.85 93.85)
		(end 107.3 93.85)
		(width 0.15)
		(layer "In5.Cu")
		(net 456)
	)
	(segment
		(start 107.3 93.85)
		(end 106.875 93.425)
		(width 0.15)
		(layer "In5.Cu")
		(net 456)
	)
	(segment
		(start 106.875 93.425)
		(end 106.875 89.25)
		(width 0.15)
		(layer "In5.Cu")
		(net 456)
	)
	(segment
		(start 107.2 84.2)
		(end 107.2 84.75)
		(width 0.15)
		(layer "B.Cu")
		(net 456)
	)
	(segment
		(start 107.2 84.2)
		(end 109.067 82.333)
		(width 0.15)
		(layer "B.Cu")
		(net 456)
	)
	(segment
		(start 111.089 81.971)
		(end 111.089 82.333)
		(width 0.15)
		(layer "B.Cu")
		(net 456)
	)
	(segment
		(start 111.089 82.333)
		(end 109.067 82.333)
		(width 0.15)
		(layer "B.Cu")
		(net 456)
	)
	(segment
		(start 112.015 80.4)
		(end 112.015 81.045)
		(width 0.15)
		(layer "B.Cu")
		(net 456)
	)
	(segment
		(start 112.015 81.045)
		(end 111.089 81.971)
		(width 0.15)
		(layer "B.Cu")
		(net 456)
	)
	(segment
		(start 81.1 86.7)
		(end 82.96906 88.56906)
		(width 0.125)
		(layer "F.Cu")
		(net 457)
	)
	(segment
		(start 77.347323 81.952677)
		(end 77.125 82.175)
		(width 0.125)
		(layer "F.Cu")
		(net 457)
	)
	(segment
		(start 77.04 83.44)
		(end 80.16 83.44)
		(width 0.125)
		(layer "F.Cu")
		(net 457)
	)
	(segment
		(start 80.35 99.35)
		(end 70.625 99.35)
		(width 0.125)
		(layer "F.Cu")
		(net 457)
	)
	(segment
		(start 70.625 99.35)
		(end 70.5 99.475)
		(width 0.125)
		(layer "F.Cu")
		(net 457)
	)
	(segment
		(start 80.16 83.44)
		(end 81.1 84.38)
		(width 0.125)
		(layer "F.Cu")
		(net 457)
	)
	(segment
		(start 77.347323 80.205136)
		(end 77.347323 81.952677)
		(width 0.125)
		(layer "F.Cu")
		(net 457)
	)
	(segment
		(start 82.96906 96.73094)
		(end 80.35 99.35)
		(width 0.125)
		(layer "F.Cu")
		(net 457)
	)
	(segment
		(start 82.96906 88.56906)
		(end 82.96906 96.73094)
		(width 0.125)
		(layer "F.Cu")
		(net 457)
	)
	(segment
		(start 76.5 82.9)
		(end 77.04 83.44)
		(width 0.125)
		(layer "F.Cu")
		(net 457)
	)
	(segment
		(start 81.1 84.38)
		(end 81.1 86.7)
		(width 0.125)
		(layer "F.Cu")
		(net 457)
	)
	(segment
		(start 76.8 82.175)
		(end 76.5 82.475)
		(width 0.125)
		(layer "F.Cu")
		(net 457)
	)
	(segment
		(start 77.125 82.175)
		(end 76.8 82.175)
		(width 0.125)
		(layer "F.Cu")
		(net 457)
	)
	(segment
		(start 76.5 82.475)
		(end 76.5 82.9)
		(width 0.125)
		(layer "F.Cu")
		(net 457)
	)
	(via
		(at 41 118.2)
		(size 0.45)
		(drill 0.1)
		(layers "F.Cu" "B.Cu")
		(net 457)
	)
	(via
		(at 70.5 99.475)
		(size 0.45)
		(drill 0.1)
		(layers "F.Cu" "B.Cu")
		(net 457)
	)
	(segment
		(start 58.93 98.08)
		(end 58.41 98.6)
		(width 0.125)
		(layer "In5.Cu")
		(net 457)
	)
	(segment
		(start 41.6 119.9)
		(end 41 119.3)
		(width 0.125)
		(layer "In5.Cu")
		(net 457)
	)
	(segment
		(start 65.957347 98.08)
		(end 58.93 98.08)
		(width 0.125)
		(layer "In5.Cu")
		(net 457)
	)
	(segment
		(start 58.41 98.6)
		(end 58.41 100.78)
		(width 0.125)
		(layer "In5.Cu")
		(net 457)
	)
	(segment
		(start 47.45 118.25)
		(end 45.8 119.9)
		(width 0.125)
		(layer "In5.Cu")
		(net 457)
	)
	(segment
		(start 69.8 100)
		(end 69.5 99.7)
		(width 0.125)
		(layer "In5.Cu")
		(net 457)
	)
	(segment
		(start 69.5 97.55)
		(end 69.1375 97.1875)
		(width 0.125)
		(layer "In5.Cu")
		(net 457)
	)
	(segment
		(start 58.41 100.78)
		(end 57.18 102.01)
		(width 0.125)
		(layer "In5.Cu")
		(net 457)
	)
	(segment
		(start 45.8 119.9)
		(end 41.6 119.9)
		(width 0.125)
		(layer "In5.Cu")
		(net 457)
	)
	(segment
		(start 41 119.3)
		(end 41 118.2)
		(width 0.125)
		(layer "In5.Cu")
		(net 457)
	)
	(segment
		(start 66.849847 97.1875)
		(end 65.957347 98.08)
		(width 0.125)
		(layer "In5.Cu")
		(net 457)
	)
	(segment
		(start 70.5 99.475)
		(end 70.5 99.9)
		(width 0.125)
		(layer "In5.Cu")
		(net 457)
	)
	(segment
		(start 53.293554 102.01)
		(end 49.1 106.203554)
		(width 0.125)
		(layer "In5.Cu")
		(net 457)
	)
	(segment
		(start 49.1 115.4)
		(end 47.45 117.05)
		(width 0.125)
		(layer "In5.Cu")
		(net 457)
	)
	(segment
		(start 47.45 117.05)
		(end 47.45 118.25)
		(width 0.125)
		(layer "In5.Cu")
		(net 457)
	)
	(segment
		(start 70.4 100)
		(end 69.8 100)
		(width 0.125)
		(layer "In5.Cu")
		(net 457)
	)
	(segment
		(start 69.1375 97.1875)
		(end 66.849847 97.1875)
		(width 0.125)
		(layer "In5.Cu")
		(net 457)
	)
	(segment
		(start 57.18 102.01)
		(end 53.293554 102.01)
		(width 0.125)
		(layer "In5.Cu")
		(net 457)
	)
	(segment
		(start 69.5 99.7)
		(end 69.5 97.55)
		(width 0.125)
		(layer "In5.Cu")
		(net 457)
	)
	(segment
		(start 70.5 99.9)
		(end 70.4 100)
		(width 0.125)
		(layer "In5.Cu")
		(net 457)
	)
	(segment
		(start 49.1 106.203554)
		(end 49.1 115.4)
		(width 0.125)
		(layer "In5.Cu")
		(net 457)
	)
	(segment
		(start 41.2 118.4)
		(end 41.2 118.815)
		(width 0.15)
		(layer "B.Cu")
		(net 457)
	)
	(segment
		(start 41 118.2)
		(end 41.2 118.4)
		(width 0.15)
		(layer "B.Cu")
		(net 457)
	)
	(segment
		(start 76.86 83.73)
		(end 75.847323 82.717323)
		(width 0.125)
		(layer "F.Cu")
		(net 459)
	)
	(segment
		(start 80.14 99.06)
		(end 82.63 96.57)
		(width 0.125)
		(layer "F.Cu")
		(net 459)
	)
	(segment
		(start 80.85 84.583554)
		(end 79.996446 83.73)
		(width 0.125)
		(layer "F.Cu")
		(net 459)
	)
	(segment
		(start 75.847323 82.717323)
		(end 75.847323 80.205136)
		(width 0.125)
		(layer "F.Cu")
		(net 459)
	)
	(segment
		(start 70.720864 98.9875)
		(end 70.793364 99.06)
		(width 0.125)
		(layer "F.Cu")
		(net 459)
	)
	(segment
		(start 82.63 88.583554)
		(end 80.85 86.803553)
		(width 0.125)
		(layer "F.Cu")
		(net 459)
	)
	(segment
		(start 69.912 99.454636)
		(end 70.379136 98.9875)
		(width 0.125)
		(layer "F.Cu")
		(net 459)
	)
	(segment
		(start 79.996446 83.73)
		(end 76.86 83.73)
		(width 0.125)
		(layer "F.Cu")
		(net 459)
	)
	(segment
		(start 70.793364 99.06)
		(end 80.14 99.06)
		(width 0.125)
		(layer "F.Cu")
		(net 459)
	)
	(segment
		(start 69.912 99.475)
		(end 69.912 99.454636)
		(width 0.125)
		(layer "F.Cu")
		(net 459)
	)
	(segment
		(start 80.85 86.803553)
		(end 80.85 84.583554)
		(width 0.125)
		(layer "F.Cu")
		(net 459)
	)
	(segment
		(start 70.379136 98.9875)
		(end 70.720864 98.9875)
		(width 0.125)
		(layer "F.Cu")
		(net 459)
	)
	(segment
		(start 82.63 96.57)
		(end 82.63 88.583554)
		(width 0.125)
		(layer "F.Cu")
		(net 459)
	)
	(via
		(at 42.45 118.15)
		(size 0.45)
		(drill 0.1)
		(layers "F.Cu" "B.Cu")
		(net 459)
	)
	(via
		(at 69.912 99.475)
		(size 0.45)
		(drill 0.1)
		(layers "F.Cu" "B.Cu")
		(net 459)
	)
	(segment
		(start 48.8 115.2)
		(end 47.1 116.9)
		(width 0.125)
		(layer "In5.Cu")
		(net 459)
	)
	(segment
		(start 42.6 119.6)
		(end 42.45 119.45)
		(width 0.125)
		(layer "In5.Cu")
		(net 459)
	)
	(segment
		(start 58.16 98.496446)
		(end 58.16 100.66)
		(width 0.125)
		(layer "In5.Cu")
		(net 459)
	)
	(segment
		(start 53.19 101.76)
		(end 48.8 106.15)
		(width 0.125)
		(layer "In5.Cu")
		(net 459)
	)
	(segment
		(start 66.746294 96.9375)
		(end 65.883794 97.8)
		(width 0.125)
		(layer "In5.Cu")
		(net 459)
	)
	(segment
		(start 69.912 99.475)
		(end 70.1 99.287)
		(width 0.125)
		(layer "In5.Cu")
		(net 459)
	)
	(segment
		(start 65.883794 97.8)
		(end 58.856446 97.8)
		(width 0.125)
		(layer "In5.Cu")
		(net 459)
	)
	(segment
		(start 47.1 118.2)
		(end 45.7 119.6)
		(width 0.125)
		(layer "In5.Cu")
		(net 459)
	)
	(segment
		(start 47.1 116.9)
		(end 47.1 118.2)
		(width 0.125)
		(layer "In5.Cu")
		(net 459)
	)
	(segment
		(start 70.1 97.2)
		(end 69.8375 96.9375)
		(width 0.125)
		(layer "In5.Cu")
		(net 459)
	)
	(segment
		(start 58.856446 97.8)
		(end 58.16 98.496446)
		(width 0.125)
		(layer "In5.Cu")
		(net 459)
	)
	(segment
		(start 69.8375 96.9375)
		(end 66.746294 96.9375)
		(width 0.125)
		(layer "In5.Cu")
		(net 459)
	)
	(segment
		(start 45.7 119.6)
		(end 42.6 119.6)
		(width 0.125)
		(layer "In5.Cu")
		(net 459)
	)
	(segment
		(start 57.06 101.76)
		(end 53.19 101.76)
		(width 0.125)
		(layer "In5.Cu")
		(net 459)
	)
	(segment
		(start 70.1 99.287)
		(end 70.1 97.2)
		(width 0.125)
		(layer "In5.Cu")
		(net 459)
	)
	(segment
		(start 48.8 106.15)
		(end 48.8 115.2)
		(width 0.125)
		(layer "In5.Cu")
		(net 459)
	)
	(segment
		(start 58.16 100.66)
		(end 57.06 101.76)
		(width 0.125)
		(layer "In5.Cu")
		(net 459)
	)
	(segment
		(start 42.45 119.45)
		(end 42.45 118.15)
		(width 0.125)
		(layer "In5.Cu")
		(net 459)
	)
	(segment
		(start 42.225 118.375)
		(end 42.225 118.79)
		(width 0.15)
		(layer "B.Cu")
		(net 459)
	)
	(segment
		(start 42.45 118.15)
		(end 42.225 118.375)
		(width 0.15)
		(layer "B.Cu")
		(net 459)
	)
	(segment
		(start 148.85 101.1)
		(end 148.45 101.5)
		(width 0.15)
		(layer "F.Cu")
		(net 460)
	)
	(segment
		(start 148.85 99.825)
		(end 148.85 101.1)
		(width 0.15)
		(layer "F.Cu")
		(net 460)
	)
	(segment
		(start 148.3 99.65)
		(end 148.675 99.65)
		(width 0.15)
		(layer "F.Cu")
		(net 460)
	)
	(segment
		(start 73.6 69.45)
		(end 73.6 70.947323)
		(width 0.15)
		(layer "F.Cu")
		(net 460)
	)
	(segment
		(start 73.6 70.947323)
		(end 73.597323 70.95)
		(width 0.15)
		(layer "F.Cu")
		(net 460)
	)
	(segment
		(start 73.597323 70.95)
		(end 73.597323 72.005136)
		(width 0.15)
		(layer "F.Cu")
		(net 460)
	)
	(segment
		(start 148.675 99.65)
		(end 148.85 99.825)
		(width 0.15)
		(layer "F.Cu")
		(net 460)
	)
	(via
		(at 73.6 69.45)
		(size 0.45)
		(drill 0.1)
		(layers "F.Cu" "B.Cu")
		(net 460)
	)
	(via
		(at 148.45 101.5)
		(size 0.45)
		(drill 0.1)
		(layers "F.Cu" "B.Cu")
		(net 460)
	)
	(segment
		(start 68.6 78.642892)
		(end 68.6 72.7)
		(width 0.125)
		(layer "In3.Cu")
		(net 460)
	)
	(segment
		(start 148.15 101.8)
		(end 147.075 101.8)
		(width 0.125)
		(layer "In3.Cu")
		(net 460)
	)
	(segment
		(start 137.07 100.45)
		(end 137.07 101.95)
		(width 0.125)
		(layer "In3.Cu")
		(net 460)
	)
	(segment
		(start 135.61 102.81)
		(end 125.17 113.25)
		(width 0.125)
		(layer "In3.Cu")
		(net 460)
	)
	(segment
		(start 136.21 102.81)
		(end 135.61 102.81)
		(width 0.125)
		(layer "In3.Cu")
		(net 460)
	)
	(segment
		(start 66.65 88.43)
		(end 68.3 86.78)
		(width 0.125)
		(layer "In3.Cu")
		(net 460)
	)
	(segment
		(start 73.6 71.12)
		(end 73.6 69.45)
		(width 0.125)
		(layer "In3.Cu")
		(net 460)
	)
	(segment
		(start 137.07 101.95)
		(end 136.21 102.81)
		(width 0.125)
		(layer "In3.Cu")
		(net 460)
	)
	(segment
		(start 125.17 113.25)
		(end 108.3 113.25)
		(width 0.125)
		(layer "In3.Cu")
		(net 460)
	)
	(segment
		(start 73.14 71.58)
		(end 73.6 71.12)
		(width 0.125)
		(layer "In3.Cu")
		(net 460)
	)
	(segment
		(start 101.25 104.15)
		(end 90.65 104.15)
		(width 0.125)
		(layer "In3.Cu")
		(net 460)
	)
	(segment
		(start 146.675 100.625)
		(end 145.975 99.925)
		(width 0.125)
		(layer "In3.Cu")
		(net 460)
	)
	(segment
		(start 77.8 104)
		(end 73.04 99.24)
		(width 0.125)
		(layer "In3.Cu")
		(net 460)
	)
	(segment
		(start 148.45 101.5)
		(end 148.15 101.8)
		(width 0.125)
		(layer "In3.Cu")
		(net 460)
	)
	(segment
		(start 68.3 86.78)
		(end 68.3 78.942892)
		(width 0.125)
		(layer "In3.Cu")
		(net 460)
	)
	(segment
		(start 73.04 99.24)
		(end 73.04 98.515)
		(width 0.125)
		(layer "In3.Cu")
		(net 460)
	)
	(segment
		(start 89.6 105.2)
		(end 85.7 105.2)
		(width 0.125)
		(layer "In3.Cu")
		(net 460)
	)
	(segment
		(start 68.6 72.7)
		(end 69.72 71.58)
		(width 0.125)
		(layer "In3.Cu")
		(net 460)
	)
	(segment
		(start 69.72 71.58)
		(end 73.14 71.58)
		(width 0.125)
		(layer "In3.Cu")
		(net 460)
	)
	(segment
		(start 84.5 104)
		(end 77.8 104)
		(width 0.125)
		(layer "In3.Cu")
		(net 460)
	)
	(segment
		(start 147.075 101.8)
		(end 146.675 101.4)
		(width 0.125)
		(layer "In3.Cu")
		(net 460)
	)
	(segment
		(start 73.04 98.515)
		(end 70.3 95.775)
		(width 0.125)
		(layer "In3.Cu")
		(net 460)
	)
	(segment
		(start 106.15 109.05)
		(end 101.25 104.15)
		(width 0.125)
		(layer "In3.Cu")
		(net 460)
	)
	(segment
		(start 146.675 101.4)
		(end 146.675 100.625)
		(width 0.125)
		(layer "In3.Cu")
		(net 460)
	)
	(segment
		(start 70.3 93.507108)
		(end 68.742892 91.95)
		(width 0.125)
		(layer "In3.Cu")
		(net 460)
	)
	(segment
		(start 90.65 104.15)
		(end 89.6 105.2)
		(width 0.125)
		(layer "In3.Cu")
		(net 460)
	)
	(segment
		(start 106.15 111.1)
		(end 106.15 109.05)
		(width 0.125)
		(layer "In3.Cu")
		(net 460)
	)
	(segment
		(start 68.742892 91.95)
		(end 67.25 91.95)
		(width 0.125)
		(layer "In3.Cu")
		(net 460)
	)
	(segment
		(start 145.975 99.925)
		(end 137.595 99.925)
		(width 0.125)
		(layer "In3.Cu")
		(net 460)
	)
	(segment
		(start 108.3 113.25)
		(end 106.15 111.1)
		(width 0.125)
		(layer "In3.Cu")
		(net 460)
	)
	(segment
		(start 70.3 95.775)
		(end 70.3 93.507108)
		(width 0.125)
		(layer "In3.Cu")
		(net 460)
	)
	(segment
		(start 68.3 78.942892)
		(end 68.6 78.642892)
		(width 0.125)
		(layer "In3.Cu")
		(net 460)
	)
	(segment
		(start 85.7 105.2)
		(end 84.5 104)
		(width 0.125)
		(layer "In3.Cu")
		(net 460)
	)
	(segment
		(start 137.595 99.925)
		(end 137.07 100.45)
		(width 0.125)
		(layer "In3.Cu")
		(net 460)
	)
	(segment
		(start 66.65 91.35)
		(end 66.65 88.43)
		(width 0.125)
		(layer "In3.Cu")
		(net 460)
	)
	(segment
		(start 67.25 91.95)
		(end 66.65 91.35)
		(width 0.125)
		(layer "In3.Cu")
		(net 460)
	)
	(segment
		(start 133.75 96.9)
		(end 135.35 98.5)
		(width 0.15)
		(layer "F.Cu")
		(net 461)
	)
	(segment
		(start 132.56 94.91)
		(end 133.51 94.91)
		(width 0.15)
		(layer "F.Cu")
		(net 461)
	)
	(segment
		(start 135.51 102.61)
		(end 135.3 102.4)
		(width 0.15)
		(layer "F.Cu")
		(net 461)
	)
	(segment
		(start 134.15 99.95)
		(end 133.15 98.95)
		(width 0.15)
		(layer "F.Cu")
		(net 461)
	)
	(segment
		(start 135.9 100.5)
		(end 135.35 99.95)
		(width 0.15)
		(layer "F.Cu")
		(net 461)
	)
	(segment
		(start 73.1 70.947323)
		(end 73.097323 70.95)
		(width 0.15)
		(layer "F.Cu")
		(net 461)
	)
	(segment
		(start 135.35 98.5)
		(end 136.95 98.5)
		(width 0.15)
		(layer "F.Cu")
		(net 461)
	)
	(segment
		(start 135.3 101.95)
		(end 135.9 101.35)
		(width 0.15)
		(layer "F.Cu")
		(net 461)
	)
	(segment
		(start 135.3 102.4)
		(end 135.3 101.95)
		(width 0.15)
		(layer "F.Cu")
		(net 461)
	)
	(segment
		(start 131.3 96.17)
		(end 132.56 94.91)
		(width 0.15)
		(layer "F.Cu")
		(net 461)
	)
	(segment
		(start 133.51 94.91)
		(end 133.75 95.15)
		(width 0.15)
		(layer "F.Cu")
		(net 461)
	)
	(segment
		(start 135.9 101.35)
		(end 135.9 100.5)
		(width 0.15)
		(layer "F.Cu")
		(net 461)
	)
	(segment
		(start 73.097323 70.95)
		(end 73.097323 72.005136)
		(width 0.15)
		(layer "F.Cu")
		(net 461)
	)
	(segment
		(start 133.15 98.95)
		(end 131.525 98.95)
		(width 0.15)
		(layer "F.Cu")
		(net 461)
	)
	(segment
		(start 137.09 102.61)
		(end 135.51 102.61)
		(width 0.15)
		(layer "F.Cu")
		(net 461)
	)
	(segment
		(start 133.75 95.15)
		(end 133.75 96.9)
		(width 0.15)
		(layer "F.Cu")
		(net 461)
	)
	(segment
		(start 135.35 99.95)
		(end 134.15 99.95)
		(width 0.15)
		(layer "F.Cu")
		(net 461)
	)
	(segment
		(start 73.1 69.8)
		(end 73.1 70.947323)
		(width 0.15)
		(layer "F.Cu")
		(net 461)
	)
	(segment
		(start 131.525 98.95)
		(end 131.3 98.725)
		(width 0.15)
		(layer "F.Cu")
		(net 461)
	)
	(segment
		(start 131.3 98.725)
		(end 131.3 96.17)
		(width 0.15)
		(layer "F.Cu")
		(net 461)
	)
	(via
		(at 73.1 69.8)
		(size 0.45)
		(drill 0.1)
		(layers "F.Cu" "B.Cu")
		(net 461)
	)
	(via
		(at 137.09 102.61)
		(size 0.45)
		(drill 0.1)
		(layers "F.Cu" "B.Cu")
		(net 461)
	)
	(segment
		(start 90.703554 104.45)
		(end 101.15 104.45)
		(width 0.125)
		(layer "In3.Cu")
		(net 461)
	)
	(segment
		(start 68.35 78.539338)
		(end 68.05 78.839338)
		(width 0.125)
		(layer "In3.Cu")
		(net 461)
	)
	(segment
		(start 68.05 86.66)
		(end 66.4 88.31)
		(width 0.125)
		(layer "In3.Cu")
		(net 461)
	)
	(segment
		(start 125.29 113.55)
		(end 135.73 103.11)
		(width 0.125)
		(layer "In3.Cu")
		(net 461)
	)
	(segment
		(start 136.59 103.11)
		(end 137.09 102.61)
		(width 0.125)
		(layer "In3.Cu")
		(net 461)
	)
	(segment
		(start 66.4 88.31)
		(end 66.4 91.453554)
		(width 0.125)
		(layer "In3.Cu")
		(net 461)
	)
	(segment
		(start 85.55 105.45)
		(end 89.703554 105.45)
		(width 0.125)
		(layer "In3.Cu")
		(net 461)
	)
	(segment
		(start 135.73 103.11)
		(end 136.59 103.11)
		(width 0.125)
		(layer "In3.Cu")
		(net 461)
	)
	(segment
		(start 68.35 72.5)
		(end 68.35 78.539338)
		(width 0.125)
		(layer "In3.Cu")
		(net 461)
	)
	(segment
		(start 70 93.560662)
		(end 70 95.925)
		(width 0.125)
		(layer "In3.Cu")
		(net 461)
	)
	(segment
		(start 72.725 98.65)
		(end 72.725 99.325)
		(width 0.125)
		(layer "In3.Cu")
		(net 461)
	)
	(segment
		(start 84.4 104.3)
		(end 85.55 105.45)
		(width 0.125)
		(layer "In3.Cu")
		(net 461)
	)
	(segment
		(start 69.55 71.3)
		(end 68.35 72.5)
		(width 0.125)
		(layer "In3.Cu")
		(net 461)
	)
	(segment
		(start 68.639338 92.2)
		(end 70 93.560662)
		(width 0.125)
		(layer "In3.Cu")
		(net 461)
	)
	(segment
		(start 73.1 69.8)
		(end 73.1 70.96)
		(width 0.125)
		(layer "In3.Cu")
		(net 461)
	)
	(segment
		(start 72.725 99.325)
		(end 77.7 104.3)
		(width 0.125)
		(layer "In3.Cu")
		(net 461)
	)
	(segment
		(start 105.855 111.205)
		(end 108.2 113.55)
		(width 0.125)
		(layer "In3.Cu")
		(net 461)
	)
	(segment
		(start 66.4 91.453554)
		(end 67.146446 92.2)
		(width 0.125)
		(layer "In3.Cu")
		(net 461)
	)
	(segment
		(start 101.15 104.45)
		(end 105.855 109.155)
		(width 0.125)
		(layer "In3.Cu")
		(net 461)
	)
	(segment
		(start 89.703554 105.45)
		(end 90.703554 104.45)
		(width 0.125)
		(layer "In3.Cu")
		(net 461)
	)
	(segment
		(start 68.05 78.839338)
		(end 68.05 86.66)
		(width 0.125)
		(layer "In3.Cu")
		(net 461)
	)
	(segment
		(start 73.1 70.96)
		(end 72.76 71.3)
		(width 0.125)
		(layer "In3.Cu")
		(net 461)
	)
	(segment
		(start 108.2 113.55)
		(end 125.29 113.55)
		(width 0.125)
		(layer "In3.Cu")
		(net 461)
	)
	(segment
		(start 67.146446 92.2)
		(end 68.639338 92.2)
		(width 0.125)
		(layer "In3.Cu")
		(net 461)
	)
	(segment
		(start 105.855 109.155)
		(end 105.855 111.205)
		(width 0.125)
		(layer "In3.Cu")
		(net 461)
	)
	(segment
		(start 77.7 104.3)
		(end 84.4 104.3)
		(width 0.125)
		(layer "In3.Cu")
		(net 461)
	)
	(segment
		(start 70 95.925)
		(end 72.725 98.65)
		(width 0.125)
		(layer "In3.Cu")
		(net 461)
	)
	(segment
		(start 72.76 71.3)
		(end 69.55 71.3)
		(width 0.125)
		(layer "In3.Cu")
		(net 461)
	)
	(segment
		(start 56.96 103.7)
		(end 57.35 104.09)
		(width 0.15)
		(layer "F.Cu")
		(net 463)
	)
	(segment
		(start 72.35 80.202459)
		(end 72.347323 80.205136)
		(width 0.15)
		(layer "F.Cu")
		(net 463)
	)
	(segment
		(start 57.35 104.09)
		(end 57.35 104.35)
		(width 0.15)
		(layer "F.Cu")
		(net 463)
	)
	(segment
		(start 72.35 79.05)
		(end 72.35 80.202459)
		(width 0.15)
		(layer "F.Cu")
		(net 463)
	)
	(segment
		(start 56.96 103.53)
		(end 56.96 103.7)
		(width 0.15)
		(layer "F.Cu")
		(net 463)
	)
	(via
		(at 72.35 79.05)
		(size 0.45)
		(drill 0.1)
		(layers "F.Cu" "B.Cu")
		(net 463)
	)
	(via
		(at 56.96 103.53)
		(size 0.45)
		(drill 0.1)
		(layers "F.Cu" "B.Cu")
		(net 463)
	)
	(via
		(at 63.2468 78.2468)
		(size 0.45)
		(drill 0.1)
		(layers "F.Cu" "B.Cu")
		(net 463)
	)
	(segment
		(start 70.85 77.55)
		(end 68.65 77.55)
		(width 0.155)
		(layer "In1.Cu")
		(net 463)
	)
	(segment
		(start 63.2468 78.2032)
		(end 63.2468 78.2468)
		(width 0.155)
		(layer "In1.Cu")
		(net 463)
	)
	(segment
		(start 68.65 77.55)
		(end 67.5 76.4)
		(width 0.155)
		(layer "In1.Cu")
		(net 463)
	)
	(segment
		(start 67.5 76.4)
		(end 66.65 76.4)
		(width 0.155)
		(layer "In1.Cu")
		(net 463)
	)
	(segment
		(start 65.4 77.65)
		(end 63.8 77.65)
		(width 0.155)
		(layer "In1.Cu")
		(net 463)
	)
	(segment
		(start 66.65 76.4)
		(end 65.4 77.65)
		(width 0.155)
		(layer "In1.Cu")
		(net 463)
	)
	(segment
		(start 63.8 77.65)
		(end 63.2468 78.2032)
		(width 0.155)
		(layer "In1.Cu")
		(net 463)
	)
	(segment
		(start 72.35 79.05)
		(end 70.85 77.55)
		(width 0.155)
		(layer "In1.Cu")
		(net 463)
	)
	(segment
		(start 59.89 87.92)
		(end 60.7 87.11)
		(width 0.125)
		(layer "In3.Cu")
		(net 463)
	)
	(segment
		(start 56.275 90.075)
		(end 58.43 87.92)
		(width 0.125)
		(layer "In3.Cu")
		(net 463)
	)
	(segment
		(start 60.7 77.5)
		(end 61.2 77)
		(width 0.125)
		(layer "In3.Cu")
		(net 463)
	)
	(segment
		(start 56.96 102.19)
		(end 54.515 99.745)
		(width 0.125)
		(layer "In3.Cu")
		(net 463)
	)
	(segment
		(start 56.275 92.425)
		(end 56.275 90.075)
		(width 0.125)
		(layer "In3.Cu")
		(net 463)
	)
	(segment
		(start 58.43 87.92)
		(end 59.89 87.92)
		(width 0.125)
		(layer "In3.Cu")
		(net 463)
	)
	(segment
		(start 54.515 99.745)
		(end 54.515 94.185)
		(width 0.125)
		(layer "In3.Cu")
		(net 463)
	)
	(segment
		(start 60.7 87.11)
		(end 60.7 77.5)
		(width 0.125)
		(layer "In3.Cu")
		(net 463)
	)
	(segment
		(start 62.9 77)
		(end 63.2468 77.3468)
		(width 0.125)
		(layer "In3.Cu")
		(net 463)
	)
	(segment
		(start 61.2 77)
		(end 62.9 77)
		(width 0.125)
		(layer "In3.Cu")
		(net 463)
	)
	(segment
		(start 56.96 103.53)
		(end 56.96 102.19)
		(width 0.125)
		(layer "In3.Cu")
		(net 463)
	)
	(segment
		(start 63.2468 77.3468)
		(end 63.2468 78.2468)
		(width 0.125)
		(layer "In3.Cu")
		(net 463)
	)
	(segment
		(start 54.515 94.185)
		(end 56.275 92.425)
		(width 0.125)
		(layer "In3.Cu")
		(net 463)
	)
	(segment
		(start 68.3 76.1)
		(end 68.7 76.5)
		(width 0.125)
		(layer "F.Cu")
		(net 467)
	)
	(segment
		(start 120.9713 112.7038)
		(end 120.9468 112.6793)
		(width 0.125)
		(layer "F.Cu")
		(net 467)
	)
	(segment
		(start 69.347323 77.147323)
		(end 69.347323 80.205136)
		(width 0.15)
		(layer "F.Cu")
		(net 467)
	)
	(segment
		(start 66.138 76.862)
		(end 66.9 76.1)
		(width 0.125)
		(layer "F.Cu")
		(net 467)
	)
	(segment
		(start 66.288 78.2)
		(end 66.138 78.05)
		(width 0.125)
		(layer "F.Cu")
		(net 467)
	)
	(segment
		(start 68.7 76.5)
		(end 69.347323 77.147323)
		(width 0.15)
		(layer "F.Cu")
		(net 467)
	)
	(segment
		(start 121.05 115.1)
		(end 120.9713 115.0213)
		(width 0.125)
		(layer "F.Cu")
		(net 467)
	)
	(segment
		(start 66.9 76.1)
		(end 68.3 76.1)
		(width 0.125)
		(layer "F.Cu")
		(net 467)
	)
	(segment
		(start 120.9713 115.0213)
		(end 120.9713 112.7038)
		(width 0.125)
		(layer "F.Cu")
		(net 467)
	)
	(segment
		(start 66.138 78.05)
		(end 66.138 76.862)
		(width 0.125)
		(layer "F.Cu")
		(net 467)
	)
	(via
		(at 66.288 78.2)
		(size 0.45)
		(drill 0.1)
		(layers "F.Cu" "B.Cu")
		(net 467)
	)
	(via
		(at 121.05 115.1)
		(size 0.45)
		(drill 0.1)
		(layers "F.Cu" "B.Cu")
		(net 467)
	)
	(via
		(at 92.100688 107.399312)
		(size 0.45)
		(drill 0.1)
		(layers "F.Cu" "B.Cu")
		(net 467)
	)
	(segment
		(start 71 99.225)
		(end 68.54 96.765)
		(width 0.125)
		(layer "In3.Cu")
		(net 467)
	)
	(segment
		(start 90.3 107.55)
		(end 85.65 107.55)
		(width 0.125)
		(layer "In3.Cu")
		(net 467)
	)
	(segment
		(start 85.65 107.55)
		(end 83.65 105.55)
		(width 0.125)
		(layer "In3.Cu")
		(net 467)
	)
	(segment
		(start 68.54 93.868432)
		(end 68.121566 93.449998)
		(width 0.125)
		(layer "In3.Cu")
		(net 467)
	)
	(segment
		(start 65.15 87.74)
		(end 66.75 86.14)
		(width 0.125)
		(layer "In3.Cu")
		(net 467)
	)
	(segment
		(start 68.54 96.765)
		(end 68.54 93.868432)
		(width 0.125)
		(layer "In3.Cu")
		(net 467)
	)
	(segment
		(start 90.450688 107.399312)
		(end 90.3 107.55)
		(width 0.125)
		(layer "In3.Cu")
		(net 467)
	)
	(segment
		(start 71 99.6)
		(end 71 99.225)
		(width 0.125)
		(layer "In3.Cu")
		(net 467)
	)
	(segment
		(start 92.100688 107.399312)
		(end 90.450688 107.399312)
		(width 0.125)
		(layer "In3.Cu")
		(net 467)
	)
	(segment
		(start 75.45 105.55)
		(end 74.5 104.6)
		(width 0.125)
		(layer "In3.Cu")
		(net 467)
	)
	(segment
		(start 68.121566 93.449998)
		(end 66.628676 93.449998)
		(width 0.125)
		(layer "In3.Cu")
		(net 467)
	)
	(segment
		(start 74.5 103.1)
		(end 71 99.6)
		(width 0.125)
		(layer "In3.Cu")
		(net 467)
	)
	(segment
		(start 83.65 105.55)
		(end 75.45 105.55)
		(width 0.125)
		(layer "In3.Cu")
		(net 467)
	)
	(segment
		(start 66.75 86.14)
		(end 66.75 82.7)
		(width 0.125)
		(layer "In3.Cu")
		(net 467)
	)
	(segment
		(start 74.5 104.6)
		(end 74.5 103.1)
		(width 0.125)
		(layer "In3.Cu")
		(net 467)
	)
	(segment
		(start 65.15 91.971319)
		(end 65.15 87.74)
		(width 0.125)
		(layer "In3.Cu")
		(net 467)
	)
	(segment
		(start 66.75 82.7)
		(end 66.2 82.15)
		(width 0.125)
		(layer "In3.Cu")
		(net 467)
	)
	(segment
		(start 66.628676 93.449998)
		(end 65.15 91.971319)
		(width 0.125)
		(layer "In3.Cu")
		(net 467)
	)
	(segment
		(start 66.2 82.15)
		(end 66.2 78.288)
		(width 0.125)
		(layer "In3.Cu")
		(net 467)
	)
	(segment
		(start 66.2 78.288)
		(end 66.288 78.2)
		(width 0.125)
		(layer "In3.Cu")
		(net 467)
	)
	(segment
		(start 120.45 115.85)
		(end 121.05 115.25)
		(width 0.125)
		(layer "In5.Cu")
		(net 467)
	)
	(segment
		(start 121.1 115.15)
		(end 121.05 115.1)
		(width 0.125)
		(layer "In5.Cu")
		(net 467)
	)
	(segment
		(start 121.05 115.25)
		(end 121.05 115.1)
		(width 0.125)
		(layer "In5.Cu")
		(net 467)
	)
	(segment
		(start 92.299312 107.399312)
		(end 98.6 113.7)
		(width 0.125)
		(layer "In5.Cu")
		(net 467)
	)
	(segment
		(start 119.25 115.85)
		(end 120.45 115.85)
		(width 0.125)
		(layer "In5.Cu")
		(net 467)
	)
	(segment
		(start 98.6 113.7)
		(end 118.45 113.7)
		(width 0.125)
		(layer "In5.Cu")
		(net 467)
	)
	(segment
		(start 92.100688 107.399312)
		(end 92.299312 107.399312)
		(width 0.125)
		(layer "In5.Cu")
		(net 467)
	)
	(segment
		(start 118.45 113.7)
		(end 118.5 113.65)
		(width 0.125)
		(layer "In5.Cu")
		(net 467)
	)
	(segment
		(start 118.5 115.1)
		(end 119.25 115.85)
		(width 0.125)
		(layer "In5.Cu")
		(net 467)
	)
	(segment
		(start 118.5 113.65)
		(end 118.5 115.1)
		(width 0.125)
		(layer "In5.Cu")
		(net 467)
	)
	(segment
		(start 68.847323 77.297323)
		(end 68.847323 80.205136)
		(width 0.15)
		(layer "F.Cu")
		(net 468)
	)
	(segment
		(start 120.5468 114.588)
		(end 120.5588 114.6)
		(width 0.125)
		(layer "F.Cu")
		(net 468)
	)
	(segment
		(start 120.5468 112.6793)
		(end 120.5468 114.588)
		(width 0.125)
		(layer "F.Cu")
		(net 468)
	)
	(segment
		(start 66.5505 76.8495)
		(end 67 76.4)
		(width 0.15)
		(layer "F.Cu")
		(net 468)
	)
	(segment
		(start 67.95 76.4)
		(end 68.847323 77.297323)
		(width 0.15)
		(layer "F.Cu")
		(net 468)
	)
	(segment
		(start 67 76.4)
		(end 67.95 76.4)
		(width 0.15)
		(layer "F.Cu")
		(net 468)
	)
	(segment
		(start 66.5505 77.3)
		(end 66.5505 76.8495)
		(width 0.15)
		(layer "F.Cu")
		(net 468)
	)
	(via
		(at 120.5588 114.6)
		(size 0.45)
		(drill 0.1)
		(layers "F.Cu" "B.Cu")
		(net 468)
	)
	(via
		(at 66.5505 77.3)
		(size 0.45)
		(drill 0.1)
		(layers "F.Cu" "B.Cu")
		(net 468)
	)
	(via
		(at 91.6645 106.949833)
		(size 0.45)
		(drill 0.1)
		(layers "F.Cu" "B.Cu")
		(net 468)
	)
	(segment
		(start 71.31 99.51)
		(end 71.31 99.11)
		(width 0.125)
		(layer "In3.Cu")
		(net 468)
	)
	(segment
		(start 71.31 99.11)
		(end 68.83 96.63)
		(width 0.125)
		(layer "In3.Cu")
		(net 468)
	)
	(segment
		(start 66.7005 78.4995)
		(end 66.7005 77.8505)
		(width 0.125)
		(layer "In3.Cu")
		(net 468)
	)
	(segment
		(start 68.225121 93.199999)
		(end 66.73223 93.199999)
		(width 0.125)
		(layer "In3.Cu")
		(net 468)
	)
	(segment
		(start 67 86.25)
		(end 67 82.544182)
		(width 0.125)
		(layer "In3.Cu")
		(net 468)
	)
	(segment
		(start 91.6645 106.949833)
		(end 90.400167 106.949833)
		(width 0.125)
		(layer "In3.Cu")
		(net 468)
	)
	(segment
		(start 66.55 77.7)
		(end 66.55 77.3005)
		(width 0.125)
		(layer "In3.Cu")
		(net 468)
	)
	(segment
		(start 66.45 78.75)
		(end 66.7005 78.4995)
		(width 0.125)
		(layer "In3.Cu")
		(net 468)
	)
	(segment
		(start 75.4 103.6)
		(end 71.31 99.51)
		(width 0.125)
		(layer "In3.Cu")
		(net 468)
	)
	(segment
		(start 66.55 77.3005)
		(end 66.5505 77.3)
		(width 0.125)
		(layer "In3.Cu")
		(net 468)
	)
	(segment
		(start 90.400167 106.949833)
		(end 90.05 107.3)
		(width 0.125)
		(layer "In3.Cu")
		(net 468)
	)
	(segment
		(start 76.1 105.3)
		(end 75.4 104.6)
		(width 0.125)
		(layer "In3.Cu")
		(net 468)
	)
	(segment
		(start 65.4 87.85)
		(end 67 86.25)
		(width 0.125)
		(layer "In3.Cu")
		(net 468)
	)
	(segment
		(start 66.73223 93.199999)
		(end 65.4 91.867766)
		(width 0.125)
		(layer "In3.Cu")
		(net 468)
	)
	(segment
		(start 66.7005 77.8505)
		(end 66.55 77.7)
		(width 0.125)
		(layer "In3.Cu")
		(net 468)
	)
	(segment
		(start 68.83 96.63)
		(end 68.83 93.804878)
		(width 0.125)
		(layer "In3.Cu")
		(net 468)
	)
	(segment
		(start 65.4 91.867766)
		(end 65.4 87.85)
		(width 0.125)
		(layer "In3.Cu")
		(net 468)
	)
	(segment
		(start 67 82.544182)
		(end 66.45 81.994182)
		(width 0.125)
		(layer "In3.Cu")
		(net 468)
	)
	(segment
		(start 75.4 104.6)
		(end 75.4 103.6)
		(width 0.125)
		(layer "In3.Cu")
		(net 468)
	)
	(segment
		(start 85.8 107.3)
		(end 83.8 105.3)
		(width 0.125)
		(layer "In3.Cu")
		(net 468)
	)
	(segment
		(start 66.45 81.994182)
		(end 66.45 78.75)
		(width 0.125)
		(layer "In3.Cu")
		(net 468)
	)
	(segment
		(start 90.05 107.3)
		(end 85.8 107.3)
		(width 0.125)
		(layer "In3.Cu")
		(net 468)
	)
	(segment
		(start 83.8 105.3)
		(end 76.1 105.3)
		(width 0.125)
		(layer "In3.Cu")
		(net 468)
	)
	(segment
		(start 68.83 93.804878)
		(end 68.225121 93.199999)
		(width 0.125)
		(layer "In3.Cu")
		(net 468)
	)
	(segment
		(start 120.6 114.6412)
		(end 120.5588 114.6)
		(width 0.125)
		(layer "In5.Cu")
		(net 468)
	)
	(segment
		(start 120.3 115.55)
		(end 120.6 115.25)
		(width 0.125)
		(layer "In5.Cu")
		(net 468)
	)
	(segment
		(start 120.6 115.25)
		(end 120.6 114.6412)
		(width 0.125)
		(layer "In5.Cu")
		(net 468)
	)
	(segment
		(start 92.299833 106.949833)
		(end 98.75 113.4)
		(width 0.125)
		(layer "In5.Cu")
		(net 468)
	)
	(segment
		(start 91.6645 106.949833)
		(end 92.299833 106.949833)
		(width 0.125)
		(layer "In5.Cu")
		(net 468)
	)
	(segment
		(start 119.4 115.55)
		(end 120.3 115.55)
		(width 0.125)
		(layer "In5.Cu")
		(net 468)
	)
	(segment
		(start 98.75 113.4)
		(end 118.8 113.4)
		(width 0.125)
		(layer "In5.Cu")
		(net 468)
	)
	(segment
		(start 118.8 114.95)
		(end 119.4 115.55)
		(width 0.125)
		(layer "In5.Cu")
		(net 468)
	)
	(segment
		(start 118.8 113.4)
		(end 118.8 114.95)
		(width 0.125)
		(layer "In5.Cu")
		(net 468)
	)
	(segment
		(start 67.137917 76.762083)
		(end 67.2 76.7)
		(width 0.15)
		(layer "F.Cu")
		(net 469)
	)
	(segment
		(start 68.347323 77.347323)
		(end 68.347323 80.205136)
		(width 0.15)
		(layer "F.Cu")
		(net 469)
	)
	(segment
		(start 67.7 76.7)
		(end 68.347323 77.347323)
		(width 0.15)
		(layer "F.Cu")
		(net 469)
	)
	(segment
		(start 120.1468 115.0968)
		(end 120.1468 112.6793)
		(width 0.125)
		(layer "F.Cu")
		(net 469)
	)
	(segment
		(start 67.137917 76.862417)
		(end 67.137917 76.762083)
		(width 0.15)
		(layer "F.Cu")
		(net 469)
	)
	(segment
		(start 67.2 76.7)
		(end 67.7 76.7)
		(width 0.15)
		(layer "F.Cu")
		(net 469)
	)
	(via
		(at 92.15 106.537833)
		(size 0.45)
		(drill 0.1)
		(layers "F.Cu" "B.Cu")
		(net 469)
	)
	(via
		(at 120.1468 115.0968)
		(size 0.45)
		(drill 0.1)
		(layers "F.Cu" "B.Cu")
		(net 469)
	)
	(via
		(at 67.137917 76.862417)
		(size 0.45)
		(drill 0.1)
		(layers "F.Cu" "B.Cu")
		(net 469)
	)
	(segment
		(start 67.3 86.31)
		(end 67.3 80.45)
		(width 0.125)
		(layer "In3.Cu")
		(net 469)
	)
	(segment
		(start 85.95 107.05)
		(end 83.95 105.05)
		(width 0.125)
		(layer "In3.Cu")
		(net 469)
	)
	(segment
		(start 67.3 80.45)
		(end 66.9625 80.1125)
		(width 0.125)
		(layer "In3.Cu")
		(net 469)
	)
	(segment
		(start 66.835784 92.95)
		(end 65.65 91.764213)
		(width 0.125)
		(layer "In3.Cu")
		(net 469)
	)
	(segment
		(start 65.65 91.764213)
		(end 65.65 87.96)
		(width 0.125)
		(layer "In3.Cu")
		(net 469)
	)
	(segment
		(start 66.9625 77.037834)
		(end 67.137917 76.862417)
		(width 0.125)
		(layer "In3.Cu")
		(net 469)
	)
	(segment
		(start 69.1 93.721324)
		(end 68.328676 92.95)
		(width 0.125)
		(layer "In3.Cu")
		(net 469)
	)
	(segment
		(start 71.65 98.975)
		(end 69.1 96.425)
		(width 0.125)
		(layer "In3.Cu")
		(net 469)
	)
	(segment
		(start 71.65 99.45)
		(end 71.65 98.975)
		(width 0.125)
		(layer "In3.Cu")
		(net 469)
	)
	(segment
		(start 65.65 87.96)
		(end 67.3 86.31)
		(width 0.125)
		(layer "In3.Cu")
		(net 469)
	)
	(segment
		(start 89.9 107.05)
		(end 85.95 107.05)
		(width 0.125)
		(layer "In3.Cu")
		(net 469)
	)
	(segment
		(start 69.1 96.425)
		(end 69.1 93.721324)
		(width 0.125)
		(layer "In3.Cu")
		(net 469)
	)
	(segment
		(start 92.15 106.537833)
		(end 90.412167 106.537833)
		(width 0.125)
		(layer "In3.Cu")
		(net 469)
	)
	(segment
		(start 68.328676 92.95)
		(end 66.835784 92.95)
		(width 0.125)
		(layer "In3.Cu")
		(net 469)
	)
	(segment
		(start 76.25 105.05)
		(end 75.7 104.5)
		(width 0.125)
		(layer "In3.Cu")
		(net 469)
	)
	(segment
		(start 83.95 105.05)
		(end 76.25 105.05)
		(width 0.125)
		(layer "In3.Cu")
		(net 469)
	)
	(segment
		(start 75.7 104.5)
		(end 75.7 103.5)
		(width 0.125)
		(layer "In3.Cu")
		(net 469)
	)
	(segment
		(start 90.412167 106.537833)
		(end 89.9 107.05)
		(width 0.125)
		(layer "In3.Cu")
		(net 469)
	)
	(segment
		(start 75.7 103.5)
		(end 71.65 99.45)
		(width 0.125)
		(layer "In3.Cu")
		(net 469)
	)
	(segment
		(start 66.9625 80.1125)
		(end 66.9625 77.037834)
		(width 0.125)
		(layer "In3.Cu")
		(net 469)
	)
	(segment
		(start 92.337833 106.537833)
		(end 98.9 113.1)
		(width 0.125)
		(layer "In5.Cu")
		(net 469)
	)
	(segment
		(start 118.95 113.1)
		(end 119.1 113.25)
		(width 0.125)
		(layer "In5.Cu")
		(net 469)
	)
	(segment
		(start 119.1 113.25)
		(end 119.1 114.75)
		(width 0.125)
		(layer "In5.Cu")
		(net 469)
	)
	(segment
		(start 119.4468 115.0968)
		(end 120.1468 115.0968)
		(width 0.125)
		(layer "In5.Cu")
		(net 469)
	)
	(segment
		(start 98.9 113.1)
		(end 118.95 113.1)
		(width 0.125)
		(layer "In5.Cu")
		(net 469)
	)
	(segment
		(start 92.15 106.537833)
		(end 92.337833 106.537833)
		(width 0.125)
		(layer "In5.Cu")
		(net 469)
	)
	(segment
		(start 119.1 114.75)
		(end 119.4468 115.0968)
		(width 0.125)
		(layer "In5.Cu")
		(net 469)
	)
	(segment
		(start 67.421691 78.022602)
		(end 67.847323 78.448234)
		(width 0.15)
		(layer "F.Cu")
		(net 470)
	)
	(segment
		(start 119.7468 114.5032)
		(end 119.7468 112.6793)
		(width 0.125)
		(layer "F.Cu")
		(net 470)
	)
	(segment
		(start 119.65 114.6)
		(end 119.7468 114.5032)
		(width 0.125)
		(layer "F.Cu")
		(net 470)
	)
	(segment
		(start 67.847323 78.448234)
		(end 67.847323 80.205136)
		(width 0.15)
		(layer "F.Cu")
		(net 470)
	)
	(via
		(at 91.6645 106.101467)
		(size 0.45)
		(drill 0.1)
		(layers "F.Cu" "B.Cu")
		(net 470)
	)
	(via
		(at 119.65 114.6)
		(size 0.45)
		(drill 0.1)
		(layers "F.Cu" "B.Cu")
		(net 470)
	)
	(via
		(at 67.421691 78.022602)
		(size 0.45)
		(drill 0.1)
		(layers "F.Cu" "B.Cu")
		(net 470)
	)
	(segment
		(start 69.4 96.275)
		(end 69.4 93.66777)
		(width 0.125)
		(layer "In3.Cu")
		(net 470)
	)
	(segment
		(start 91.6645 106.101467)
		(end 90.448533 106.101467)
		(width 0.125)
		(layer "In3.Cu")
		(net 470)
	)
	(segment
		(start 67.55 79.95)
		(end 67.421691 79.821691)
		(width 0.125)
		(layer "In3.Cu")
		(net 470)
	)
	(segment
		(start 84.1 104.8)
		(end 77.4 104.8)
		(width 0.125)
		(layer "In3.Cu")
		(net 470)
	)
	(segment
		(start 86.1 106.8)
		(end 84.1 104.8)
		(width 0.125)
		(layer "In3.Cu")
		(net 470)
	)
	(segment
		(start 77.4 104.8)
		(end 72 99.4)
		(width 0.125)
		(layer "In3.Cu")
		(net 470)
	)
	(segment
		(start 67.421691 79.821691)
		(end 67.421691 78.022602)
		(width 0.125)
		(layer "In3.Cu")
		(net 470)
	)
	(segment
		(start 65.9 91.66066)
		(end 65.9 88.07)
		(width 0.125)
		(layer "In3.Cu")
		(net 470)
	)
	(segment
		(start 67.55 86.42)
		(end 67.55 79.95)
		(width 0.125)
		(layer "In3.Cu")
		(net 470)
	)
	(segment
		(start 90.448533 106.101467)
		(end 89.75 106.8)
		(width 0.125)
		(layer "In3.Cu")
		(net 470)
	)
	(segment
		(start 66.939338 92.7)
		(end 65.9 91.66066)
		(width 0.125)
		(layer "In3.Cu")
		(net 470)
	)
	(segment
		(start 89.75 106.8)
		(end 86.1 106.8)
		(width 0.125)
		(layer "In3.Cu")
		(net 470)
	)
	(segment
		(start 65.9 88.07)
		(end 67.55 86.42)
		(width 0.125)
		(layer "In3.Cu")
		(net 470)
	)
	(segment
		(start 72 98.875)
		(end 69.4 96.275)
		(width 0.125)
		(layer "In3.Cu")
		(net 470)
	)
	(segment
		(start 72 99.4)
		(end 72 98.875)
		(width 0.125)
		(layer "In3.Cu")
		(net 470)
	)
	(segment
		(start 68.43223 92.7)
		(end 66.939338 92.7)
		(width 0.125)
		(layer "In3.Cu")
		(net 470)
	)
	(segment
		(start 69.4 93.66777)
		(end 68.43223 92.7)
		(width 0.125)
		(layer "In3.Cu")
		(net 470)
	)
	(segment
		(start 91.6645 106.101467)
		(end 92.301467 106.101467)
		(width 0.125)
		(layer "In5.Cu")
		(net 470)
	)
	(segment
		(start 119.15 112.8)
		(end 119.4 113.05)
		(width 0.125)
		(layer "In5.Cu")
		(net 470)
	)
	(segment
		(start 92.301467 106.101467)
		(end 99 112.8)
		(width 0.125)
		(layer "In5.Cu")
		(net 470)
	)
	(segment
		(start 99 112.8)
		(end 119.15 112.8)
		(width 0.125)
		(layer "In5.Cu")
		(net 470)
	)
	(segment
		(start 119.4 114.35)
		(end 119.65 114.6)
		(width 0.125)
		(layer "In5.Cu")
		(net 470)
	)
	(segment
		(start 119.4 113.05)
		(end 119.4 114.35)
		(width 0.125)
		(layer "In5.Cu")
		(net 470)
	)
	(segment
		(start 71.8745 76.020181)
		(end 71.8745 77.040368)
		(width 0.155)
		(layer "F.Cu")
		(net 471)
	)
	(segment
		(start 146.787662 89.8005)
		(end 146.612632 89.8005)
		(width 0.155)
		(layer "F.Cu")
		(net 471)
	)
	(segment
		(start 67.597323 72.005136)
		(end 67.597323 72.730136)
		(width 0.155)
		(layer "F.Cu")
		(net 471)
	)
	(segment
		(start 67.597323 72.730136)
		(end 67.496823 72.830636)
		(width 0.155)
		(layer "F.Cu")
		(net 471)
	)
	(segment
		(start 71.918434 77.146434)
		(end 71.997 77.225)
		(width 0.155)
		(layer "F.Cu")
		(net 471)
	)
	(segment
		(start 147.137368 90.0005)
		(end 147.111926 90.0005)
		(width 0.155)
		(layer "F.Cu")
		(net 471)
	)
	(segment
		(start 147.111926 90.0005)
		(end 146.999794 89.888368)
		(width 0.155)
		(layer "F.Cu")
		(net 471)
	)
	(segment
		(start 148.17 89.83)
		(end 147.845001 89.83)
		(width 0.155)
		(layer "F.Cu")
		(net 471)
	)
	(segment
		(start 147.825001 89.85)
		(end 147.45 89.85)
		(width 0.155)
		(layer "F.Cu")
		(net 471)
	)
	(segment
		(start 67.599336 73.63791)
		(end 68.659414 74.697988)
		(width 0.155)
		(layer "F.Cu")
		(net 471)
	)
	(segment
		(start 68.906901 74.8005)
		(end 70.654819 74.8005)
		(width 0.155)
		(layer "F.Cu")
		(net 471)
	)
	(segment
		(start 147.35 89.85)
		(end 147.243434 89.956566)
		(width 0.155)
		(layer "F.Cu")
		(net 471)
	)
	(segment
		(start 67.496823 72.830636)
		(end 67.496823 73.390422)
		(width 0.155)
		(layer "F.Cu")
		(net 471)
	)
	(segment
		(start 71.008373 74.946947)
		(end 71.728054 75.666628)
		(width 0.155)
		(layer "F.Cu")
		(net 471)
	)
	(segment
		(start 147.845001 89.83)
		(end 147.825001 89.85)
		(width 0.155)
		(layer "F.Cu")
		(net 471)
	)
	(segment
		(start 146.506566 89.756566)
		(end 146.3 89.55)
		(width 0.155)
		(layer "F.Cu")
		(net 471)
	)
	(via
		(at 148.17 89.83)
		(size 0.45)
		(drill 0.1)
		(layers "F.Cu" "B.Cu")
		(net 471)
	)
	(via
		(at 71.997 77.225)
		(size 0.45)
		(drill 0.1)
		(layers "F.Cu" "B.Cu")
		(net 471)
	)
	(arc
		(start 146.787662 89.8005)
		(mid 146.902467 89.823336)
		(end 146.999794 89.888368)
		(width 0.155)
		(layer "F.Cu")
		(net 471)
	)
	(arc
		(start 67.599336 73.63791)
		(mid 67.523465 73.524362)
		(end 67.496823 73.390422)
		(width 0.155)
		(layer "F.Cu")
		(net 471)
	)
	(arc
		(start 146.612632 89.8005)
		(mid 146.555229 89.789082)
		(end 146.506566 89.756566)
		(width 0.155)
		(layer "F.Cu")
		(net 471)
	)
	(arc
		(start 71.918434 77.146434)
		(mid 71.885918 77.097771)
		(end 71.8745 77.040368)
		(width 0.155)
		(layer "F.Cu")
		(net 471)
	)
	(arc
		(start 70.654819 74.8005)
		(mid 70.846161 74.83856)
		(end 71.008373 74.946947)
		(width 0.155)
		(layer "F.Cu")
		(net 471)
	)
	(arc
		(start 68.659414 74.697988)
		(mid 68.772962 74.773858)
		(end 68.906901 74.8005)
		(width 0.155)
		(layer "F.Cu")
		(net 471)
	)
	(arc
		(start 71.728054 75.666628)
		(mid 71.83644 75.82884)
		(end 71.8745 76.020181)
		(width 0.155)
		(layer "F.Cu")
		(net 471)
	)
	(arc
		(start 147.137368 90.0005)
		(mid 147.194771 89.989082)
		(end 147.243434 89.956566)
		(width 0.155)
		(layer "F.Cu")
		(net 471)
	)
	(segment
		(start 115.606693 110.751)
		(end 123.068307 110.751)
		(width 0.16)
		(layer "In3.Cu")
		(net 471)
	)
	(segment
		(start 104.101512 99.540794)
		(end 107.552553 102.991835)
		(width 0.16)
		(layer "In3.Cu")
		(net 471)
	)
	(segment
		(start 81.782289 100.571572)
		(end 81.984618 100.7739)
		(width 0.16)
		(layer "In3.Cu")
		(net 471)
	)
	(segment
		(start 71.976512 86.865794)
		(end 72.759205 87.648487)
		(width 0.16)
		(layer "In3.Cu")
		(net 471)
	)
	(segment
		(start 81.723192 99.78214)
		(end 81.782289 99.841237)
		(width 0.16)
		(layer "In3.Cu")
		(net 471)
	)
	(segment
		(start 71.997 77.225)
		(end 71.917934 77.304066)
		(width 0.16)
		(layer "In3.Cu")
		(net 471)
	)
	(segment
		(start 143.690794 97.998488)
		(end 147.398487 94.290795)
		(width 0.16)
		(layer "In3.Cu")
		(net 471)
	)
	(segment
		(start 147.301 90.887454)
		(end 147.301 90.412546)
		(width 0.16)
		(layer "In3.Cu")
		(net 471)
	)
	(segment
		(start 78.693195 98.801)
		(end 79.62948 98.801)
		(width 0.16)
		(layer "In3.Cu")
		(net 471)
	)
	(segment
		(start 147.457066 91.167784)
		(end 147.388868 91.099586)
		(width 0.16)
		(layer "In3.Cu")
		(net 471)
	)
	(segment
		(start 74.668458 87.83274)
		(end 75.088148 88.25243)
		(width 0.16)
		(layer "In3.Cu")
		(net 471)
	)
	(segment
		(start 103.999 98.445389)
		(end 103.999 99.293307)
		(width 0.16)
		(layer "In3.Cu")
		(net 471)
	)
	(segment
		(start 82.170754 100.851)
		(end 87.743307 100.851)
		(width 0.16)
		(layer "In3.Cu")
		(net 471)
	)
	(segment
		(start 111.306693 107.251)
		(end 111.754611 107.251)
		(width 0.16)
		(layer "In3.Cu")
		(net 471)
	)
	(segment
		(start 107.801512 103.890794)
		(end 111.059205 107.148487)
		(width 0.16)
		(layer "In3.Cu")
		(net 471)
	)
	(segment
		(start 147.712546 90.001)
		(end 147.936868 90.001)
		(width 0.16)
		(layer "In3.Cu")
		(net 471)
	)
	(segment
		(start 81.782287 100.571571)
		(end 81.782289 100.571572)
		(width 0.16)
		(layer "In3.Cu")
		(net 471)
	)
	(segment
		(start 147.388868 90.200414)
		(end 147.500414 90.088868)
		(width 0.16)
		(layer "In3.Cu")
		(net 471)
	)
	(segment
		(start 107.699 103.345389)
		(end 107.699 103.643307)
		(width 0.16)
		(layer "In3.Cu")
		(net 471)
	)
	(segment
		(start 81.358026 99.78214)
		(end 81.358025 99.782141)
		(width 0.16)
		(layer "In3.Cu")
		(net 471)
	)
	(segment
		(start 147.501 94.043307)
		(end 147.501 91.27385)
		(width 0.16)
		(layer "In3.Cu")
		(net 471)
	)
	(segment
		(start 87.990794 100.748488)
		(end 93.471835 95.267447)
		(width 0.16)
		(layer "In3.Cu")
		(net 471)
	)
	(segment
		(start 73.006693 87.751)
		(end 74.47112 87.751)
		(width 0.16)
		(layer "In3.Cu")
		(net 471)
	)
	(segment
		(start 93.825389 95.121)
		(end 100.674611 95.121)
		(width 0.16)
		(layer "In3.Cu")
		(net 471)
	)
	(segment
		(start 71.874 77.410132)
		(end 71.874 86.618307)
		(width 0.16)
		(layer "In3.Cu")
		(net 471)
	)
	(segment
		(start 81.723193 99.78214)
		(end 81.723192 99.78214)
		(width 0.16)
		(layer "In3.Cu")
		(net 471)
	)
	(segment
		(start 75.199 88.52005)
		(end 75.199 96.262455)
		(width 0.16)
		(layer "In3.Cu")
		(net 471)
	)
	(segment
		(start 101.028164 95.267446)
		(end 103.852553 98.091835)
		(width 0.16)
		(layer "In3.Cu")
		(net 471)
	)
	(segment
		(start 123.315794 110.648488)
		(end 135.716835 98.247447)
		(width 0.16)
		(layer "In3.Cu")
		(net 471)
	)
	(segment
		(start 148.042934 89.957066)
		(end 148.17 89.83)
		(width 0.16)
		(layer "In3.Cu")
		(net 471)
	)
	(segment
		(start 81.358025 99.782141)
		(end 81.358026 99.782141)
		(width 0.16)
		(layer "In3.Cu")
		(net 471)
	)
	(segment
		(start 75.323328 96.56261)
		(end 76.761644 98.000926)
		(width 0.16)
		(layer "In3.Cu")
		(net 471)
	)
	(segment
		(start 80.282001 99.071283)
		(end 80.992859 99.782141)
		(width 0.16)
		(layer "In3.Cu")
		(net 471)
	)
	(segment
		(start 136.070389 98.101)
		(end 143.443307 98.101)
		(width 0.16)
		(layer "In3.Cu")
		(net 471)
	)
	(segment
		(start 112.108164 107.397446)
		(end 115.359205 110.648487)
		(width 0.16)
		(layer "In3.Cu")
		(net 471)
	)
	(arc
		(start 93.471835 95.267447)
		(mid 93.634047 95.15906)
		(end 93.825389 95.121)
		(width 0.16)
		(layer "In3.Cu")
		(net 471)
	)
	(arc
		(start 71.874 86.618307)
		(mid 71.900642 86.752246)
		(end 71.976512 86.865794)
		(width 0.16)
		(layer "In3.Cu")
		(net 471)
	)
	(arc
		(start 74.47112 87.751)
		(mid 74.577919 87.772243)
		(end 74.668458 87.83274)
		(width 0.16)
		(layer "In3.Cu")
		(net 471)
	)
	(arc
		(start 103.999 99.293307)
		(mid 104.025642 99.427246)
		(end 104.101512 99.540794)
		(width 0.16)
		(layer "In3.Cu")
		(net 471)
	)
	(arc
		(start 103.852553 98.091835)
		(mid 103.96094 98.254047)
		(end 103.999 98.445389)
		(width 0.16)
		(layer "In3.Cu")
		(net 471)
	)
	(arc
		(start 115.359205 110.648487)
		(mid 115.472753 110.724358)
		(end 115.606693 110.751)
		(width 0.16)
		(layer "In3.Cu")
		(net 471)
	)
	(arc
		(start 111.754611 107.251)
		(mid 111.945952 107.28906)
		(end 112.108164 107.397446)
		(width 0.16)
		(layer "In3.Cu")
		(net 471)
	)
	(arc
		(start 143.443307 98.101)
		(mid 143.577246 98.074358)
		(end 143.690794 97.998488)
		(width 0.16)
		(layer "In3.Cu")
		(net 471)
	)
	(arc
		(start 147.500414 90.088868)
		(mid 147.597741 90.023836)
		(end 147.712546 90.001)
		(width 0.16)
		(layer "In3.Cu")
		(net 471)
	)
	(arc
		(start 123.068307 110.751)
		(mid 123.202246 110.724358)
		(end 123.315794 110.648488)
		(width 0.16)
		(layer "In3.Cu")
		(net 471)
	)
	(arc
		(start 107.699 103.643307)
		(mid 107.725642 103.777246)
		(end 107.801512 103.890794)
		(width 0.16)
		(layer "In3.Cu")
		(net 471)
	)
	(arc
		(start 100.674611 95.121)
		(mid 100.865952 95.15906)
		(end 101.028164 95.267446)
		(width 0.16)
		(layer "In3.Cu")
		(net 471)
	)
	(arc
		(start 147.501 91.27385)
		(mid 147.489582 91.216447)
		(end 147.457066 91.167784)
		(width 0.16)
		(layer "In3.Cu")
		(net 471)
	)
	(arc
		(start 80.992859 99.782141)
		(mid 81.175443 99.857769)
		(end 81.358026 99.78214)
		(width 0.16)
		(layer "In3.Cu")
		(net 471)
	)
	(arc
		(start 72.759205 87.648487)
		(mid 72.872753 87.724358)
		(end 73.006693 87.751)
		(width 0.16)
		(layer "In3.Cu")
		(net 471)
	)
	(arc
		(start 79.62948 98.801)
		(mid 79.982622 98.871244)
		(end 80.282001 99.071283)
		(width 0.16)
		(layer "In3.Cu")
		(net 471)
	)
	(arc
		(start 111.059205 107.148487)
		(mid 111.172753 107.224358)
		(end 111.306693 107.251)
		(width 0.16)
		(layer "In3.Cu")
		(net 471)
	)
	(arc
		(start 75.199 96.262455)
		(mid 75.231312 96.424898)
		(end 75.323328 96.56261)
		(width 0.16)
		(layer "In3.Cu")
		(net 471)
	)
	(arc
		(start 81.984618 100.7739)
		(mid 82.070018 100.830962)
		(end 82.170754 100.851)
		(width 0.16)
		(layer "In3.Cu")
		(net 471)
	)
	(arc
		(start 87.743307 100.851)
		(mid 87.877246 100.824358)
		(end 87.990794 100.748488)
		(width 0.16)
		(layer "In3.Cu")
		(net 471)
	)
	(arc
		(start 71.917934 77.304066)
		(mid 71.885418 77.352729)
		(end 71.874 77.410132)
		(width 0.16)
		(layer "In3.Cu")
		(net 471)
	)
	(arc
		(start 135.716835 98.247447)
		(mid 135.879047 98.13906)
		(end 136.070389 98.101)
		(width 0.16)
		(layer "In3.Cu")
		(net 471)
	)
	(arc
		(start 107.552553 102.991835)
		(mid 107.66094 103.154047)
		(end 107.699 103.345389)
		(width 0.16)
		(layer "In3.Cu")
		(net 471)
	)
	(arc
		(start 75.088148 88.25243)
		(mid 75.17019 88.375215)
		(end 75.199 88.52005)
		(width 0.16)
		(layer "In3.Cu")
		(net 471)
	)
	(arc
		(start 147.398487 94.290795)
		(mid 147.474358 94.177247)
		(end 147.501 94.043307)
		(width 0.16)
		(layer "In3.Cu")
		(net 471)
	)
	(arc
		(start 76.761644 98.000926)
		(mid 77.647847 98.593068)
		(end 78.693195 98.801)
		(width 0.16)
		(layer "In3.Cu")
		(net 471)
	)
	(arc
		(start 147.301 90.412546)
		(mid 147.323836 90.297741)
		(end 147.388868 90.200414)
		(width 0.16)
		(layer "In3.Cu")
		(net 471)
	)
	(arc
		(start 81.782289 99.841237)
		(mid 81.857917 100.023821)
		(end 81.782288 100.206404)
		(width 0.16)
		(layer "In3.Cu")
		(net 471)
	)
	(arc
		(start 81.782288 100.206404)
		(mid 81.706659 100.388987)
		(end 81.782287 100.571571)
		(width 0.16)
		(layer "In3.Cu")
		(net 471)
	)
	(arc
		(start 81.358026 99.782141)
		(mid 81.540609 99.706512)
		(end 81.723193 99.78214)
		(width 0.16)
		(layer "In3.Cu")
		(net 471)
	)
	(arc
		(start 147.936868 90.001)
		(mid 147.994271 89.989582)
		(end 148.042934 89.957066)
		(width 0.16)
		(layer "In3.Cu")
		(net 471)
	)
	(arc
		(start 147.388868 91.099586)
		(mid 147.323836 91.002259)
		(end 147.301 90.887454)
		(width 0.16)
		(layer "In3.Cu")
		(net 471)
	)
	(segment
		(start 71.5755 76.081901)
		(end 71.5755 77.012368)
		(width 0.155)
		(layer "F.Cu")
		(net 472)
	)
	(segment
		(start 67.34427 73.805696)
		(end 68.491628 74.953054)
		(width 0.155)
		(layer "F.Cu")
		(net 472)
	)
	(segment
		(start 146.900206 90.211632)
		(end 146.832008 90.143434)
		(width 0.155)
		(layer "F.Cu")
		(net 472)
	)
	(segment
		(start 67.097323 72.005136)
		(end 67.097323 72.730136)
		(width 0.155)
		(layer "F.Cu")
		(net 472)
	)
	(segment
		(start 148.17 90.43)
		(end 148.083434 90.343434)
		(width 0.155)
		(layer "F.Cu")
		(net 472)
	)
	(segment
		(start 71.531566 77.118434)
		(end 71.42 77.23)
		(width 0.155)
		(layer "F.Cu")
		(net 472)
	)
	(segment
		(start 147.137368 90.2995)
		(end 147.112338 90.2995)
		(width 0.155)
		(layer "F.Cu")
		(net 472)
	)
	(segment
		(start 147.975501 90.2995)
		(end 147.868935 90.406066)
		(width 0.155)
		(layer "F.Cu")
		(net 472)
	)
	(segment
		(start 68.845181 75.0995)
		(end 70.593099 75.0995)
		(width 0.155)
		(layer "F.Cu")
		(net 472)
	)
	(segment
		(start 146.506566 90.143434)
		(end 146.3 90.35)
		(width 0.155)
		(layer "F.Cu")
		(net 472)
	)
	(segment
		(start 146.725942 90.0995)
		(end 146.612632 90.0995)
		(width 0.155)
		(layer "F.Cu")
		(net 472)
	)
	(segment
		(start 147.762869 90.45)
		(end 147.45 90.45)
		(width 0.155)
		(layer "F.Cu")
		(net 472)
	)
	(segment
		(start 67.197823 72.830636)
		(end 67.197823 73.452142)
		(width 0.155)
		(layer "F.Cu")
		(net 472)
	)
	(segment
		(start 70.840587 75.202013)
		(end 71.472988 75.834414)
		(width 0.155)
		(layer "F.Cu")
		(net 472)
	)
	(segment
		(start 147.35 90.45)
		(end 147.243434 90.343434)
		(width 0.155)
		(layer "F.Cu")
		(net 472)
	)
	(segment
		(start 67.097323 72.730136)
		(end 67.197823 72.830636)
		(width 0.155)
		(layer "F.Cu")
		(net 472)
	)
	(segment
		(start 147.977368 90.2995)
		(end 147.975501 90.2995)
		(width 0.155)
		(layer "F.Cu")
		(net 472)
	)
	(via
		(at 148.17 90.43)
		(size 0.45)
		(drill 0.1)
		(layers "F.Cu" "B.Cu")
		(net 472)
	)
	(via
		(at 71.42 77.23)
		(size 0.45)
		(drill 0.1)
		(layers "F.Cu" "B.Cu")
		(net 472)
	)
	(arc
		(start 147.868935 90.406066)
		(mid 147.820272 90.438582)
		(end 147.762869 90.45)
		(width 0.155)
		(layer "F.Cu")
		(net 472)
	)
	(arc
		(start 148.083434 90.343434)
		(mid 148.034771 90.310918)
		(end 147.977368 90.2995)
		(width 0.155)
		(layer "F.Cu")
		(net 472)
	)
	(arc
		(start 70.840587 75.202013)
		(mid 70.727039 75.126142)
		(end 70.593099 75.0995)
		(width 0.155)
		(layer "F.Cu")
		(net 472)
	)
	(arc
		(start 147.137368 90.2995)
		(mid 147.194771 90.310918)
		(end 147.243434 90.343434)
		(width 0.155)
		(layer "F.Cu")
		(net 472)
	)
	(arc
		(start 71.5755 77.012368)
		(mid 71.564082 77.069771)
		(end 71.531566 77.118434)
		(width 0.155)
		(layer "F.Cu")
		(net 472)
	)
	(arc
		(start 68.491628 74.953054)
		(mid 68.65384 75.06144)
		(end 68.845181 75.0995)
		(width 0.155)
		(layer "F.Cu")
		(net 472)
	)
	(arc
		(start 146.506566 90.143434)
		(mid 146.555229 90.110918)
		(end 146.612632 90.0995)
		(width 0.155)
		(layer "F.Cu")
		(net 472)
	)
	(arc
		(start 67.34427 73.805696)
		(mid 67.235883 73.643484)
		(end 67.197823 73.452142)
		(width 0.155)
		(layer "F.Cu")
		(net 472)
	)
	(arc
		(start 146.832008 90.143434)
		(mid 146.783345 90.110918)
		(end 146.725942 90.0995)
		(width 0.155)
		(layer "F.Cu")
		(net 472)
	)
	(arc
		(start 71.5755 76.081901)
		(mid 71.548858 75.947962)
		(end 71.472988 75.834414)
		(width 0.155)
		(layer "F.Cu")
		(net 472)
	)
	(arc
		(start 146.900206 90.211632)
		(mid 146.997533 90.276664)
		(end 147.112338 90.2995)
		(width 0.155)
		(layer "F.Cu")
		(net 472)
	)
	(segment
		(start 103.701 98.506693)
		(end 103.701 99.354611)
		(width 0.16)
		(layer "In3.Cu")
		(net 472)
	)
	(segment
		(start 82.131526 101.149)
		(end 87.804611 101.149)
		(width 0.16)
		(layer "In3.Cu")
		(net 472)
	)
	(segment
		(start 71.722446 87.033164)
		(end 72.591835 87.902553)
		(width 0.16)
		(layer "In3.Cu")
		(net 472)
	)
	(segment
		(start 107.401 103.406693)
		(end 107.401 103.704611)
		(width 0.16)
		(layer "In3.Cu")
		(net 472)
	)
	(segment
		(start 74.901 88.528139)
		(end 74.901 96.313103)
		(width 0.16)
		(layer "In3.Cu")
		(net 472)
	)
	(segment
		(start 148.082934 90.342934)
		(end 148.17 90.43)
		(width 0.16)
		(layer "In3.Cu")
		(net 472)
	)
	(segment
		(start 75.076797 96.737515)
		(end 76.576832 98.23755)
		(width 0.16)
		(layer "In3.Cu")
		(net 472)
	)
	(segment
		(start 93.886693 95.419)
		(end 100.613307 95.419)
		(width 0.16)
		(layer "In3.Cu")
		(net 472)
	)
	(segment
		(start 103.847446 99.708164)
		(end 107.298487 103.159205)
		(width 0.16)
		(layer "In3.Cu")
		(net 472)
	)
	(segment
		(start 88.158164 101.002554)
		(end 93.639205 95.521513)
		(width 0.16)
		(layer "In3.Cu")
		(net 472)
	)
	(segment
		(start 143.858164 98.252554)
		(end 147.652553 94.458165)
		(width 0.16)
		(layer "In3.Cu")
		(net 472)
	)
	(segment
		(start 78.656555 99.099)
		(end 79.586688 99.099)
		(width 0.16)
		(layer "In3.Cu")
		(net 472)
	)
	(segment
		(start 71.42 77.23)
		(end 71.532066 77.342066)
		(width 0.16)
		(layer "In3.Cu")
		(net 472)
	)
	(segment
		(start 147.799 94.104611)
		(end 147.799 91.212546)
		(width 0.16)
		(layer "In3.Cu")
		(net 472)
	)
	(segment
		(start 74.492572 88.07829)
		(end 74.871711 88.457429)
		(width 0.16)
		(layer "In3.Cu")
		(net 472)
	)
	(segment
		(start 147.642934 90.367784)
		(end 147.667784 90.342934)
		(width 0.16)
		(layer "In3.Cu")
		(net 472)
	)
	(segment
		(start 100.860794 95.521512)
		(end 103.598487 98.259205)
		(width 0.16)
		(layer "In3.Cu")
		(net 472)
	)
	(segment
		(start 111.940794 107.651512)
		(end 115.191835 110.902553)
		(width 0.16)
		(layer "In3.Cu")
		(net 472)
	)
	(segment
		(start 123.483164 110.902554)
		(end 135.884205 98.501513)
		(width 0.16)
		(layer "In3.Cu")
		(net 472)
	)
	(segment
		(start 80.101541 99.312259)
		(end 81.801638 101.012356)
		(width 0.16)
		(layer "In3.Cu")
		(net 472)
	)
	(segment
		(start 71.576 77.448132)
		(end 71.576 86.679611)
		(width 0.16)
		(layer "In3.Cu")
		(net 472)
	)
	(segment
		(start 147.77385 90.299)
		(end 147.976868 90.299)
		(width 0.16)
		(layer "In3.Cu")
		(net 472)
	)
	(segment
		(start 136.131693 98.399)
		(end 143.504611 98.399)
		(width 0.16)
		(layer "In3.Cu")
		(net 472)
	)
	(segment
		(start 115.545389 111.049)
		(end 123.129611 111.049)
		(width 0.16)
		(layer "In3.Cu")
		(net 472)
	)
	(segment
		(start 147.711132 91.000414)
		(end 147.642934 90.932216)
		(width 0.16)
		(layer "In3.Cu")
		(net 472)
	)
	(segment
		(start 147.599 90.82615)
		(end 147.599 90.47385)
		(width 0.16)
		(layer "In3.Cu")
		(net 472)
	)
	(segment
		(start 72.945389 88.049)
		(end 74.421861 88.049)
		(width 0.16)
		(layer "In3.Cu")
		(net 472)
	)
	(segment
		(start 107.547446 104.058164)
		(end 110.891835 107.402553)
		(width 0.16)
		(layer "In3.Cu")
		(net 472)
	)
	(segment
		(start 111.245389 107.549)
		(end 111.693307 107.549)
		(width 0.16)
		(layer "In3.Cu")
		(net 472)
	)
	(arc
		(start 115.191835 110.902553)
		(mid 115.354047 111.01094)
		(end 115.545389 111.049)
		(width 0.16)
		(layer "In3.Cu")
		(net 472)
	)
	(arc
		(start 107.401 103.704611)
		(mid 107.43906 103.895952)
		(end 107.547446 104.058164)
		(width 0.16)
		(layer "In3.Cu")
		(net 472)
	)
	(arc
		(start 147.976868 90.299)
		(mid 148.034271 90.310418)
		(end 148.082934 90.342934)
		(width 0.16)
		(layer "In3.Cu")
		(net 472)
	)
	(arc
		(start 74.901 88.528139)
		(mid 74.893388 88.489871)
		(end 74.871711 88.457429)
		(width 0.16)
		(layer "In3.Cu")
		(net 472)
	)
	(arc
		(start 111.693307 107.549)
		(mid 111.827246 107.575642)
		(end 111.940794 107.651512)
		(width 0.16)
		(layer "In3.Cu")
		(net 472)
	)
	(arc
		(start 81.801638 101.012356)
		(mid 81.952992 101.113487)
		(end 82.131526 101.149)
		(width 0.16)
		(layer "In3.Cu")
		(net 472)
	)
	(arc
		(start 143.504611 98.399)
		(mid 143.695952 98.36094)
		(end 143.858164 98.252554)
		(width 0.16)
		(layer "In3.Cu")
		(net 472)
	)
	(arc
		(start 147.642934 90.932216)
		(mid 147.610418 90.883553)
		(end 147.599 90.82615)
		(width 0.16)
		(layer "In3.Cu")
		(net 472)
	)
	(arc
		(start 100.613307 95.419)
		(mid 100.747246 95.445642)
		(end 100.860794 95.521512)
		(width 0.16)
		(layer "In3.Cu")
		(net 472)
	)
	(arc
		(start 72.591835 87.902553)
		(mid 72.754047 88.01094)
		(end 72.945389 88.049)
		(width 0.16)
		(layer "In3.Cu")
		(net 472)
	)
	(arc
		(start 71.532066 77.342066)
		(mid 71.564582 77.390729)
		(end 71.576 77.448132)
		(width 0.16)
		(layer "In3.Cu")
		(net 472)
	)
	(arc
		(start 103.701 99.354611)
		(mid 103.73906 99.545952)
		(end 103.847446 99.708164)
		(width 0.16)
		(layer "In3.Cu")
		(net 472)
	)
	(arc
		(start 147.799 91.212546)
		(mid 147.776164 91.097741)
		(end 147.711132 91.000414)
		(width 0.16)
		(layer "In3.Cu")
		(net 472)
	)
	(arc
		(start 123.129611 111.049)
		(mid 123.320952 111.01094)
		(end 123.483164 110.902554)
		(width 0.16)
		(layer "In3.Cu")
		(net 472)
	)
	(arc
		(start 93.639205 95.521513)
		(mid 93.752753 95.445642)
		(end 93.886693 95.419)
		(width 0.16)
		(layer "In3.Cu")
		(net 472)
	)
	(arc
		(start 147.667784 90.342934)
		(mid 147.716447 90.310418)
		(end 147.77385 90.299)
		(width 0.16)
		(layer "In3.Cu")
		(net 472)
	)
	(arc
		(start 75.076797 96.737515)
		(mid 74.946688 96.542793)
		(end 74.901 96.313103)
		(width 0.16)
		(layer "In3.Cu")
		(net 472)
	)
	(arc
		(start 103.598487 98.259205)
		(mid 103.674358 98.372753)
		(end 103.701 98.506693)
		(width 0.16)
		(layer "In3.Cu")
		(net 472)
	)
	(arc
		(start 74.492572 88.07829)
		(mid 74.46013 88.056612)
		(end 74.421861 88.049)
		(width 0.16)
		(layer "In3.Cu")
		(net 472)
	)
	(arc
		(start 87.804611 101.149)
		(mid 87.995952 101.11094)
		(end 88.158164 101.002554)
		(width 0.16)
		(layer "In3.Cu")
		(net 472)
	)
	(arc
		(start 107.298487 103.159205)
		(mid 107.374358 103.272753)
		(end 107.401 103.406693)
		(width 0.16)
		(layer "In3.Cu")
		(net 472)
	)
	(arc
		(start 147.599 90.47385)
		(mid 147.610418 90.416447)
		(end 147.642934 90.367784)
		(width 0.16)
		(layer "In3.Cu")
		(net 472)
	)
	(arc
		(start 71.576 86.679611)
		(mid 71.61406 86.870952)
		(end 71.722446 87.033164)
		(width 0.16)
		(layer "In3.Cu")
		(net 472)
	)
	(arc
		(start 110.891835 107.402553)
		(mid 111.054047 107.51094)
		(end 111.245389 107.549)
		(width 0.16)
		(layer "In3.Cu")
		(net 472)
	)
	(arc
		(start 147.652553 94.458165)
		(mid 147.76094 94.295953)
		(end 147.799 94.104611)
		(width 0.16)
		(layer "In3.Cu")
		(net 472)
	)
	(arc
		(start 135.884205 98.501513)
		(mid 135.997753 98.425642)
		(end 136.131693 98.399)
		(width 0.16)
		(layer "In3.Cu")
		(net 472)
	)
	(arc
		(start 76.576832 98.23755)
		(mid 77.531017 98.875117)
		(end 78.656555 99.099)
		(width 0.16)
		(layer "In3.Cu")
		(net 472)
	)
	(arc
		(start 79.586688 99.099)
		(mid 79.865324 99.154424)
		(end 80.101541 99.312259)
		(width 0.16)
		(layer "In3.Cu")
		(net 472)
	)
	(segment
		(start 65.300167 78.1)
		(end 65.55 78.1)
		(width 0.15)
		(layer "F.Cu")
		(net 473)
	)
	(segment
		(start 66.35 78.9)
		(end 66.6 78.9)
		(width 0.15)
		(layer "F.Cu")
		(net 473)
	)
	(segment
		(start 65.55 78.1)
		(end 66.35 78.9)
		(width 0.15)
		(layer "F.Cu")
		(net 473)
	)
	(segment
		(start 56.36 103.52)
		(end 56.36 103.98)
		(width 0.15)
		(layer "F.Cu")
		(net 473)
	)
	(segment
		(start 66.6 78.9)
		(end 66.847323 79.147323)
		(width 0.15)
		(layer "F.Cu")
		(net 473)
	)
	(segment
		(start 66.847323 79.147323)
		(end 66.847323 80.205136)
		(width 0.15)
		(layer "F.Cu")
		(net 473)
	)
	(segment
		(start 56.36 103.98)
		(end 56.45 104.07)
		(width 0.15)
		(layer "F.Cu")
		(net 473)
	)
	(segment
		(start 56.45 104.07)
		(end 56.45 104.35)
		(width 0.15)
		(layer "F.Cu")
		(net 473)
	)
	(via
		(at 56.36 103.52)
		(size 0.45)
		(drill 0.1)
		(layers "F.Cu" "B.Cu")
		(net 473)
	)
	(via
		(at 65.300167 78.1)
		(size 0.45)
		(drill 0.1)
		(layers "F.Cu" "B.Cu")
		(net 473)
	)
	(segment
		(start 54.24 93.96)
		(end 54.24 99.93)
		(width 0.125)
		(layer "In3.Cu")
		(net 473)
	)
	(segment
		(start 61.03 76.7)
		(end 60.3 77.43)
		(width 0.125)
		(layer "In3.Cu")
		(net 473)
	)
	(segment
		(start 60.3 87.05)
		(end 59.815 87.535)
		(width 0.125)
		(layer "In3.Cu")
		(net 473)
	)
	(segment
		(start 55.975 90.021446)
		(end 55.975 92.225)
		(width 0.125)
		(layer "In3.Cu")
		(net 473)
	)
	(segment
		(start 58.461446 87.535)
		(end 55.975 90.021446)
		(width 0.125)
		(layer "In3.Cu")
		(net 473)
	)
	(segment
		(start 56.36 102.05)
		(end 56.36 103.52)
		(width 0.125)
		(layer "In3.Cu")
		(net 473)
	)
	(segment
		(start 55.975 92.225)
		(end 54.24 93.96)
		(width 0.125)
		(layer "In3.Cu")
		(net 473)
	)
	(segment
		(start 65.300167 78.1)
		(end 65.300167 77.000167)
		(width 0.125)
		(layer "In3.Cu")
		(net 473)
	)
	(segment
		(start 59.815 87.535)
		(end 58.461446 87.535)
		(width 0.125)
		(layer "In3.Cu")
		(net 473)
	)
	(segment
		(start 65 76.7)
		(end 61.03 76.7)
		(width 0.125)
		(layer "In3.Cu")
		(net 473)
	)
	(segment
		(start 65.300167 77.000167)
		(end 65 76.7)
		(width 0.125)
		(layer "In3.Cu")
		(net 473)
	)
	(segment
		(start 54.24 99.93)
		(end 56.36 102.05)
		(width 0.125)
		(layer "In3.Cu")
		(net 473)
	)
	(segment
		(start 60.3 77.43)
		(end 60.3 87.05)
		(width 0.125)
		(layer "In3.Cu")
		(net 473)
	)
	(segment
		(start 65.745 77.054293)
		(end 65.745 75.875)
		(width 0.15)
		(layer "F.Cu")
		(net 474)
	)
	(segment
		(start 66.097323 75.522677)
		(end 66.097323 72.005136)
		(width 0.15)
		(layer "F.Cu")
		(net 474)
	)
	(segment
		(start 64.6 78.3)
		(end 64.6 78.199293)
		(width 0.15)
		(layer "F.Cu")
		(net 474)
	)
	(segment
		(start 64.6 78.199293)
		(end 65.745 77.054293)
		(width 0.15)
		(layer "F.Cu")
		(net 474)
	)
	(segment
		(start 65.745 75.875)
		(end 66.097323 75.522677)
		(width 0.15)
		(layer "F.Cu")
		(net 474)
	)
	(via
		(at 64.6 78.3)
		(size 0.45)
		(drill 0.1)
		(layers "F.Cu" "B.Cu")
		(net 474)
	)
	(segment
		(start 60.05 80.2)
		(end 59.25 81)
		(width 0.15)
		(layer "B.Cu")
		(net 474)
	)
	(segment
		(start 62.7 80.2)
		(end 60.05 80.2)
		(width 0.15)
		(layer "B.Cu")
		(net 474)
	)
	(segment
		(start 59.25 81)
		(end 57.62 81)
		(width 0.15)
		(layer "B.Cu")
		(net 474)
	)
	(segment
		(start 64.6 78.3)
		(end 62.7 80.2)
		(width 0.15)
		(layer "B.Cu")
		(net 474)
	)
	(segment
		(start 57.62 81)
		(end 57.32 80.7)
		(width 0.15)
		(layer "B.Cu")
		(net 474)
	)
	(via
		(at 56.5 85)
		(size 0.45)
		(drill 0.1)
		(layers "F.Cu" "B.Cu")
		(net 475)
	)
	(via
		(at 58.2826 108.30019)
		(size 0.45)
		(drill 0.1)
		(layers "F.Cu" "B.Cu")
		(net 475)
	)
	(segment
		(start 55.675 85.825)
		(end 55.675 92.025)
		(width 0.13)
		(layer "In3.Cu")
		(net 475)
	)
	(segment
		(start 55.675 92.025)
		(end 53.965 93.735)
		(width 0.13)
		(layer "In3.Cu")
		(net 475)
	)
	(segment
		(start 58.18279 108.4)
		(end 58.2826 108.30019)
		(width 0.13)
		(layer "In3.Cu")
		(net 475)
	)
	(segment
		(start 53.965 93.735)
		(end 53.965 105.665)
		(width 0.13)
		(layer "In3.Cu")
		(net 475)
	)
	(segment
		(start 56.7 108.4)
		(end 58.18279 108.4)
		(width 0.13)
		(layer "In3.Cu")
		(net 475)
	)
	(segment
		(start 53.965 105.665)
		(end 56.7 108.4)
		(width 0.13)
		(layer "In3.Cu")
		(net 475)
	)
	(segment
		(start 56.5 85)
		(end 55.675 85.825)
		(width 0.13)
		(layer "In3.Cu")
		(net 475)
	)
	(segment
		(start 60.54 80.6)
		(end 59.79 81.35)
		(width 0.15)
		(layer "B.Cu")
		(net 475)
	)
	(segment
		(start 56.05 84.551041)
		(end 56.498959 85)
		(width 0.15)
		(layer "B.Cu")
		(net 475)
	)
	(segment
		(start 58.2826 108.3826)
		(end 58.6 108.7)
		(width 0.16)
		(layer "B.Cu")
		(net 475)
	)
	(segment
		(start 67.825 80.8525)
		(end 67.825 81.715)
		(width 0.15)
		(layer "B.Cu")
		(net 475)
	)
	(segment
		(start 63.7 80.6)
		(end 60.54 80.6)
		(width 0.15)
		(layer "B.Cu")
		(net 475)
	)
	(segment
		(start 58.45 112.45)
		(end 58.035 112.45)
		(width 0.16)
		(layer "B.Cu")
		(net 475)
	)
	(segment
		(start 67.825 81.715)
		(end 67.258788 82.281212)
		(width 0.15)
		(layer "B.Cu")
		(net 475)
	)
	(segment
		(start 67.55 80.28)
		(end 67.55 80.5775)
		(width 0.15)
		(layer "B.Cu")
		(net 475)
	)
	(segment
		(start 56.05 82.26)
		(end 56.05 84.551041)
		(width 0.15)
		(layer "B.Cu")
		(net 475)
	)
	(segment
		(start 64.02 81.602754)
		(end 64.02 80.92)
		(width 0.15)
		(layer "B.Cu")
		(net 475)
	)
	(segment
		(start 64.698458 82.281212)
		(end 64.02 81.602754)
		(width 0.15)
		(layer "B.Cu")
		(net 475)
	)
	(segment
		(start 56.498959 85)
		(end 56.5 85)
		(width 0.15)
		(layer "B.Cu")
		(net 475)
	)
	(segment
		(start 58.83 110.23)
		(end 58.83 112.07)
		(width 0.16)
		(layer "B.Cu")
		(net 475)
	)
	(segment
		(start 58.6 108.7)
		(end 58.6 110)
		(width 0.16)
		(layer "B.Cu")
		(net 475)
	)
	(segment
		(start 59.79 81.35)
		(end 56.96 81.35)
		(width 0.15)
		(layer "B.Cu")
		(net 475)
	)
	(segment
		(start 58.2826 108.30019)
		(end 58.2826 108.3826)
		(width 0.16)
		(layer "B.Cu")
		(net 475)
	)
	(segment
		(start 67.258788 82.281212)
		(end 64.698458 82.281212)
		(width 0.15)
		(layer "B.Cu")
		(net 475)
	)
	(segment
		(start 56.96 81.35)
		(end 56.05 82.26)
		(width 0.15)
		(layer "B.Cu")
		(net 475)
	)
	(segment
		(start 58.6 110)
		(end 58.83 110.23)
		(width 0.16)
		(layer "B.Cu")
		(net 475)
	)
	(segment
		(start 67.55 80.5775)
		(end 67.825 80.8525)
		(width 0.15)
		(layer "B.Cu")
		(net 475)
	)
	(segment
		(start 64.02 80.92)
		(end 63.7 80.6)
		(width 0.15)
		(layer "B.Cu")
		(net 475)
	)
	(segment
		(start 58.83 112.07)
		(end 58.45 112.45)
		(width 0.16)
		(layer "B.Cu")
		(net 475)
	)
	(segment
		(start 64.55 77.15)
		(end 64.55 73.6)
		(width 0.15)
		(layer "F.Cu")
		(net 476)
	)
	(segment
		(start 65.097323 73.052677)
		(end 65.097323 72.005136)
		(width 0.15)
		(layer "F.Cu")
		(net 476)
	)
	(segment
		(start 64.6 77.2)
		(end 64.55 77.15)
		(width 0.15)
		(layer "F.Cu")
		(net 476)
	)
	(segment
		(start 64.55 73.6)
		(end 65.097323 73.052677)
		(width 0.15)
		(layer "F.Cu")
		(net 476)
	)
	(via
		(at 64.6 77.2)
		(size 0.45)
		(drill 0.1)
		(layers "F.Cu" "B.Cu")
		(net 476)
	)
	(segment
		(start 64.6 77.2)
		(end 64.6 77.285)
		(width 0.15)
		(layer "B.Cu")
		(net 476)
	)
	(segment
		(start 64.6 77.285)
		(end 64.815 77.5)
		(width 0.15)
		(layer "B.Cu")
		(net 476)
	)
	(via
		(at 58.028373 108.865324)
		(size 0.45)
		(drill 0.1)
		(layers "F.Cu" "B.Cu")
		(net 477)
	)
	(via
		(at 56.475 84.375)
		(size 0.45)
		(drill 0.1)
		(layers "F.Cu" "B.Cu")
		(net 477)
	)
	(segment
		(start 53.69 93.51)
		(end 55.4 91.8)
		(width 0.13)
		(layer "In3.Cu")
		(net 477)
	)
	(segment
		(start 56.765324 108.865324)
		(end 53.69 105.79)
		(width 0.13)
		(layer "In3.Cu")
		(net 477)
	)
	(segment
		(start 55.4 91.8)
		(end 55.4 85.45)
		(width 0.13)
		(layer "In3.Cu")
		(net 477)
	)
	(segment
		(start 53.69 105.79)
		(end 53.69 93.51)
		(width 0.13)
		(layer "In3.Cu")
		(net 477)
	)
	(segment
		(start 55.4 85.45)
		(end 56.475 84.375)
		(width 0.13)
		(layer "In3.Cu")
		(net 477)
	)
	(segment
		(start 58.028373 108.865324)
		(end 56.765324 108.865324)
		(width 0.13)
		(layer "In3.Cu")
		(net 477)
	)
	(segment
		(start 68.15 80)
		(end 68.15 81.85)
		(width 0.15)
		(layer "B.Cu")
		(net 477)
	)
	(segment
		(start 63.745 81.055)
		(end 63.565 80.875)
		(width 0.15)
		(layer "B.Cu")
		(net 477)
	)
	(segment
		(start 67.55 79.695)
		(end 67.845 79.695)
		(width 0.15)
		(layer "B.Cu")
		(net 477)
	)
	(segment
		(start 68.15 81.85)
		(end 67.443788 82.556212)
		(width 0.15)
		(layer "B.Cu")
		(net 477)
	)
	(segment
		(start 57.15 81.65)
		(end 56.335 82.465)
		(width 0.15)
		(layer "B.Cu")
		(net 477)
	)
	(segment
		(start 60.775 80.875)
		(end 60 81.65)
		(width 0.15)
		(layer "B.Cu")
		(net 477)
	)
	(segment
		(start 63.745 81.845)
		(end 63.745 81.055)
		(width 0.15)
		(layer "B.Cu")
		(net 477)
	)
	(segment
		(start 56.335 82.465)
		(end 56.335 84.235)
		(width 0.15)
		(layer "B.Cu")
		(net 477)
	)
	(segment
		(start 67.845 79.695)
		(end 68.15 80)
		(width 0.15)
		(layer "B.Cu")
		(net 477)
	)
	(segment
		(start 60 81.65)
		(end 57.15 81.65)
		(width 0.15)
		(layer "B.Cu")
		(net 477)
	)
	(segment
		(start 56.335 84.235)
		(end 56.475 84.375)
		(width 0.15)
		(layer "B.Cu")
		(net 477)
	)
	(segment
		(start 63.565 80.875)
		(end 60.775 80.875)
		(width 0.15)
		(layer "B.Cu")
		(net 477)
	)
	(segment
		(start 57.935 108.958697)
		(end 57.935 109.45)
		(width 0.15)
		(layer "B.Cu")
		(net 477)
	)
	(segment
		(start 64.456212 82.556212)
		(end 63.745 81.845)
		(width 0.15)
		(layer "B.Cu")
		(net 477)
	)
	(segment
		(start 58.028373 108.865324)
		(end 57.935 108.958697)
		(width 0.15)
		(layer "B.Cu")
		(net 477)
	)
	(segment
		(start 67.443788 82.556212)
		(end 64.456212 82.556212)
		(width 0.15)
		(layer "B.Cu")
		(net 477)
	)
	(segment
		(start 64.347323 81.222823)
		(end 64.347323 80.205136)
		(width 0.15)
		(layer "F.Cu")
		(net 478)
	)
	(segment
		(start 64.5245 81.4)
		(end 64.347323 81.222823)
		(width 0.15)
		(layer "F.Cu")
		(net 478)
	)
	(via
		(at 51.46 75.45)
		(size 0.45)
		(drill 0.1)
		(layers "F.Cu" "B.Cu")
		(net 478)
	)
	(via
		(at 64.5245 81.4)
		(size 0.45)
		(drill 0.1)
		(layers "F.Cu" "B.Cu")
		(net 478)
	)
	(segment
		(start 60.4 82.3)
		(end 53.55 75.45)
		(width 0.15)
		(layer "In1.Cu")
		(net 478)
	)
	(segment
		(start 63.6245 82.3)
		(end 60.4 82.3)
		(width 0.15)
		(layer "In1.Cu")
		(net 478)
	)
	(segment
		(start 53.55 75.45)
		(end 51.46 75.45)
		(width 0.15)
		(layer "In1.Cu")
		(net 478)
	)
	(segment
		(start 64.5245 81.4)
		(end 63.6245 82.3)
		(width 0.15)
		(layer "In1.Cu")
		(net 478)
	)
	(segment
		(start 63.205 71.3)
		(end 62.515 71.3)
		(width 0.125)
		(layer "B.Cu")
		(net 478)
	)
	(segment
		(start 52.51 72.65)
		(end 52.51 74.4)
		(width 0.125)
		(layer "B.Cu")
		(net 478)
	)
	(segment
		(start 62.515 71.3)
		(end 61.215 70)
		(width 0.125)
		(layer "B.Cu")
		(net 478)
	)
	(segment
		(start 53.43 71.73)
		(end 52.51 72.65)
		(width 0.125)
		(layer "B.Cu")
		(net 478)
	)
	(segment
		(start 52.51 74.4)
		(end 51.46 75.45)
		(width 0.125)
		(layer "B.Cu")
		(net 478)
	)
	(segment
		(start 54.71 71.73)
		(end 53.43 71.73)
		(width 0.125)
		(layer "B.Cu")
		(net 478)
	)
	(segment
		(start 61.215 70)
		(end 56.44 70)
		(width 0.125)
		(layer "B.Cu")
		(net 478)
	)
	(segment
		(start 56.44 70)
		(end 54.71 71.73)
		(width 0.125)
		(layer "B.Cu")
		(net 478)
	)
	(segment
		(start 138 111.9)
		(end 141.45 111.9)
		(width 0.3)
		(layer "F.Cu")
		(net 483)
	)
	(segment
		(start 137.9 111.8)
		(end 137.9 113.085)
		(width 0.3)
		(layer "F.Cu")
		(net 483)
	)
	(segment
		(start 143.1 114.9)
		(end 143.1 112.8)
		(width 0.3)
		(layer "F.Cu")
		(net 484)
	)
	(segment
		(start 142.1 115.9)
		(end 143.1 114.9)
		(width 0.3)
		(layer "F.Cu")
		(net 484)
	)
	(segment
		(start 143.87 112.03)
		(end 145.92 112.03)
		(width 0.3)
		(layer "F.Cu")
		(net 484)
	)
	(segment
		(start 143.1 112.8)
		(end 143.87 112.03)
		(width 0.3)
		(layer "F.Cu")
		(net 484)
	)
	(segment
		(start 146.65 111.95)
		(end 147.49 112.79)
		(width 0.3)
		(layer "F.Cu")
		(net 484)
	)
	(segment
		(start 146 111.95)
		(end 146.65 111.95)
		(width 0.3)
		(layer "F.Cu")
		(net 484)
	)
	(segment
		(start 137.9 115.9)
		(end 142.1 115.9)
		(width 0.3)
		(layer "F.Cu")
		(net 484)
	)
	(segment
		(start 93.855 105.531777)
		(end 93.855 114.711778)
		(width 0.125)
		(layer "F.Cu")
		(net 486)
	)
	(segment
		(start 92.475 104.151777)
		(end 93.855 105.531777)
		(width 0.125)
		(layer "F.Cu")
		(net 486)
	)
	(segment
		(start 91.545 97.195)
		(end 91.852451 97.195)
		(width 0.125)
		(layer "F.Cu")
		(net 486)
	)
	(segment
		(start 90.095 95.455)
		(end 90.498222 95.455)
		(width 0.125)
		(layer "F.Cu")
		(net 486)
	)
	(segment
		(start 96.95 116.496778)
		(end 96.95 117.925)
		(width 0.125)
		(layer "F.Cu")
		(net 486)
	)
	(segment
		(start 91.045 96.001778)
		(end 91.045 96.695)
		(width 0.125)
		(layer "F.Cu")
		(net 486)
	)
	(segment
		(start 88.981778 95.455)
		(end 89.245 95.455)
		(width 0.125)
		(layer "F.Cu")
		(net 486)
	)
	(segment
		(start 91.045 98.861225)
		(end 91.045 101.041778)
		(width 0.125)
		(layer "F.Cu")
		(net 486)
	)
	(segment
		(start 90.337549 98.111225)
		(end 90.337549 98.278775)
		(width 0.125)
		(layer "F.Cu")
		(net 486)
	)
	(segment
		(start 92.475 102.471778)
		(end 92.475 104.151777)
		(width 0.125)
		(layer "F.Cu")
		(net 486)
	)
	(segment
		(start 91.045 101.041778)
		(end 92.475 102.471778)
		(width 0.125)
		(layer "F.Cu")
		(net 486)
	)
	(segment
		(start 88.7375 96.36)
		(end 88.575 96.1975)
		(width 0.125)
		(layer "F.Cu")
		(net 486)
	)
	(segment
		(start 96.95 117.925)
		(end 96.875 118)
		(width 0.125)
		(layer "F.Cu")
		(net 486)
	)
	(segment
		(start 96.458222 116.005)
		(end 96.95 116.496778)
		(width 0.125)
		(layer "F.Cu")
		(net 486)
	)
	(segment
		(start 90.498222 95.455)
		(end 91.045 96.001778)
		(width 0.125)
		(layer "F.Cu")
		(net 486)
	)
	(segment
		(start 90.753774 98.695)
		(end 90.878775 98.695)
		(width 0.125)
		(layer "F.Cu")
		(net 486)
	)
	(segment
		(start 88.575 96.1975)
		(end 88.575 95.861778)
		(width 0.125)
		(layer "F.Cu")
		(net 486)
	)
	(segment
		(start 95.148222 116.005)
		(end 96.458222 116.005)
		(width 0.125)
		(layer "F.Cu")
		(net 486)
	)
	(segment
		(start 90.753774 97.695)
		(end 91.852451 97.695)
		(width 0.125)
		(layer "F.Cu")
		(net 486)
	)
	(segment
		(start 89.845 96.06373)
		(end 89.845 95.655)
		(width 0.125)
		(layer "F.Cu")
		(net 486)
	)
	(segment
		(start 88.575 95.861778)
		(end 88.981778 95.455)
		(width 0.125)
		(layer "F.Cu")
		(net 486)
	)
	(segment
		(start 90.045 95.455)
		(end 90.095 95.455)
		(width 0.125)
		(layer "F.Cu")
		(net 486)
	)
	(segment
		(start 89.445 95.655)
		(end 89.445 96.06373)
		(width 0.125)
		(layer "F.Cu")
		(net 486)
	)
	(segment
		(start 93.855 114.711778)
		(end 95.148222 116.005)
		(width 0.125)
		(layer "F.Cu")
		(net 486)
	)
	(via
		(at 88.7375 96.36)
		(size 0.45)
		(drill 0.1)
		(layers "F.Cu" "B.Cu")
		(net 486)
	)
	(arc
		(start 90.337549 98.278775)
		(mid 90.459458 98.573091)
		(end 90.753774 98.695)
		(width 0.125)
		(layer "F.Cu")
		(net 486)
	)
	(arc
		(start 91.852451 97.195)
		(mid 92.029228 97.268223)
		(end 92.102451 97.445)
		(width 0.125)
		(layer "F.Cu")
		(net 486)
	)
	(arc
		(start 90.753774 97.695)
		(mid 90.459458 97.816909)
		(end 90.337549 98.111225)
		(width 0.125)
		(layer "F.Cu")
		(net 486)
	)
	(arc
		(start 90.878775 98.695)
		(mid 90.996314 98.743686)
		(end 91.045 98.861225)
		(width 0.125)
		(layer "F.Cu")
		(net 486)
	)
	(arc
		(start 89.245 95.455)
		(mid 89.386421 95.513579)
		(end 89.445 95.655)
		(width 0.125)
		(layer "F.Cu")
		(net 486)
	)
	(arc
		(start 89.445 96.06373)
		(mid 89.503579 96.205151)
		(end 89.645 96.26373)
		(width 0.125)
		(layer "F.Cu")
		(net 486)
	)
	(arc
		(start 89.645 96.26373)
		(mid 89.786421 96.205151)
		(end 89.845 96.06373)
		(width 0.125)
		(layer "F.Cu")
		(net 486)
	)
	(arc
		(start 92.102451 97.445)
		(mid 92.029228 97.621777)
		(end 91.852451 97.695)
		(width 0.125)
		(layer "F.Cu")
		(net 486)
	)
	(arc
		(start 89.845 95.655)
		(mid 89.903579 95.513579)
		(end 90.045 95.455)
		(width 0.125)
		(layer "F.Cu")
		(net 486)
	)
	(arc
		(start 91.045 96.695)
		(mid 91.191447 97.048553)
		(end 91.545 97.195)
		(width 0.125)
		(layer "F.Cu")
		(net 486)
	)
	(segment
		(start 89.5075 95.825)
		(end 88.871778 95.825)
		(width 0.125)
		(layer "B.Cu")
		(net 486)
	)
	(segment
		(start 89.6325 95.95)
		(end 89.5075 95.825)
		(width 0.125)
		(layer "B.Cu")
		(net 486)
	)
	(segment
		(start 88.575 96.1975)
		(end 88.7375 96.36)
		(width 0.125)
		(layer "B.Cu")
		(net 486)
	)
	(segment
		(start 88.871778 95.825)
		(end 88.575 96.121778)
		(width 0.125)
		(layer "B.Cu")
		(net 486)
	)
	(segment
		(start 88.575 96.121778)
		(end 88.575 96.1975)
		(width 0.125)
		(layer "B.Cu")
		(net 486)
	)
	(segment
		(start 95.998222 117.155)
		(end 95.691777 117.155)
		(width 0.125)
		(layer "F.Cu")
		(net 487)
	)
	(segment
		(start 95.691777 117.155)
		(end 95.533294 117.313483)
		(width 0.125)
		(layer "F.Cu")
		(net 487)
	)
	(segment
		(start 96.15 117.925)
		(end 96.15 117.306778)
		(width 0.125)
		(layer "F.Cu")
		(net 487)
	)
	(segment
		(start 96.15 117.306778)
		(end 95.998222 117.155)
		(width 0.125)
		(layer "F.Cu")
		(net 487)
	)
	(segment
		(start 95.533294 117.313483)
		(end 95.533294 117.543294)
		(width 0.125)
		(layer "F.Cu")
		(net 487)
	)
	(segment
		(start 96.075 118)
		(end 96.15 117.925)
		(width 0.125)
		(layer "F.Cu")
		(net 487)
	)
	(via
		(at 95.533294 117.543294)
		(size 0.45)
		(drill 0.1)
		(layers "F.Cu" "B.Cu")
		(net 487)
	)
	(segment
		(start 94.45 113.398222)
		(end 94.845 113.793222)
		(width 0.125)
		(layer "B.Cu")
		(net 487)
	)
	(segment
		(start 89.610811 99.534035)
		(end 89.610811 99.534034)
		(width 0.125)
		(layer "B.Cu")
		(net 487)
	)
	(segment
		(start 95.765 117.081777)
		(end 95.533294 117.313483)
		(width 0.125)
		(layer "B.Cu")
		(net 487)
	)
	(segment
		(start 88.750456 99.722639)
		(end 88.750455 99.72264)
		(width 0.125)
		(layer "B.Cu")
		(net 487)
	)
	(segment
		(start 89.610811 99.534034)
		(end 91.851777 101.775)
		(width 0.125)
		(layer "B.Cu")
		(net 487)
	)
	(segment
		(start 94.845 115.198222)
		(end 95.765 116.118222)
		(width 0.125)
		(layer "B.Cu")
		(net 487)
	)
	(segment
		(start 88.444087 98.049112)
		(end 88.632691 97.860505)
		(width 0.125)
		(layer "B.Cu")
		(net 487)
	)
	(segment
		(start 88.221778 94.825)
		(end 87.425 95.621778)
		(width 0.125)
		(layer "B.Cu")
		(net 487)
	)
	(segment
		(start 95.533294 117.313483)
		(end 95.533294 117.543294)
		(width 0.125)
		(layer "B.Cu")
		(net 487)
	)
	(segment
		(start 87.425 97.348222)
		(end 88.125887 98.04911)
		(width 0.125)
		(layer "B.Cu")
		(net 487)
	)
	(segment
		(start 94.845 113.793222)
		(end 94.845 115.198222)
		(width 0.125)
		(layer "B.Cu")
		(net 487)
	)
	(segment
		(start 89.304442 98.532256)
		(end 88.432257 99.404442)
		(width 0.125)
		(layer "B.Cu")
		(net 487)
	)
	(segment
		(start 95.765 116.118222)
		(end 95.765 117.081777)
		(width 0.125)
		(layer "B.Cu")
		(net 487)
	)
	(segment
		(start 94.45 104.773222)
		(end 94.45 113.398222)
		(width 0.125)
		(layer "B.Cu")
		(net 487)
	)
	(segment
		(start 92.751778 101.775)
		(end 93.275 102.298222)
		(width 0.125)
		(layer "B.Cu")
		(net 487)
	)
	(segment
		(start 91.851777 101.775)
		(end 92.751778 101.775)
		(width 0.125)
		(layer "B.Cu")
		(net 487)
	)
	(segment
		(start 87.425 95.621778)
		(end 87.425 97.348222)
		(width 0.125)
		(layer "B.Cu")
		(net 487)
	)
	(segment
		(start 93.275 103.598222)
		(end 94.45 104.773222)
		(width 0.125)
		(layer "B.Cu")
		(net 487)
	)
	(segment
		(start 89.304442 97.860506)
		(end 89.304443 97.860506)
		(width 0.125)
		(layer "B.Cu")
		(net 487)
	)
	(segment
		(start 89.6325 94.95)
		(end 89.5075 94.825)
		(width 0.125)
		(layer "B.Cu")
		(net 487)
	)
	(segment
		(start 88.750455 99.72264)
		(end 88.93906 99.534034)
		(width 0.125)
		(layer "B.Cu")
		(net 487)
	)
	(segment
		(start 89.304442 98.532257)
		(end 89.304442 98.532256)
		(width 0.125)
		(layer "B.Cu")
		(net 487)
	)
	(segment
		(start 93.275 102.298222)
		(end 93.275 103.598222)
		(width 0.125)
		(layer "B.Cu")
		(net 487)
	)
	(segment
		(start 89.5075 94.825)
		(end 88.221778 94.825)
		(width 0.125)
		(layer "B.Cu")
		(net 487)
	)
	(arc
		(start 88.93906 99.534034)
		(mid 89.274936 99.39491)
		(end 89.610811 99.534035)
		(width 0.125)
		(layer "B.Cu")
		(net 487)
	)
	(arc
		(start 88.125887 98.04911)
		(mid 88.284988 98.115013)
		(end 88.444087 98.049112)
		(width 0.125)
		(layer "B.Cu")
		(net 487)
	)
	(arc
		(start 88.432257 99.404442)
		(mid 88.366356 99.563541)
		(end 88.432257 99.72264)
		(width 0.125)
		(layer "B.Cu")
		(net 487)
	)
	(arc
		(start 88.632691 97.860505)
		(mid 88.968567 97.721381)
		(end 89.304442 97.860506)
		(width 0.125)
		(layer "B.Cu")
		(net 487)
	)
	(arc
		(start 88.432257 99.72264)
		(mid 88.591357 99.788541)
		(end 88.750456 99.722639)
		(width 0.125)
		(layer "B.Cu")
		(net 487)
	)
	(arc
		(start 89.304443 97.860506)
		(mid 89.443567 98.196382)
		(end 89.304442 98.532257)
		(width 0.125)
		(layer "B.Cu")
		(net 487)
	)
	(segment
		(start 87.898222 93.825)
		(end 87.4925 93.825)
		(width 0.125)
		(layer "F.Cu")
		(net 488)
	)
	(segment
		(start 87.400712 98.34938)
		(end 87.400712 98.349381)
		(width 0.125)
		(layer "F.Cu")
		(net 488)
	)
	(segment
		(start 88.900804 97.521042)
		(end 88.072464 98.349382)
		(width 0.125)
		(layer "F.Cu")
		(net 488)
	)
	(segment
		(start 93.9 117.925)
		(end 93.9 116.576778)
		(width 0.125)
		(layer "F.Cu")
		(net 488)
	)
	(segment
		(start 87.266635 95.109097)
		(end 87.250283 95.092745)
		(width 0.125)
		(layer "F.Cu")
		(net 488)
	)
	(segment
		(start 87.400711 97.67763)
		(end 87.400712 97.677629)
		(width 0.125)
		(layer "F.Cu")
		(net 488)
	)
	(segment
		(start 92.685 115.361778)
		(end 92.685 111.061778)
		(width 0.125)
		(layer "F.Cu")
		(net 488)
	)
	(segment
		(start 86.825 96.591777)
		(end 87.496683 97.263457)
		(width 0.125)
		(layer "F.Cu")
		(net 488)
	)
	(segment
		(start 87.250283 94.845258)
		(end 87.250282 94.845258)
		(width 0.125)
		(layer "F.Cu")
		(net 488)
	)
	(segment
		(start 90.675 104.451777)
		(end 89.675 103.451777)
		(width 0.125)
		(layer "F.Cu")
		(net 488)
	)
	(segment
		(start 88.125 94.051778)
		(end 87.898222 93.825)
		(width 0.125)
		(layer "F.Cu")
		(net 488)
	)
	(segment
		(start 89.675 99.441777)
		(end 88.98161 98.748386)
		(width 0.125)
		(layer "F.Cu")
		(net 488)
	)
	(segment
		(start 87.761611 94.861611)
		(end 88.125 94.498222)
		(width 0.125)
		(layer "F.Cu")
		(net 488)
	)
	(segment
		(start 90.675 109.051778)
		(end 90.675 104.451777)
		(width 0.125)
		(layer "F.Cu")
		(net 488)
	)
	(segment
		(start 88.125 94.498222)
		(end 88.125 94.051778)
		(width 0.125)
		(layer "F.Cu")
		(net 488)
	)
	(segment
		(start 88.98161 98.076634)
		(end 89.219003 97.83924)
		(width 0.125)
		(layer "F.Cu")
		(net 488)
	)
	(segment
		(start 87.400712 97.677629)
		(end 87.496683 97.581655)
		(width 0.125)
		(layer "F.Cu")
		(net 488)
	)
	(segment
		(start 87.49777 94.845258)
		(end 87.514123 94.861611)
		(width 0.125)
		(layer "F.Cu")
		(net 488)
	)
	(segment
		(start 87.250283 95.092745)
		(end 87.250283 95.092744)
		(width 0.125)
		(layer "F.Cu")
		(net 488)
	)
	(segment
		(start 86.825 96.591777)
		(end 86.825 95.798222)
		(width 0.125)
		(layer "F.Cu")
		(net 488)
	)
	(segment
		(start 88.900804 97.521041)
		(end 88.900804 97.521042)
		(width 0.125)
		(layer "F.Cu")
		(net 488)
	)
	(segment
		(start 86.825 95.798222)
		(end 87.266635 95.356585)
		(width 0.125)
		(layer "F.Cu")
		(net 488)
	)
	(segment
		(start 87.4925 93.825)
		(end 87.33 93.9875)
		(width 0.125)
		(layer "F.Cu")
		(net 488)
	)
	(segment
		(start 93.9 116.576778)
		(end 92.685 115.361778)
		(width 0.125)
		(layer "F.Cu")
		(net 488)
	)
	(segment
		(start 89.675 103.451777)
		(end 89.675 99.441777)
		(width 0.125)
		(layer "F.Cu")
		(net 488)
	)
	(segment
		(start 93.825 118)
		(end 93.9 117.925)
		(width 0.125)
		(layer "F.Cu")
		(net 488)
	)
	(segment
		(start 92.685 111.061778)
		(end 90.675 109.051778)
		(width 0.125)
		(layer "F.Cu")
		(net 488)
	)
	(via
		(at 87.33 93.9875)
		(size 0.45)
		(drill 0.1)
		(layers "F.Cu" "B.Cu")
		(net 488)
	)
	(arc
		(start 87.514123 94.861611)
		(mid 87.637867 94.912867)
		(end 87.761611 94.861611)
		(width 0.125)
		(layer "F.Cu")
		(net 488)
	)
	(arc
		(start 89.219003 97.521042)
		(mid 89.059904 97.45514)
		(end 88.900804 97.521041)
		(width 0.125)
		(layer "F.Cu")
		(net 488)
	)
	(arc
		(start 89.219003 97.83924)
		(mid 89.284904 97.680141)
		(end 89.219003 97.521042)
		(width 0.125)
		(layer "F.Cu")
		(net 488)
	)
	(arc
		(start 87.496683 97.581655)
		(mid 87.562584 97.422556)
		(end 87.496683 97.263457)
		(width 0.125)
		(layer "F.Cu")
		(net 488)
	)
	(arc
		(start 88.98161 98.748386)
		(mid 88.842486 98.41251)
		(end 88.98161 98.076634)
		(width 0.125)
		(layer "F.Cu")
		(net 488)
	)
	(arc
		(start 87.266635 95.356585)
		(mid 87.317891 95.232841)
		(end 87.266635 95.109097)
		(width 0.125)
		(layer "F.Cu")
		(net 488)
	)
	(arc
		(start 87.400712 98.349381)
		(mid 87.261587 98.013506)
		(end 87.400711 97.67763)
		(width 0.125)
		(layer "F.Cu")
		(net 488)
	)
	(arc
		(start 88.072464 98.349382)
		(mid 87.736588 98.488505)
		(end 87.400712 98.34938)
		(width 0.125)
		(layer "F.Cu")
		(net 488)
	)
	(arc
		(start 87.250282 94.845258)
		(mid 87.374026 94.794002)
		(end 87.49777 94.845258)
		(width 0.125)
		(layer "F.Cu")
		(net 488)
	)
	(arc
		(start 87.250283 95.092744)
		(mid 87.199027 94.969001)
		(end 87.250283 94.845258)
		(width 0.125)
		(layer "F.Cu")
		(net 488)
	)
	(segment
		(start 87.4925 93.825)
		(end 87.33 93.9875)
		(width 0.125)
		(layer "B.Cu")
		(net 488)
	)
	(segment
		(start 89.5075 93.825)
		(end 87.4925 93.825)
		(width 0.125)
		(layer "B.Cu")
		(net 488)
	)
	(segment
		(start 89.6325 93.95)
		(end 89.5075 93.825)
		(width 0.125)
		(layer "B.Cu")
		(net 488)
	)
	(segment
		(start 92.543294 117.663294)
		(end 92.543294 117.433483)
		(width 0.125)
		(layer "F.Cu")
		(net 489)
	)
	(segment
		(start 92.661777 117.315)
		(end 92.918222 117.315)
		(width 0.125)
		(layer "F.Cu")
		(net 489)
	)
	(segment
		(start 93.1 117.925)
		(end 93.025 118)
		(width 0.125)
		(layer "F.Cu")
		(net 489)
	)
	(segment
		(start 92.918222 117.315)
		(end 93.1 117.496778)
		(width 0.125)
		(layer "F.Cu")
		(net 489)
	)
	(segment
		(start 93.1 117.496778)
		(end 93.1 117.925)
		(width 0.125)
		(layer "F.Cu")
		(net 489)
	)
	(segment
		(start 92.543294 117.433483)
		(end 92.661777 117.315)
		(width 0.125)
		(layer "F.Cu")
		(net 489)
	)
	(via
		(at 92.543294 117.663294)
		(size 0.45)
		(drill 0.1)
		(layers "F.Cu" "B.Cu")
		(net 489)
	)
	(segment
		(start 90.051778 103.175)
		(end 90.751777 103.175)
		(width 0.125)
		(layer "B.Cu")
		(net 489)
	)
	(segment
		(start 93.725 115.225)
		(end 93.869564 115.225)
		(width 0.125)
		(layer "B.Cu")
		(net 489)
	)
	(segment
		(start 93.475 116.025)
		(end 93.475 116.501777)
		(width 0.125)
		(layer "B.Cu")
		(net 489)
	)
	(segment
		(start 89.5075 92.825)
		(end 86.741778 92.825)
		(width 0.125)
		(layer "B.Cu")
		(net 489)
	)
	(segment
		(start 86.205 93.361778)
		(end 86.205 99.328222)
		(width 0.125)
		(layer "B.Cu")
		(net 489)
	)
	(segment
		(start 86.741778 92.825)
		(end 86.205 93.361778)
		(width 0.125)
		(layer "B.Cu")
		(net 489)
	)
	(segment
		(start 86.205 99.328222)
		(end 90.051778 103.175)
		(width 0.125)
		(layer "B.Cu")
		(net 489)
	)
	(segment
		(start 92.543294 117.433483)
		(end 92.543294 117.663294)
		(width 0.125)
		(layer "B.Cu")
		(net 489)
	)
	(segment
		(start 93.475 116.501777)
		(end 92.543294 117.433483)
		(width 0.125)
		(layer "B.Cu")
		(net 489)
	)
	(segment
		(start 90.751777 103.175)
		(end 93.475 105.898223)
		(width 0.125)
		(layer "B.Cu")
		(net 489)
	)
	(segment
		(start 93.475 115.975)
		(end 93.475 116.025)
		(width 0.125)
		(layer "B.Cu")
		(net 489)
	)
	(segment
		(start 93.475 105.898223)
		(end 93.475 114.975)
		(width 0.125)
		(layer "B.Cu")
		(net 489)
	)
	(segment
		(start 89.6325 92.95)
		(end 89.5075 92.825)
		(width 0.125)
		(layer "B.Cu")
		(net 489)
	)
	(segment
		(start 93.869564 115.725)
		(end 93.725 115.725)
		(width 0.125)
		(layer "B.Cu")
		(net 489)
	)
	(arc
		(start 93.475 114.975)
		(mid 93.548223 115.151777)
		(end 93.725 115.225)
		(width 0.125)
		(layer "B.Cu")
		(net 489)
	)
	(arc
		(start 93.725 115.725)
		(mid 93.548223 115.798223)
		(end 93.475 115.975)
		(width 0.125)
		(layer "B.Cu")
		(net 489)
	)
	(arc
		(start 93.869564 115.225)
		(mid 94.046341 115.298223)
		(end 94.119564 115.475)
		(width 0.125)
		(layer "B.Cu")
		(net 489)
	)
	(arc
		(start 94.119564 115.475)
		(mid 94.046341 115.651777)
		(end 93.869564 115.725)
		(width 0.125)
		(layer "B.Cu")
		(net 489)
	)
	(segment
		(start 75.425 104.892469)
		(end 75.425 102.508223)
		(width 0.125)
		(layer "F.Cu")
		(net 490)
	)
	(segment
		(start 76.72 101.213223)
		(end 76.72 100.96)
		(width 0.125)
		(layer "F.Cu")
		(net 490)
	)
	(segment
		(start 75.425 102.508223)
		(end 76.72 101.213223)
		(width 0.125)
		(layer "F.Cu")
		(net 490)
	)
	(segment
		(start 75.35 104.967469)
		(end 75.425 104.892469)
		(width 0.125)
		(layer "F.Cu")
		(net 490)
	)
	(via
		(at 76.72 100.96)
		(size 0.45)
		(drill 0.1)
		(layers "F.Cu" "B.Cu")
		(net 490)
	)
	(via
		(at 86.466706 90.463294)
		(size 0.45)
		(drill 0.1)
		(layers "F.Cu" "B.Cu")
		(net 490)
	)
	(segment
		(start 87.09824 96.82)
		(end 86.555 96.82)
		(width 0.125)
		(layer "In5.Cu")
		(net 490)
	)
	(segment
		(start 85.955 99.12)
		(end 85.955 99.467512)
		(width 0.125)
		(layer "In5.Cu")
		(net 490)
	)
	(segment
		(start 77.047512 100.835)
		(end 76.922512 100.96)
		(width 0.125)
		(layer "In5.Cu")
		(net 490)
	)
	(segment
		(start 77.047512 100.835)
		(end 83.08619 100.835)
		(width 0.125)
		(layer "In5.Cu")
		(net 490)
	)
	(segment
		(start 85.89588 95.10412)
		(end 85.72088 95.10412)
		(width 0.125)
		(layer "In5.Cu")
		(net 490)
	)
	(segment
		(start 84.587512 100.835)
		(end 83.685 100.835)
		(width 0.125)
		(layer "In5.Cu")
		(net 490)
	)
	(segment
		(start 87.59824 98.52)
		(end 86.555 98.52)
		(width 0.125)
		(layer "In5.Cu")
		(net 490)
	)
	(segment
		(start 86.555 98.02)
		(end 87.59824 98.02)
		(width 0.125)
		(layer "In5.Cu")
		(net 490)
	)
	(segment
		(start 85.955 99.467512)
		(end 84.587512 100.835)
		(width 0.125)
		(layer "In5.Cu")
		(net 490)
	)
	(segment
		(start 86.835 92.217512)
		(end 85.955 93.097512)
		(width 0.125)
		(layer "In5.Cu")
		(net 490)
	)
	(segment
		(start 86.625806 90.463294)
		(end 86.835 90.672488)
		(width 0.125)
		(layer "In5.Cu")
		(net 490)
	)
	(segment
		(start 85.31176 95.51324)
		(end 85.31176 95.895)
		(width 0.125)
		(layer "In5.Cu")
		(net 490)
	)
	(segment
		(start 76.922512 100.96)
		(end 76.72 100.96)
		(width 0.125)
		(layer "In5.Cu")
		(net 490)
	)
	(segment
		(start 86.835 90.672488)
		(end 86.835 92.217512)
		(width 0.125)
		(layer "In5.Cu")
		(net 490)
	)
	(segment
		(start 85.72088 96.30412)
		(end 86.13 96.30412)
		(width 0.125)
		(layer "In5.Cu")
		(net 490)
	)
	(segment
		(start 83.560595 100.710595)
		(end 83.560595 100.710594)
		(width 0.125)
		(layer "In5.Cu")
		(net 490)
	)
	(segment
		(start 83.210595 100.710594)
		(end 83.210595 100.710595)
		(width 0.125)
		(layer "In5.Cu")
		(net 490)
	)
	(segment
		(start 86.466706 90.463294)
		(end 86.625806 90.463294)
		(width 0.125)
		(layer "In5.Cu")
		(net 490)
	)
	(segment
		(start 83.43619 100.586189)
		(end 83.335 100.586189)
		(width 0.125)
		(layer "In5.Cu")
		(net 490)
	)
	(segment
		(start 86.13 96.32)
		(end 87.09824 96.32)
		(width 0.125)
		(layer "In5.Cu")
		(net 490)
	)
	(segment
		(start 86.13 96.30412)
		(end 86.13 96.32)
		(width 0.125)
		(layer "In5.Cu")
		(net 490)
	)
	(segment
		(start 85.955 93.097512)
		(end 85.955 95.045)
		(width 0.125)
		(layer "In5.Cu")
		(net 490)
	)
	(arc
		(start 87.84824 98.27)
		(mid 87.775017 98.446777)
		(end 87.59824 98.52)
		(width 0.125)
		(layer "In5.Cu")
		(net 490)
	)
	(arc
		(start 87.59824 98.02)
		(mid 87.775017 98.093223)
		(end 87.84824 98.27)
		(width 0.125)
		(layer "In5.Cu")
		(net 490)
	)
	(arc
		(start 85.72088 95.10412)
		(mid 85.431588 95.223948)
		(end 85.31176 95.51324)
		(width 0.125)
		(layer "In5.Cu")
		(net 490)
	)
	(arc
		(start 83.685 100.835)
		(mid 83.597032 100.798563)
		(end 83.560595 100.710595)
		(width 0.125)
		(layer "In5.Cu")
		(net 490)
	)
	(arc
		(start 85.955 97.42)
		(mid 86.130736 97.844264)
		(end 86.555 98.02)
		(width 0.125)
		(layer "In5.Cu")
		(net 490)
	)
	(arc
		(start 86.555 96.82)
		(mid 86.130736 96.995736)
		(end 85.955 97.42)
		(width 0.125)
		(layer "In5.Cu")
		(net 490)
	)
	(arc
		(start 83.210595 100.710595)
		(mid 83.174158 100.798563)
		(end 83.08619 100.835)
		(width 0.125)
		(layer "In5.Cu")
		(net 490)
	)
	(arc
		(start 83.335 100.586189)
		(mid 83.247032 100.622626)
		(end 83.210595 100.710594)
		(width 0.125)
		(layer "In5.Cu")
		(net 490)
	)
	(arc
		(start 85.31176 95.895)
		(mid 85.431588 96.184292)
		(end 85.72088 96.30412)
		(width 0.125)
		(layer "In5.Cu")
		(net 490)
	)
	(arc
		(start 85.955 95.045)
		(mid 85.937684 95.086804)
		(end 85.89588 95.10412)
		(width 0.125)
		(layer "In5.Cu")
		(net 490)
	)
	(arc
		(start 83.560595 100.710594)
		(mid 83.524158 100.622626)
		(end 83.43619 100.586189)
		(width 0.125)
		(layer "In5.Cu")
		(net 490)
	)
	(arc
		(start 87.09824 96.32)
		(mid 87.275017 96.393223)
		(end 87.34824 96.57)
		(width 0.125)
		(layer "In5.Cu")
		(net 490)
	)
	(arc
		(start 86.555 98.52)
		(mid 86.130736 98.695736)
		(end 85.955 99.12)
		(width 0.125)
		(layer "In5.Cu")
		(net 490)
	)
	(arc
		(start 87.34824 96.57)
		(mid 87.275017 96.746777)
		(end 87.09824 96.82)
		(width 0.125)
		(layer "In5.Cu")
		(net 490)
	)
	(segment
		(start 89.6325 90.45)
		(end 89.5075 90.325)
		(width 0.125)
		(layer "B.Cu")
		(net 490)
	)
	(segment
		(start 87.811778 90.865)
		(end 87.098223 90.865)
		(width 0.125)
		(layer "B.Cu")
		(net 490)
	)
	(segment
		(start 88.351778 90.325)
		(end 87.811778 90.865)
		(width 0.125)
		(layer "B.Cu")
		(net 490)
	)
	(segment
		(start 89.5075 90.325)
		(end 88.351778 90.325)
		(width 0.125)
		(layer "B.Cu")
		(net 490)
	)
	(segment
		(start 86.696517 90.463294)
		(end 86.466706 90.463294)
		(width 0.125)
		(layer "B.Cu")
		(net 490)
	)
	(segment
		(start 87.098223 90.865)
		(end 86.696517 90.463294)
		(width 0.125)
		(layer "B.Cu")
		(net 490)
	)
	(segment
		(start 74.225 104.892469)
		(end 74.225 101.598223)
		(width 0.125)
		(layer "F.Cu")
		(net 491)
	)
	(segment
		(start 74.15 104.967469)
		(end 74.225 104.892469)
		(width 0.125)
		(layer "F.Cu")
		(net 491)
	)
	(segment
		(start 74.225 101.598223)
		(end 75.162412 100.660811)
		(width 0.125)
		(layer "F.Cu")
		(net 491)
	)
	(segment
		(start 75.162412 100.660811)
		(end 75.162412 100.362412)
		(width 0.125)
		(layer "F.Cu")
		(net 491)
	)
	(via
		(at 85.396706 89.243294)
		(size 0.45)
		(drill 0.1)
		(layers "F.Cu" "B.Cu")
		(net 491)
	)
	(via
		(at 75.162412 100.362412)
		(size 0.45)
		(drill 0.1)
		(layers "F.Cu" "B.Cu")
		(net 491)
	)
	(segment
		(start 75.777512 99.975)
		(end 81.167512 99.975)
		(width 0.125)
		(layer "In5.Cu")
		(net 491)
	)
	(segment
		(start 84.224173 90.524783)
		(end 83.972342 90.272952)
		(width 0.125)
		(layer "In5.Cu")
		(net 491)
	)
	(segment
		(start 85.555806 89.243294)
		(end 85.396706 89.243294)
		(width 0.125)
		(layer "In5.Cu")
		(net 491)
	)
	(segment
		(start 84.975 97.747512)
		(end 84.975 96.762488)
		(width 0.125)
		(layer "In5.Cu")
		(net 491)
	)
	(segment
		(start 81.167512 99.975)
		(end 81.733756 99.408756)
		(width 0.125)
		(layer "In5.Cu")
		(net 491)
	)
	(segment
		(start 84.975 96.762488)
		(end 84.025 95.812488)
		(width 0.125)
		(layer "In5.Cu")
		(net 491)
	)
	(segment
		(start 85.605 89.497512)
		(end 85.605 89.292488)
		(width 0.125)
		(layer "In5.Cu")
		(net 491)
	)
	(segment
		(start 84.556278 94.715)
		(end 84.731278 94.715)
		(width 0.125)
		(layer "In5.Cu")
		(net 491)
	)
	(segment
		(start 84.025 91.077512)
		(end 84.224172 90.878336)
		(width 0.125)
		(layer "In5.Cu")
		(net 491)
	)
	(segment
		(start 75.162412 100.362412)
		(end 75.3901 100.362412)
		(width 0.125)
		(layer "In5.Cu")
		(net 491)
	)
	(segment
		(start 82.013158 99.129357)
		(end 82.013158 99.129358)
		(width 0.125)
		(layer "In5.Cu")
		(net 491)
	)
	(segment
		(start 84.731278 92.796278)
		(end 84.556278 92.796278)
		(width 0.125)
		(layer "In5.Cu")
		(net 491)
	)
	(segment
		(start 83.097512 98.045)
		(end 84.677512 98.045)
		(width 0.125)
		(layer "In5.Cu")
		(net 491)
	)
	(segment
		(start 84.82087 89.424424)
		(end 85.072702 89.676256)
		(width 0.125)
		(layer "In5.Cu")
		(net 491)
	)
	(segment
		(start 84.55 93.196279)
		(end 84.731277 93.196279)
		(width 0.125)
		(layer "In5.Cu")
		(net 491)
	)
	(segment
		(start 84.025 95.812488)
		(end 84.025 95.246278)
		(width 0.125)
		(layer "In5.Cu")
		(net 491)
	)
	(segment
		(start 81.910535 99.129356)
		(end 81.910536 99.129357)
		(width 0.125)
		(layer "In5.Cu")
		(net 491)
	)
	(segment
		(start 84.912556 94.533722)
		(end 84.912556 94.496278)
		(width 0.125)
		(layer "In5.Cu")
		(net 491)
	)
	(segment
		(start 85.426256 89.676256)
		(end 85.605 89.497512)
		(width 0.125)
		(layer "In5.Cu")
		(net 491)
	)
	(segment
		(start 84.912556 93.015)
		(end 84.912556 92.977556)
		(width 0.125)
		(layer "In5.Cu")
		(net 491)
	)
	(segment
		(start 84.731277 93.196279)
		(end 84.731278 93.196278)
		(width 0.125)
		(layer "In5.Cu")
		(net 491)
	)
	(segment
		(start 81.910534 99.129356)
		(end 81.910535 99.129356)
		(width 0.125)
		(layer "In5.Cu")
		(net 491)
	)
	(segment
		(start 84.731278 94.315)
		(end 84.55 94.315)
		(width 0.125)
		(layer "In5.Cu")
		(net 491)
	)
	(segment
		(start 75.3901 100.362412)
		(end 75.777512 99.975)
		(width 0.125)
		(layer "In5.Cu")
		(net 491)
	)
	(segment
		(start 85.605 89.292488)
		(end 85.555806 89.243294)
		(width 0.125)
		(layer "In5.Cu")
		(net 491)
	)
	(segment
		(start 81.733757 99.20351)
		(end 81.807911 99.129357)
		(width 0.125)
		(layer "In5.Cu")
		(net 491)
	)
	(segment
		(start 84.025 92.265)
		(end 84.025 91.077512)
		(width 0.125)
		(layer "In5.Cu")
		(net 491)
	)
	(segment
		(start 84.677512 98.045)
		(end 84.975 97.747512)
		(width 0.125)
		(layer "In5.Cu")
		(net 491)
	)
	(segment
		(start 84.018722 93.783722)
		(end 84.018722 93.727556)
		(width 0.125)
		(layer "In5.Cu")
		(net 491)
	)
	(segment
		(start 82.013158 99.129358)
		(end 83.097512 98.045)
		(width 0.125)
		(layer "In5.Cu")
		(net 491)
	)
	(segment
		(start 81.733756 99.203512)
		(end 81.733757 99.20351)
		(width 0.125)
		(layer "In5.Cu")
		(net 491)
	)
	(arc
		(start 81.733756 99.306134)
		(mid 81.712503 99.254822)
		(end 81.733756 99.203512)
		(width 0.125)
		(layer "In5.Cu")
		(net 491)
	)
	(arc
		(start 84.025 95.246278)
		(mid 84.180608 94.870608)
		(end 84.556278 94.715)
		(width 0.125)
		(layer "In5.Cu")
		(net 491)
	)
	(arc
		(start 84.912556 92.977556)
		(mid 84.859461 92.849373)
		(end 84.731278 92.796278)
		(width 0.125)
		(layer "In5.Cu")
		(net 491)
	)
	(arc
		(start 81.733756 99.408756)
		(mid 81.755011 99.357444)
		(end 81.733756 99.306134)
		(width 0.125)
		(layer "In5.Cu")
		(net 491)
	)
	(arc
		(start 84.018722 93.727556)
		(mid 84.17433 93.351886)
		(end 84.55 93.196279)
		(width 0.125)
		(layer "In5.Cu")
		(net 491)
	)
	(arc
		(start 84.556278 92.796278)
		(mid 84.180608 92.64067)
		(end 84.025 92.265)
		(width 0.125)
		(layer "In5.Cu")
		(net 491)
	)
	(arc
		(start 84.55 94.315)
		(mid 84.17433 94.159392)
		(end 84.018722 93.783722)
		(width 0.125)
		(layer "In5.Cu")
		(net 491)
	)
	(arc
		(start 83.972342 89.424424)
		(mid 84.396606 89.248688)
		(end 84.82087 89.424424)
		(width 0.125)
		(layer "In5.Cu")
		(net 491)
	)
	(arc
		(start 81.807911 99.129357)
		(mid 81.859223 99.108102)
		(end 81.910534 99.129356)
		(width 0.125)
		(layer "In5.Cu")
		(net 491)
	)
	(arc
		(start 84.224172 90.878336)
		(mid 84.297396 90.70156)
		(end 84.224173 90.524783)
		(width 0.125)
		(layer "In5.Cu")
		(net 491)
	)
	(arc
		(start 81.910536 99.129357)
		(mid 81.961846 99.150612)
		(end 82.013158 99.129357)
		(width 0.125)
		(layer "In5.Cu")
		(net 491)
	)
	(arc
		(start 84.912556 94.496278)
		(mid 84.859461 94.368095)
		(end 84.731278 94.315)
		(width 0.125)
		(layer "In5.Cu")
		(net 491)
	)
	(arc
		(start 84.731278 94.715)
		(mid 84.859461 94.661905)
		(end 84.912556 94.533722)
		(width 0.125)
		(layer "In5.Cu")
		(net 491)
	)
	(arc
		(start 83.972342 90.272952)
		(mid 83.796606 89.848688)
		(end 83.972342 89.424424)
		(width 0.125)
		(layer "In5.Cu")
		(net 491)
	)
	(arc
		(start 85.072702 89.676256)
		(mid 85.249479 89.749479)
		(end 85.426256 89.676256)
		(width 0.125)
		(layer "In5.Cu")
		(net 491)
	)
	(arc
		(start 84.731278 93.196278)
		(mid 84.859461 93.143183)
		(end 84.912556 93.015)
		(width 0.125)
		(layer "In5.Cu")
		(net 491)
	)
	(segment
		(start 89.5075 89.325)
		(end 85.708223 89.325)
		(width 0.125)
		(layer "B.Cu")
		(net 491)
	)
	(segment
		(start 89.6325 89.45)
		(end 89.5075 89.325)
		(width 0.125)
		(layer "B.Cu")
		(net 491)
	)
	(segment
		(start 85.708223 89.325)
		(end 85.626517 89.243294)
		(width 0.125)
		(layer "B.Cu")
		(net 491)
	)
	(segment
		(start 85.626517 89.243294)
		(end 85.396706 89.243294)
		(width 0.125)
		(layer "B.Cu")
		(net 491)
	)
	(segment
		(start 88.878222 95.205)
		(end 90.601778 95.205)
		(width 0.125)
		(layer "F.Cu")
		(net 492)
	)
	(segment
		(start 91.295 100.938222)
		(end 92.725 102.368222)
		(width 0.125)
		(layer "F.Cu")
		(net 492)
	)
	(segment
		(start 91.295 95.898222)
		(end 91.295 96.695)
		(width 0.125)
		(layer "F.Cu")
		(net 492)
	)
	(segment
		(start 96.561778 115.755)
		(end 97.2 116.393222)
		(width 0.125)
		(layer "F.Cu")
		(net 492)
	)
	(segment
		(start 90.753774 97.945)
		(end 91.852451 97.945)
		(width 0.125)
		(layer "F.Cu")
		(net 492)
	)
	(segment
		(start 97.2 117.925)
		(end 97.275 118)
		(width 0.125)
		(layer "F.Cu")
		(net 492)
	)
	(segment
		(start 91.545 96.945)
		(end 91.852451 96.945)
		(width 0.125)
		(layer "F.Cu")
		(net 492)
	)
	(segment
		(start 95.251778 115.755)
		(end 96.561778 115.755)
		(width 0.125)
		(layer "F.Cu")
		(net 492)
	)
	(segment
		(start 88.325 96.1975)
		(end 88.325 95.758222)
		(width 0.125)
		(layer "F.Cu")
		(net 492)
	)
	(segment
		(start 90.753774 98.445)
		(end 90.878775 98.445)
		(width 0.125)
		(layer "F.Cu")
		(net 492)
	)
	(segment
		(start 91.295 98.861225)
		(end 91.295 100.938222)
		(width 0.125)
		(layer "F.Cu")
		(net 492)
	)
	(segment
		(start 94.105 114.608222)
		(end 95.251778 115.755)
		(width 0.125)
		(layer "F.Cu")
		(net 492)
	)
	(segment
		(start 97.2 116.393222)
		(end 97.2 117.925)
		(width 0.125)
		(layer "F.Cu")
		(net 492)
	)
	(segment
		(start 88.1625 96.36)
		(end 88.325 96.1975)
		(width 0.125)
		(layer "F.Cu")
		(net 492)
	)
	(segment
		(start 90.601778 95.205)
		(end 91.295 95.898222)
		(width 0.125)
		(layer "F.Cu")
		(net 492)
	)
	(segment
		(start 92.725 104.048223)
		(end 94.105 105.428223)
		(width 0.125)
		(layer "F.Cu")
		(net 492)
	)
	(segment
		(start 94.105 105.428223)
		(end 94.105 114.608222)
		(width 0.125)
		(layer "F.Cu")
		(net 492)
	)
	(segment
		(start 90.587549 98.111225)
		(end 90.587549 98.278775)
		(width 0.125)
		(layer "F.Cu")
		(net 492)
	)
	(segment
		(start 92.725 102.368222)
		(end 92.725 104.048223)
		(width 0.125)
		(layer "F.Cu")
		(net 492)
	)
	(segment
		(start 88.325 95.758222)
		(end 88.878222 95.205)
		(width 0.125)
		(layer "F.Cu")
		(net 492)
	)
	(via
		(at 88.1625 96.36)
		(size 0.45)
		(drill 0.1)
		(layers "F.Cu" "B.Cu")
		(net 492)
	)
	(arc
		(start 92.352451 97.445)
		(mid 92.206004 97.798553)
		(end 91.852451 97.945)
		(width 0.125)
		(layer "F.Cu")
		(net 492)
	)
	(arc
		(start 90.753774 97.945)
		(mid 90.636235 97.993686)
		(end 90.587549 98.111225)
		(width 0.125)
		(layer "F.Cu")
		(net 492)
	)
	(arc
		(start 91.295 96.695)
		(mid 91.368223 96.871777)
		(end 91.545 96.945)
		(width 0.125)
		(layer "F.Cu")
		(net 492)
	)
	(arc
		(start 90.878775 98.445)
		(mid 91.173091 98.566909)
		(end 91.295 98.861225)
		(width 0.125)
		(layer "F.Cu")
		(net 492)
	)
	(arc
		(start 91.852451 96.945)
		(mid 92.206004 97.091447)
		(end 92.352451 97.445)
		(width 0.125)
		(layer "F.Cu")
		(net 492)
	)
	(arc
		(start 90.587549 98.278775)
		(mid 90.636235 98.396314)
		(end 90.753774 98.445)
		(width 0.125)
		(layer "F.Cu")
		(net 492)
	)
	(segment
		(start 88.325 96.1975)
		(end 88.1625 96.36)
		(width 0.125)
		(layer "B.Cu")
		(net 492)
	)
	(segment
		(start 89.5075 95.575)
		(end 88.768222 95.575)
		(width 0.125)
		(layer "B.Cu")
		(net 492)
	)
	(segment
		(start 88.325 96.018222)
		(end 88.325 96.1975)
		(width 0.125)
		(layer "B.Cu")
		(net 492)
	)
	(segment
		(start 88.768222 95.575)
		(end 88.325 96.018222)
		(width 0.125)
		(layer "B.Cu")
		(net 492)
	)
	(segment
		(start 89.6325 95.45)
		(end 89.5075 95.575)
		(width 0.125)
		(layer "B.Cu")
		(net 492)
	)
	(segment
		(start 95.588223 116.905)
		(end 95.356517 117.136706)
		(width 0.125)
		(layer "F.Cu")
		(net 493)
	)
	(segment
		(start 96.475 118)
		(end 96.4 117.925)
		(width 0.125)
		(layer "F.Cu")
		(net 493)
	)
	(segment
		(start 95.356517 117.136706)
		(end 95.126706 117.136706)
		(width 0.125)
		(layer "F.Cu")
		(net 493)
	)
	(segment
		(start 96.101778 116.905)
		(end 95.588223 116.905)
		(width 0.125)
		(layer "F.Cu")
		(net 493)
	)
	(segment
		(start 96.4 117.925)
		(end 96.4 117.203222)
		(width 0.125)
		(layer "F.Cu")
		(net 493)
	)
	(segment
		(start 96.4 117.203222)
		(end 96.101778 116.905)
		(width 0.125)
		(layer "F.Cu")
		(net 493)
	)
	(via
		(at 95.126706 117.136706)
		(size 0.45)
		(drill 0.1)
		(layers "F.Cu" "B.Cu")
		(net 493)
	)
	(segment
		(start 89.5075 94.575)
		(end 88.118222 94.575)
		(width 0.125)
		(layer "B.Cu")
		(net 493)
	)
	(segment
		(start 88.927232 99.899416)
		(end 88.927232 99.899417)
		(width 0.125)
		(layer "B.Cu")
		(net 493)
	)
	(segment
		(start 94.595 113.896778)
		(end 94.595 115.301778)
		(width 0.125)
		(layer "B.Cu")
		(net 493)
	)
	(segment
		(start 87.175 97.451778)
		(end 87.94911 98.225887)
		(width 0.125)
		(layer "B.Cu")
		(net 493)
	)
	(segment
		(start 89.127665 98.355481)
		(end 89.127666 98.35548)
		(width 0.125)
		(layer "B.Cu")
		(net 493)
	)
	(segment
		(start 94.595 115.301778)
		(end 95.515 116.221778)
		(width 0.125)
		(layer "B.Cu")
		(net 493)
	)
	(segment
		(start 93.025 102.401778)
		(end 93.025 103.701778)
		(width 0.125)
		(layer "B.Cu")
		(net 493)
	)
	(segment
		(start 88.620864 98.225889)
		(end 88.809468 98.037282)
		(width 0.125)
		(layer "B.Cu")
		(net 493)
	)
	(segment
		(start 94.2 113.501778)
		(end 94.595 113.896778)
		(width 0.125)
		(layer "B.Cu")
		(net 493)
	)
	(segment
		(start 89.6325 94.45)
		(end 89.5075 94.575)
		(width 0.125)
		(layer "B.Cu")
		(net 493)
	)
	(segment
		(start 94.2 104.876778)
		(end 94.2 113.501778)
		(width 0.125)
		(layer "B.Cu")
		(net 493)
	)
	(segment
		(start 89.127666 98.35548)
		(end 88.255481 99.227666)
		(width 0.125)
		(layer "B.Cu")
		(net 493)
	)
	(segment
		(start 88.255481 99.899416)
		(end 88.255481 99.899417)
		(width 0.125)
		(layer "B.Cu")
		(net 493)
	)
	(segment
		(start 93.025 103.701778)
		(end 94.2 104.876778)
		(width 0.125)
		(layer "B.Cu")
		(net 493)
	)
	(segment
		(start 91.748223 102.025)
		(end 92.648222 102.025)
		(width 0.125)
		(layer "B.Cu")
		(net 493)
	)
	(segment
		(start 88.118222 94.575)
		(end 87.175 95.518222)
		(width 0.125)
		(layer "B.Cu")
		(net 493)
	)
	(segment
		(start 89.434035 99.710811)
		(end 91.748223 102.025)
		(width 0.125)
		(layer "B.Cu")
		(net 493)
	)
	(segment
		(start 88.927232 99.899417)
		(end 89.115837 99.710811)
		(width 0.125)
		(layer "B.Cu")
		(net 493)
	)
	(segment
		(start 95.515 116.221778)
		(end 95.515 116.978223)
		(width 0.125)
		(layer "B.Cu")
		(net 493)
	)
	(segment
		(start 95.515 116.978223)
		(end 95.356517 117.136706)
		(width 0.125)
		(layer "B.Cu")
		(net 493)
	)
	(segment
		(start 87.175 95.518222)
		(end 87.175 97.451778)
		(width 0.125)
		(layer "B.Cu")
		(net 493)
	)
	(segment
		(start 92.648222 102.025)
		(end 93.025 102.401778)
		(width 0.125)
		(layer "B.Cu")
		(net 493)
	)
	(segment
		(start 95.356517 117.136706)
		(end 95.126706 117.136706)
		(width 0.125)
		(layer "B.Cu")
		(net 493)
	)
	(arc
		(start 88.255481 99.899417)
		(mid 88.591357 100.038541)
		(end 88.927232 99.899416)
		(width 0.125)
		(layer "B.Cu")
		(net 493)
	)
	(arc
		(start 88.809468 98.037282)
		(mid 88.968567 97.971381)
		(end 89.127666 98.037282)
		(width 0.125)
		(layer "B.Cu")
		(net 493)
	)
	(arc
		(start 87.94911 98.225887)
		(mid 88.284988 98.365013)
		(end 88.620864 98.225889)
		(width 0.125)
		(layer "B.Cu")
		(net 493)
	)
	(arc
		(start 89.127666 98.037282)
		(mid 89.193568 98.196383)
		(end 89.127665 98.355481)
		(width 0.125)
		(layer "B.Cu")
		(net 493)
	)
	(arc
		(start 88.255481 99.227666)
		(mid 88.116357 99.563541)
		(end 88.255481 99.899416)
		(width 0.125)
		(layer "B.Cu")
		(net 493)
	)
	(arc
		(start 89.115837 99.710811)
		(mid 89.274936 99.64491)
		(end 89.434035 99.710811)
		(width 0.125)
		(layer "B.Cu")
		(net 493)
	)
	(segment
		(start 94.15 116.473222)
		(end 92.935 115.258222)
		(width 0.125)
		(layer "F.Cu")
		(net 494)
	)
	(segment
		(start 94.225 118)
		(end 94.15 117.925)
		(width 0.125)
		(layer "F.Cu")
		(net 494)
	)
	(segment
		(start 90.925 104.348223)
		(end 89.925 103.348223)
		(width 0.125)
		(layer "F.Cu")
		(net 494)
	)
	(segment
		(start 92.935 110.958222)
		(end 90.925 108.948222)
		(width 0.125)
		(layer "F.Cu")
		(net 494)
	)
	(segment
		(start 87.577489 97.854406)
		(end 87.67346 97.758432)
		(width 0.125)
		(layer "F.Cu")
		(net 494)
	)
	(segment
		(start 88.001778 93.575)
		(end 87.4925 93.575)
		(width 0.125)
		(layer "F.Cu")
		(net 494)
	)
	(segment
		(start 87.4925 93.575)
		(end 87.33 93.4125)
		(width 0.125)
		(layer "F.Cu")
		(net 494)
	)
	(segment
		(start 90.925 108.948222)
		(end 90.925 104.348223)
		(width 0.125)
		(layer "F.Cu")
		(net 494)
	)
	(segment
		(start 89.925 99.338223)
		(end 89.158387 98.571609)
		(width 0.125)
		(layer "F.Cu")
		(net 494)
	)
	(segment
		(start 87.673459 97.086681)
		(end 87.673461 97.086682)
		(width 0.125)
		(layer "F.Cu")
		(net 494)
	)
	(segment
		(start 89.158387 98.253411)
		(end 89.39578 98.016017)
		(width 0.125)
		(layer "F.Cu")
		(net 494)
	)
	(segment
		(start 94.15 117.925)
		(end 94.15 116.473222)
		(width 0.125)
		(layer "F.Cu")
		(net 494)
	)
	(segment
		(start 87.673461 97.086682)
		(end 87.075 96.488222)
		(width 0.125)
		(layer "F.Cu")
		(net 494)
	)
	(segment
		(start 88.375 93.948222)
		(end 88.001778 93.575)
		(width 0.125)
		(layer "F.Cu")
		(net 494)
	)
	(segment
		(start 92.935 115.258222)
		(end 92.935 110.958222)
		(width 0.125)
		(layer "F.Cu")
		(net 494)
	)
	(segment
		(start 88.724029 97.344265)
		(end 88.724028 97.344266)
		(width 0.125)
		(layer "F.Cu")
		(net 494)
	)
	(segment
		(start 88.724028 97.344266)
		(end 87.895686 98.172604)
		(width 0.125)
		(layer "F.Cu")
		(net 494)
	)
	(segment
		(start 89.39578 97.344265)
		(end 89.39578 97.344266)
		(width 0.125)
		(layer "F.Cu")
		(net 494)
	)
	(segment
		(start 87.577487 97.854405)
		(end 87.577489 97.854406)
		(width 0.125)
		(layer "F.Cu")
		(net 494)
	)
	(segment
		(start 87.075 96.488222)
		(end 87.075 95.901778)
		(width 0.125)
		(layer "F.Cu")
		(net 494)
	)
	(segment
		(start 87.075 95.901778)
		(end 88.375 94.601778)
		(width 0.125)
		(layer "F.Cu")
		(net 494)
	)
	(segment
		(start 89.925 103.348223)
		(end 89.925 99.338223)
		(width 0.125)
		(layer "F.Cu")
		(net 494)
	)
	(segment
		(start 88.375 94.601778)
		(end 88.375 93.948222)
		(width 0.125)
		(layer "F.Cu")
		(net 494)
	)
	(via
		(at 87.33 93.4125)
		(size 0.45)
		(drill 0.1)
		(layers "F.Cu" "B.Cu")
		(net 494)
	)
	(arc
		(start 87.577488 98.172604)
		(mid 87.511587 98.013506)
		(end 87.577487 97.854405)
		(width 0.125)
		(layer "F.Cu")
		(net 494)
	)
	(arc
		(start 87.67346 97.758432)
		(mid 87.812584 97.422556)
		(end 87.673459 97.086681)
		(width 0.125)
		(layer "F.Cu")
		(net 494)
	)
	(arc
		(start 89.158387 98.571609)
		(mid 89.092486 98.41251)
		(end 89.158387 98.253411)
		(width 0.125)
		(layer "F.Cu")
		(net 494)
	)
	(arc
		(start 89.39578 97.344266)
		(mid 89.059905 97.205141)
		(end 88.724029 97.344265)
		(width 0.125)
		(layer "F.Cu")
		(net 494)
	)
	(arc
		(start 89.39578 98.016017)
		(mid 89.534904 97.680141)
		(end 89.39578 97.344265)
		(width 0.125)
		(layer "F.Cu")
		(net 494)
	)
	(arc
		(start 87.895686 98.172604)
		(mid 87.736587 98.238505)
		(end 87.577488 98.172604)
		(width 0.125)
		(layer "F.Cu")
		(net 494)
	)
	(segment
		(start 89.5075 93.575)
		(end 87.4925 93.575)
		(width 0.125)
		(layer "B.Cu")
		(net 494)
	)
	(segment
		(start 89.6325 93.45)
		(end 89.5075 93.575)
		(width 0.125)
		(layer "B.Cu")
		(net 494)
	)
	(segment
		(start 87.4925 93.575)
		(end 87.33 93.4125)
		(width 0.125)
		(layer "B.Cu")
		(net 494)
	)
	(segment
		(start 92.136706 117.256706)
		(end 92.366517 117.256706)
		(width 0.125)
		(layer "F.Cu")
		(net 495)
	)
	(segment
		(start 92.558223 117.065)
		(end 93.021778 117.065)
		(width 0.125)
		(layer "F.Cu")
		(net 495)
	)
	(segment
		(start 93.021778 117.065)
		(end 93.35 117.393222)
		(width 0.125)
		(layer "F.Cu")
		(net 495)
	)
	(segment
		(start 92.366517 117.256706)
		(end 92.558223 117.065)
		(width 0.125)
		(layer "F.Cu")
		(net 495)
	)
	(segment
		(start 93.35 117.925)
		(end 93.425 118)
		(width 0.125)
		(layer "F.Cu")
		(net 495)
	)
	(segment
		(start 93.35 117.393222)
		(end 93.35 117.925)
		(width 0.125)
		(layer "F.Cu")
		(net 495)
	)
	(via
		(at 92.136706 117.256706)
		(size 0.45)
		(drill 0.1)
		(layers "F.Cu" "B.Cu")
		(net 495)
	)
	(segment
		(start 90.648223 103.425)
		(end 89.948222 103.425)
		(width 0.125)
		(layer "B.Cu")
		(net 495)
	)
	(segment
		(start 92.136706 117.256706)
		(end 92.366517 117.256706)
		(width 0.125)
		(layer "B.Cu")
		(net 495)
	)
	(segment
		(start 93.225 106.001777)
		(end 90.648223 103.425)
		(width 0.125)
		(layer "B.Cu")
		(net 495)
	)
	(segment
		(start 89.5075 92.575)
		(end 89.6325 92.45)
		(width 0.125)
		(layer "B.Cu")
		(net 495)
	)
	(segment
		(start 89.948222 103.425)
		(end 85.955 99.431778)
		(width 0.125)
		(layer "B.Cu")
		(net 495)
	)
	(segment
		(start 86.638222 92.575)
		(end 89.5075 92.575)
		(width 0.125)
		(layer "B.Cu")
		(net 495)
	)
	(segment
		(start 92.366517 117.256706)
		(end 93.225 116.398223)
		(width 0.125)
		(layer "B.Cu")
		(net 495)
	)
	(segment
		(start 85.955 99.431778)
		(end 85.955 93.258222)
		(width 0.125)
		(layer "B.Cu")
		(net 495)
	)
	(segment
		(start 93.225 116.398223)
		(end 93.225 106.001777)
		(width 0.125)
		(layer "B.Cu")
		(net 495)
	)
	(segment
		(start 85.955 93.258222)
		(end 86.638222 92.575)
		(width 0.125)
		(layer "B.Cu")
		(net 495)
	)
	(segment
		(start 76.875 103.801777)
		(end 77.846777 102.83)
		(width 0.125)
		(layer "F.Cu")
		(net 496)
	)
	(segment
		(start 76.875 104.892469)
		(end 76.875 103.801777)
		(width 0.125)
		(layer "F.Cu")
		(net 496)
	)
	(segment
		(start 77.846777 102.83)
		(end 78.08 102.83)
		(width 0.125)
		(layer "F.Cu")
		(net 496)
	)
	(segment
		(start 76.95 104.967469)
		(end 76.875 104.892469)
		(width 0.125)
		(layer "F.Cu")
		(net 496)
	)
	(via
		(at 88.236706 91.296706)
		(size 0.45)
		(drill 0.1)
		(layers "F.Cu" "B.Cu")
		(net 496)
	)
	(via
		(at 78.08 102.83)
		(size 0.45)
		(drill 0.1)
		(layers "F.Cu" "B.Cu")
		(net 496)
	)
	(segment
		(start 89.975 96.542488)
		(end 89.185 97.332488)
		(width 0.125)
		(layer "In5.Cu")
		(net 496)
	)
	(segment
		(start 88.709542 95.295)
		(end 89.425 95.295)
		(width 0.125)
		(layer "In5.Cu")
		(net 496)
	)
	(segment
		(start 78.412488 102.325)
		(end 78.08 102.657488)
		(width 0.125)
		(layer "In5.Cu")
		(net 496)
	)
	(segment
		(start 85.382488 102.325)
		(end 78.412488 102.325)
		(width 0.125)
		(layer "In5.Cu")
		(net 496)
	)
	(segment
		(start 89.442488 91.055)
		(end 89.975 91.587512)
		(width 0.125)
		(layer "In5.Cu")
		(net 496)
	)
	(segment
		(start 89.8 93.395)
		(end 88.709542 93.395)
		(width 0.125)
		(layer "In5.Cu")
		(net 496)
	)
	(segment
		(start 90.170229 92.290229)
		(end 90.345229 92.290229)
		(width 0.125)
		(layer "In5.Cu")
		(net 496)
	)
	(segment
		(start 90.590458 94.190229)
		(end 90.590458 94.499771)
		(width 0.125)
		(layer "In5.Cu")
		(net 496)
	)
	(segment
		(start 89.8 93.390229)
		(end 89.8 93.395)
		(width 0.125)
		(layer "In5.Cu")
		(net 496)
	)
	(segment
		(start 88.236706 91.296706)
		(end 88.395806 91.296706)
		(width 0.125)
		(layer "In5.Cu")
		(net 496)
	)
	(segment
		(start 88.395806 91.296706)
		(end 88.637512 91.055)
		(width 0.125)
		(layer "In5.Cu")
		(net 496)
	)
	(segment
		(start 78.08 102.657488)
		(end 78.08 102.83)
		(width 0.125)
		(layer "In5.Cu")
		(net 496)
	)
	(segment
		(start 89.185 97.332488)
		(end 89.185 98.522488)
		(width 0.125)
		(layer "In5.Cu")
		(net 496)
	)
	(segment
		(start 88.709542 93.795)
		(end 90.195229 93.795)
		(width 0.125)
		(layer "In5.Cu")
		(net 496)
	)
	(segment
		(start 90.890458 92.835458)
		(end 90.890458 92.845)
		(width 0.125)
		(layer "In5.Cu")
		(net 496)
	)
	(segment
		(start 88.637512 91.055)
		(end 89.442488 91.055)
		(width 0.125)
		(layer "In5.Cu")
		(net 496)
	)
	(segment
		(start 89.185 98.522488)
		(end 85.382488 102.325)
		(width 0.125)
		(layer "In5.Cu")
		(net 496)
	)
	(segment
		(start 89.975 91.587512)
		(end 89.975 92.095)
		(width 0.125)
		(layer "In5.Cu")
		(net 496)
	)
	(segment
		(start 89.975 95.845)
		(end 89.975 96.542488)
		(width 0.125)
		(layer "In5.Cu")
		(net 496)
	)
	(segment
		(start 88.709542 94.895)
		(end 90.195229 94.895)
		(width 0.125)
		(layer "In5.Cu")
		(net 496)
	)
	(segment
		(start 89.8 93.390229)
		(end 90.345229 93.390229)
		(width 0.125)
		(layer "In5.Cu")
		(net 496)
	)
	(arc
		(start 90.195229 93.795)
		(mid 90.474698 93.91076)
		(end 90.590458 94.190229)
		(width 0.125)
		(layer "In5.Cu")
		(net 496)
	)
	(arc
		(start 90.345229 92.290229)
		(mid 90.730764 92.449923)
		(end 90.890458 92.835458)
		(width 0.125)
		(layer "In5.Cu")
		(net 496)
	)
	(arc
		(start 88.509542 93.595)
		(mid 88.568121 93.736421)
		(end 88.709542 93.795)
		(width 0.125)
		(layer "In5.Cu")
		(net 496)
	)
	(arc
		(start 89.425 95.295)
		(mid 89.813909 95.456091)
		(end 89.975 95.845)
		(width 0.125)
		(layer "In5.Cu")
		(net 496)
	)
	(arc
		(start 90.590458 94.499771)
		(mid 90.474698 94.77924)
		(end 90.195229 94.895)
		(width 0.125)
		(layer "In5.Cu")
		(net 496)
	)
	(arc
		(start 89.975 92.095)
		(mid 90.032181 92.233048)
		(end 90.170229 92.290229)
		(width 0.125)
		(layer "In5.Cu")
		(net 496)
	)
	(arc
		(start 90.890458 92.845)
		(mid 90.730764 93.230535)
		(end 90.345229 93.390229)
		(width 0.125)
		(layer "In5.Cu")
		(net 496)
	)
	(arc
		(start 88.509542 95.095)
		(mid 88.568121 95.236421)
		(end 88.709542 95.295)
		(width 0.125)
		(layer "In5.Cu")
		(net 496)
	)
	(arc
		(start 88.709542 93.395)
		(mid 88.568121 93.453579)
		(end 88.509542 93.595)
		(width 0.125)
		(layer "In5.Cu")
		(net 496)
	)
	(arc
		(start 88.709542 94.895)
		(mid 88.568121 94.953579)
		(end 88.509542 95.095)
		(width 0.125)
		(layer "In5.Cu")
		(net 496)
	)
	(segment
		(start 88.688223 91.075)
		(end 88.466517 91.296706)
		(width 0.125)
		(layer "B.Cu")
		(net 496)
	)
	(segment
		(start 89.6325 90.95)
		(end 89.5075 91.075)
		(width 0.125)
		(layer "B.Cu")
		(net 496)
	)
	(segment
		(start 89.5075 91.075)
		(end 88.688223 91.075)
		(width 0.125)
		(layer "B.Cu")
		(net 496)
	)
	(segment
		(start 88.466517 91.296706)
		(end 88.236706 91.296706)
		(width 0.125)
		(layer "B.Cu")
		(net 496)
	)
	(segment
		(start 74.55 104.967469)
		(end 74.475 104.892469)
		(width 0.125)
		(layer "F.Cu")
		(net 497)
	)
	(segment
		(start 75.339189 100.837588)
		(end 75.637588 100.837588)
		(width 0.125)
		(layer "F.Cu")
		(net 497)
	)
	(segment
		(start 74.475 101.701777)
		(end 75.339189 100.837588)
		(width 0.125)
		(layer "F.Cu")
		(net 497)
	)
	(segment
		(start 74.475 104.892469)
		(end 74.475 101.701777)
		(width 0.125)
		(layer "F.Cu")
		(net 497)
	)
	(via
		(at 75.637588 100.837588)
		(size 0.45)
		(drill 0.1)
		(layers "F.Cu" "B.Cu")
		(net 497)
	)
	(via
		(at 85.803294 88.836706)
		(size 0.45)
		(drill 0.1)
		(layers "F.Cu" "B.Cu")
		(net 497)
	)
	(segment
		(start 84.731277 93.965001)
		(end 84.731278 93.965)
		(width 0.125)
		(layer "In5.Cu")
		(net 497)
	)
	(segment
		(start 85.803294 88.836706)
		(end 85.803294 88.995806)
		(width 0.125)
		(layer "In5.Cu")
		(net 497)
	)
	(segment
		(start 85.803294 88.995806)
		(end 85.955 89.147512)
		(width 0.125)
		(layer "In5.Cu")
		(net 497)
	)
	(segment
		(start 84.471661 91.125823)
		(end 84.471662 91.125825)
		(width 0.125)
		(layer "In5.Cu")
		(net 497)
	)
	(segment
		(start 84.21983 90.025463)
		(end 84.21983 90.025464)
		(width 0.125)
		(layer "In5.Cu")
		(net 497)
	)
	(segment
		(start 85.955 89.147512)
		(end 85.955 89.642488)
		(width 0.125)
		(layer "In5.Cu")
		(net 497)
	)
	(segment
		(start 84.375 95.246278)
		(end 84.375 95.667512)
		(width 0.125)
		(layer "In5.Cu")
		(net 497)
	)
	(segment
		(start 75.637588 100.6099)
		(end 75.637588 100.837588)
		(width 0.125)
		(layer "In5.Cu")
		(net 497)
	)
	(segment
		(start 85.325 97.892488)
		(end 84.822488 98.395)
		(width 0.125)
		(layer "In5.Cu")
		(net 497)
	)
	(segment
		(start 75.922488 100.325)
		(end 75.637588 100.6099)
		(width 0.125)
		(layer "In5.Cu")
		(net 497)
	)
	(segment
		(start 84.731278 93.546278)
		(end 84.55 93.546278)
		(width 0.125)
		(layer "In5.Cu")
		(net 497)
	)
	(segment
		(start 85.955 89.642488)
		(end 85.673743 89.923743)
		(width 0.125)
		(layer "In5.Cu")
		(net 497)
	)
	(segment
		(start 85.262556 94.496278)
		(end 85.262556 94.533722)
		(width 0.125)
		(layer "In5.Cu")
		(net 497)
	)
	(segment
		(start 84.368722 93.727556)
		(end 84.368722 93.783722)
		(width 0.125)
		(layer "In5.Cu")
		(net 497)
	)
	(segment
		(start 84.822488 98.395)
		(end 83.242488 98.395)
		(width 0.125)
		(layer "In5.Cu")
		(net 497)
	)
	(segment
		(start 84.375 95.667512)
		(end 85.325 96.617512)
		(width 0.125)
		(layer "In5.Cu")
		(net 497)
	)
	(segment
		(start 85.262556 92.977556)
		(end 85.262556 93.015)
		(width 0.125)
		(layer "In5.Cu")
		(net 497)
	)
	(segment
		(start 84.471662 91.125825)
		(end 84.375 91.222488)
		(width 0.125)
		(layer "In5.Cu")
		(net 497)
	)
	(segment
		(start 84.21983 90.025464)
		(end 84.471661 90.277295)
		(width 0.125)
		(layer "In5.Cu")
		(net 497)
	)
	(segment
		(start 84.556278 92.446278)
		(end 84.731278 92.446278)
		(width 0.125)
		(layer "In5.Cu")
		(net 497)
	)
	(segment
		(start 84.825215 89.923743)
		(end 84.573383 89.671911)
		(width 0.125)
		(layer "In5.Cu")
		(net 497)
	)
	(segment
		(start 84.731278 95.065)
		(end 84.556278 95.065)
		(width 0.125)
		(layer "In5.Cu")
		(net 497)
	)
	(segment
		(start 85.325 96.617512)
		(end 85.325 97.892488)
		(width 0.125)
		(layer "In5.Cu")
		(net 497)
	)
	(segment
		(start 84.55 93.965001)
		(end 84.731277 93.965001)
		(width 0.125)
		(layer "In5.Cu")
		(net 497)
	)
	(segment
		(start 81.312488 100.325)
		(end 75.922488 100.325)
		(width 0.125)
		(layer "In5.Cu")
		(net 497)
	)
	(segment
		(start 83.242488 98.395)
		(end 81.312488 100.325)
		(width 0.125)
		(layer "In5.Cu")
		(net 497)
	)
	(segment
		(start 84.375 91.222488)
		(end 84.375 92.265)
		(width 0.125)
		(layer "In5.Cu")
		(net 497)
	)
	(segment
		(start 84.21983 89.671912)
		(end 84.21983 89.671911)
		(width 0.125)
		(layer "In5.Cu")
		(net 497)
	)
	(arc
		(start 84.556278 95.065)
		(mid 84.428095 95.118095)
		(end 84.375 95.246278)
		(width 0.125)
		(layer "In5.Cu")
		(net 497)
	)
	(arc
		(start 84.731278 92.446278)
		(mid 85.106948 92.601886)
		(end 85.262556 92.977556)
		(width 0.125)
		(layer "In5.Cu")
		(net 497)
	)
	(arc
		(start 84.731278 93.965)
		(mid 85.106948 94.120608)
		(end 85.262556 94.496278)
		(width 0.125)
		(layer "In5.Cu")
		(net 497)
	)
	(arc
		(start 84.375 92.265)
		(mid 84.428095 92.393183)
		(end 84.556278 92.446278)
		(width 0.125)
		(layer "In5.Cu")
		(net 497)
	)
	(arc
		(start 84.21983 89.671911)
		(mid 84.146607 89.848687)
		(end 84.21983 90.025463)
		(width 0.125)
		(layer "In5.Cu")
		(net 497)
	)
	(arc
		(start 85.673743 89.923743)
		(mid 85.249479 90.099479)
		(end 84.825215 89.923743)
		(width 0.125)
		(layer "In5.Cu")
		(net 497)
	)
	(arc
		(start 84.573383 89.671911)
		(mid 84.396606 89.598688)
		(end 84.21983 89.671912)
		(width 0.125)
		(layer "In5.Cu")
		(net 497)
	)
	(arc
		(start 85.262556 93.015)
		(mid 85.106948 93.39067)
		(end 84.731278 93.546278)
		(width 0.125)
		(layer "In5.Cu")
		(net 497)
	)
	(arc
		(start 84.471661 90.277295)
		(mid 84.647397 90.701559)
		(end 84.471661 91.125823)
		(width 0.125)
		(layer "In5.Cu")
		(net 497)
	)
	(arc
		(start 84.55 93.546278)
		(mid 84.421817 93.599373)
		(end 84.368722 93.727556)
		(width 0.125)
		(layer "In5.Cu")
		(net 497)
	)
	(arc
		(start 85.262556 94.533722)
		(mid 85.106948 94.909392)
		(end 84.731278 95.065)
		(width 0.125)
		(layer "In5.Cu")
		(net 497)
	)
	(arc
		(start 84.368722 93.783722)
		(mid 84.421817 93.911905)
		(end 84.55 93.965001)
		(width 0.125)
		(layer "In5.Cu")
		(net 497)
	)
	(segment
		(start 89.5075 89.075)
		(end 89.6325 88.95)
		(width 0.125)
		(layer "B.Cu")
		(net 497)
	)
	(segment
		(start 85.803294 89.066517)
		(end 85.811777 89.075)
		(width 0.125)
		(layer "B.Cu")
		(net 497)
	)
	(segment
		(start 85.811777 89.075)
		(end 89.5075 89.075)
		(width 0.125)
		(layer "B.Cu")
		(net 497)
	)
	(segment
		(start 85.803294 88.836706)
		(end 85.803294 89.066517)
		(width 0.125)
		(layer "B.Cu")
		(net 497)
	)
	(segment
		(start 90.625 122.725)
		(end 90.75 122.6)
		(width 0.2)
		(layer "F.Cu")
		(net 498)
	)
	(segment
		(start 88.55 117.75)
		(end 88.835 117.465)
		(width 0.2)
		(layer "F.Cu")
		(net 498)
	)
	(segment
		(start 88.55 119)
		(end 88.55 117.75)
		(width 0.2)
		(layer "F.Cu")
		(net 498)
	)
	(segment
		(start 89.75 122.6)
		(end 89.875 122.725)
		(width 0.2)
		(layer "F.Cu")
		(net 498)
	)
	(segment
		(start 88.45 120.8)
		(end 89.05 120.8)
		(width 0.2)
		(layer "F.Cu")
		(net 498)
	)
	(segment
		(start 88.835 117.465)
		(end 89.3 117.465)
		(width 0.2)
		(layer "F.Cu")
		(net 498)
	)
	(segment
		(start 89.05 120.8)
		(end 89.75 121.5)
		(width 0.2)
		(layer "F.Cu")
		(net 498)
	)
	(segment
		(start 88.55 119)
		(end 88.55 120.7)
		(width 0.2)
		(layer "F.Cu")
		(net 498)
	)
	(segment
		(start 90.75 122.6)
		(end 90.75 122)
		(width 0.2)
		(layer "F.Cu")
		(net 498)
	)
	(segment
		(start 88.401 119.149)
		(end 88.401 119.5)
		(width 0.2)
		(layer "F.Cu")
		(net 498)
	)
	(segment
		(start 90.305 117.25)
		(end 89.515 117.25)
		(width 0.2)
		(layer "F.Cu")
		(net 498)
	)
	(segment
		(start 89.515 117.25)
		(end 89.3 117.465)
		(width 0.2)
		(layer "F.Cu")
		(net 498)
	)
	(segment
		(start 88.55 120.7)
		(end 88.45 120.8)
		(width 0.2)
		(layer "F.Cu")
		(net 498)
	)
	(segment
		(start 89.670025 117.25)
		(end 90.305 117.25)
		(width 0.155)
		(layer "F.Cu")
		(net 498)
	)
	(segment
		(start 89.875 122.725)
		(end 90.625 122.725)
		(width 0.2)
		(layer "F.Cu")
		(net 498)
	)
	(segment
		(start 89.75 121.5)
		(end 89.75 122.6)
		(width 0.2)
		(layer "F.Cu")
		(net 498)
	)
	(segment
		(start 88.55 119)
		(end 88.401 119.149)
		(width 0.2)
		(layer "F.Cu")
		(net 498)
	)
	(via
		(at 88.55 119)
		(size 0.45)
		(drill 0.1)
		(layers "F.Cu" "B.Cu")
		(net 498)
	)
	(segment
		(start 91.3 117.515)
		(end 89.9 117.515)
		(width 0.155)
		(layer "B.Cu")
		(net 498)
	)
	(segment
		(start 89.9 117.515)
		(end 88.785 117.515)
		(width 0.2)
		(layer "B.Cu")
		(net 498)
	)
	(segment
		(start 88.785 117.515)
		(end 88.55 117.75)
		(width 0.2)
		(layer "B.Cu")
		(net 498)
	)
	(segment
		(start 88.55 117.75)
		(end 88.55 119)
		(width 0.2)
		(layer "B.Cu")
		(net 498)
	)
	(segment
		(start 44.64 73.975)
		(end 44.04 73.975)
		(width 0.15)
		(layer "B.Cu")
		(net 500)
	)
	(segment
		(start 43.24 73.175)
		(end 42.125 73.175)
		(width 0.15)
		(layer "B.Cu")
		(net 500)
	)
	(segment
		(start 44.04 73.975)
		(end 43.24 73.175)
		(width 0.15)
		(layer "B.Cu")
		(net 500)
	)
	(segment
		(start 42.125 73.175)
		(end 41.85 73.45)
		(width 0.15)
		(layer "B.Cu")
		(net 500)
	)
	(segment
		(start 64.585 115.27)
		(end 64.585 122.375)
		(width 0.15)
		(layer "F.Cu")
		(net 501)
	)
	(segment
		(start 64.05 112.635)
		(end 63.425 112.635)
		(width 0.15)
		(layer "F.Cu")
		(net 501)
	)
	(segment
		(start 63.11 113.795)
		(end 64.585 115.27)
		(width 0.15)
		(layer "F.Cu")
		(net 501)
	)
	(segment
		(start 63.425 112.635)
		(end 63.11 112.95)
		(width 0.15)
		(layer "F.Cu")
		(net 501)
	)
	(segment
		(start 64.05 112.63)
		(end 64.05 111.45)
		(width 0.15)
		(layer "F.Cu")
		(net 501)
	)
	(segment
		(start 63.11 112.95)
		(end 63.11 113.795)
		(width 0.15)
		(layer "F.Cu")
		(net 501)
	)
	(segment
		(start 64.585 122.375)
		(end 64.475 122.485)
		(width 0.15)
		(layer "F.Cu")
		(net 501)
	)
	(segment
		(start 73.75 109.325)
		(end 73.7 109.375)
		(width 0.15)
		(layer "F.Cu")
		(net 502)
	)
	(segment
		(start 73.75 108.767469)
		(end 73.75 109.325)
		(width 0.15)
		(layer "F.Cu")
		(net 502)
	)
	(via
		(at 73.7 109.375)
		(size 0.45)
		(drill 0.1)
		(layers "F.Cu" "B.Cu")
		(net 502)
	)
	(segment
		(start 73.975 110.14)
		(end 73.975 109.65)
		(width 0.15)
		(layer "B.Cu")
		(net 502)
	)
	(segment
		(start 73.975 109.65)
		(end 73.7 109.375)
		(width 0.15)
		(layer "B.Cu")
		(net 502)
	)
	(segment
		(start 66.95 114.2)
		(end 66.95 112.75)
		(width 0.125)
		(layer "F.Cu")
		(net 505)
	)
	(via
		(at 66.95 112.75)
		(size 0.45)
		(drill 0.1)
		(layers "F.Cu" "B.Cu")
		(net 505)
	)
	(via
		(at 90.8 113.15)
		(size 0.45)
		(drill 0.1)
		(layers "F.Cu" "B.Cu")
		(net 505)
	)
	(segment
		(start 66.95 112.75)
		(end 67.153554 112.546446)
		(width 0.125)
		(layer "In5.Cu")
		(net 505)
	)
	(segment
		(start 90.5 114.1)
		(end 90.8 113.8)
		(width 0.125)
		(layer "In5.Cu")
		(net 505)
	)
	(segment
		(start 85.55 115.35)
		(end 86.8 114.1)
		(width 0.125)
		(layer "In5.Cu")
		(net 505)
	)
	(segment
		(start 86.8 114.1)
		(end 90.5 114.1)
		(width 0.125)
		(layer "In5.Cu")
		(net 505)
	)
	(segment
		(start 75.103554 115.35)
		(end 85.55 115.35)
		(width 0.125)
		(layer "In5.Cu")
		(net 505)
	)
	(segment
		(start 90.8 113.8)
		(end 90.8 113.15)
		(width 0.125)
		(layer "In5.Cu")
		(net 505)
	)
	(segment
		(start 72.3 112.546446)
		(end 75.103554 115.35)
		(width 0.125)
		(layer "In5.Cu")
		(net 505)
	)
	(segment
		(start 67.153554 112.546446)
		(end 72.3 112.546446)
		(width 0.125)
		(layer "In5.Cu")
		(net 505)
	)
	(segment
		(start 91.98 114.715)
		(end 90.8 113.535)
		(width 0.125)
		(layer "B.Cu")
		(net 505)
	)
	(segment
		(start 90.8 113.15)
		(end 91 112.95)
		(width 0.125)
		(layer "B.Cu")
		(net 505)
	)
	(segment
		(start 90.8 113.535)
		(end 90.8 113.15)
		(width 0.125)
		(layer "B.Cu")
		(net 505)
	)
	(segment
		(start 91 112.95)
		(end 91 112.55)
		(width 0.125)
		(layer "B.Cu")
		(net 505)
	)
	(segment
		(start 92.35 114.715)
		(end 91.98 114.715)
		(width 0.125)
		(layer "B.Cu")
		(net 505)
	)
	(segment
		(start 104.716 120.551)
		(end 104.725 120.56)
		(width 0.15)
		(layer "F.Cu")
		(net 508)
	)
	(segment
		(start 104.5005 120.5855)
		(end 104.665 120.75)
		(width 0.125)
		(layer "F.Cu")
		(net 508)
	)
	(segment
		(start 104.5005 119.688)
		(end 104.5005 120.5855)
		(width 0.125)
		(layer "F.Cu")
		(net 508)
	)
	(segment
		(start 103.304 120.551)
		(end 104.716 120.551)
		(width 0.15)
		(layer "F.Cu")
		(net 508)
	)
	(via
		(at 91.412 113.5)
		(size 0.45)
		(drill 0.1)
		(layers "F.Cu" "B.Cu")
		(net 508)
	)
	(via
		(at 104.5005 119.688)
		(size 0.45)
		(drill 0.1)
		(layers "F.Cu" "B.Cu")
		(net 508)
	)
	(segment
		(start 91.412 113.5)
		(end 91.925 113.5)
		(width 0.125)
		(layer "In3.Cu")
		(net 508)
	)
	(segment
		(start 93.438 119.688)
		(end 104.5005 119.688)
		(width 0.125)
		(layer "In3.Cu")
		(net 508)
	)
	(segment
		(start 93.15 119.4)
		(end 93.438 119.688)
		(width 0.125)
		(layer "In3.Cu")
		(net 508)
	)
	(segment
		(start 91.925 113.5)
		(end 93.15 114.725)
		(width 0.125)
		(layer "In3.Cu")
		(net 508)
	)
	(segment
		(start 93.15 114.725)
		(end 93.15 119.4)
		(width 0.125)
		(layer "In3.Cu")
		(net 508)
	)
	(segment
		(start 91.4 113.488)
		(end 91.4 112.55)
		(width 0.125)
		(layer "B.Cu")
		(net 508)
	)
	(segment
		(start 91.412 113.5)
		(end 91.4 113.488)
		(width 0.125)
		(layer "B.Cu")
		(net 508)
	)
	(segment
		(start 97.0475 100.2525)
		(end 96.7825 100.2525)
		(width 0.15)
		(layer "F.Cu")
		(net 511)
	)
	(segment
		(start 97.333318 100.538318)
		(end 97.0475 100.2525)
		(width 0.15)
		(layer "F.Cu")
		(net 511)
	)
	(segment
		(start 96.7825 100.2525)
		(end 96.635 100.4)
		(width 0.15)
		(layer "F.Cu")
		(net 511)
	)
	(segment
		(start 97.333318 101.216682)
		(end 97.333318 100.538318)
		(width 0.15)
		(layer "F.Cu")
		(net 511)
	)
	(via
		(at 97.333318 101.216682)
		(size 0.45)
		(drill 0.1)
		(layers "F.Cu" "B.Cu")
		(net 511)
	)
	(segment
		(start 97.333318 101.216682)
		(end 97.573318 101.216682)
		(width 0.15)
		(layer "B.Cu")
		(net 511)
	)
	(segment
		(start 97.573318 101.216682)
		(end 97.79 101)
		(width 0.15)
		(layer "B.Cu")
		(net 511)
	)
	(segment
		(start 97.7825 101.6825)
		(end 96.9175 101.6825)
		(width 0.15)
		(layer "F.Cu")
		(net 512)
	)
	(segment
		(start 98 101.9)
		(end 97.7825 101.6825)
		(width 0.15)
		(layer "F.Cu")
		(net 512)
	)
	(segment
		(start 96.9175 101.6825)
		(end 96.635 101.4)
		(width 0.15)
		(layer "F.Cu")
		(net 512)
	)
	(via
		(at 98 101.9)
		(size 0.45)
		(drill 0.1)
		(layers "F.Cu" "B.Cu")
		(net 512)
	)
	(segment
		(start 98 101.5)
		(end 98 101.9)
		(width 0.15)
		(layer "B.Cu")
		(net 512)
	)
	(segment
		(start 146 95.15)
		(end 146.65 95.15)
		(width 0.15)
		(layer "F.Cu")
		(net 513)
	)
	(segment
		(start 146.65 95.15)
		(end 146.8 95.3)
		(width 0.15)
		(layer "F.Cu")
		(net 513)
	)
	(segment
		(start 146.8 95.3)
		(end 147.3 95.3)
		(width 0.15)
		(layer "F.Cu")
		(net 513)
	)
	(via
		(at 58.85 105.2)
		(size 0.45)
		(drill 0.1)
		(layers "F.Cu" "B.Cu")
		(net 514)
	)
	(via
		(at 91.4 107.9)
		(size 0.45)
		(drill 0.1)
		(layers "F.Cu" "B.Cu")
		(net 514)
	)
	(segment
		(start 65.7 108.6)
		(end 67.9 108.6)
		(width 0.125)
		(layer "In5.Cu")
		(net 514)
	)
	(segment
		(start 58.9 108.1)
		(end 59.6125 108.8125)
		(width 0.125)
		(layer "In5.Cu")
		(net 514)
	)
	(segment
		(start 91.3 107.8)
		(end 91.4 107.9)
		(width 0.125)
		(layer "In5.Cu")
		(net 514)
	)
	(segment
		(start 85.9875 108.8125)
		(end 87 107.8)
		(width 0.125)
		(layer "In5.Cu")
		(net 514)
	)
	(segment
		(start 58.85 105.2)
		(end 58.9 105.25)
		(width 0.125)
		(layer "In5.Cu")
		(net 514)
	)
	(segment
		(start 67.9 108.6)
		(end 68.1125 108.8125)
		(width 0.125)
		(layer "In5.Cu")
		(net 514)
	)
	(segment
		(start 59.6125 108.8125)
		(end 65.4875 108.8125)
		(width 0.125)
		(layer "In5.Cu")
		(net 514)
	)
	(segment
		(start 65.4875 108.8125)
		(end 65.7 108.6)
		(width 0.125)
		(layer "In5.Cu")
		(net 514)
	)
	(segment
		(start 87 107.8)
		(end 91.3 107.8)
		(width 0.125)
		(layer "In5.Cu")
		(net 514)
	)
	(segment
		(start 58.9 105.25)
		(end 58.9 108.1)
		(width 0.125)
		(layer "In5.Cu")
		(net 514)
	)
	(segment
		(start 68.1125 108.8125)
		(end 85.9875 108.8125)
		(width 0.125)
		(layer "In5.Cu")
		(net 514)
	)
	(segment
		(start 91.1 105.9)
		(end 90.785 105.9)
		(width 0.15)
		(layer "B.Cu")
		(net 514)
	)
	(segment
		(start 91.4 107.9)
		(end 91.24 107.74)
		(width 0.15)
		(layer "B.Cu")
		(net 514)
	)
	(segment
		(start 58.275 104.625)
		(end 57.235 104.625)
		(width 0.15)
		(layer "B.Cu")
		(net 514)
	)
	(segment
		(start 91.24 107.74)
		(end 91.24 106.04)
		(width 0.15)
		(layer "B.Cu")
		(net 514)
	)
	(segment
		(start 90.785 105.9)
		(end 90.735 105.95)
		(width 0.15)
		(layer "B.Cu")
		(net 514)
	)
	(segment
		(start 91.24 106.04)
		(end 91.1 105.9)
		(width 0.15)
		(layer "B.Cu")
		(net 514)
	)
	(segment
		(start 58.85 105.2)
		(end 58.275 104.625)
		(width 0.15)
		(layer "B.Cu")
		(net 514)
	)
	(segment
		(start 138.35 95.6)
		(end 138.65 95.3)
		(width 0.15)
		(layer "F.Cu")
		(net 515)
	)
	(segment
		(start 138.65 95.3)
		(end 140.15 95.3)
		(width 0.15)
		(layer "F.Cu")
		(net 515)
	)
	(segment
		(start 137.85 95.6)
		(end 138.35 95.6)
		(width 0.15)
		(layer "F.Cu")
		(net 515)
	)
	(segment
		(start 140.8 95.95)
		(end 141.5 95.95)
		(width 0.15)
		(layer "F.Cu")
		(net 515)
	)
	(segment
		(start 140.15 95.3)
		(end 140.8 95.95)
		(width 0.15)
		(layer "F.Cu")
		(net 515)
	)
	(segment
		(start 120.8 85.35)
		(end 120.8 86.675)
		(width 0.15)
		(layer "F.Cu")
		(net 516)
	)
	(segment
		(start 101.097323 74.347323)
		(end 101.097323 72.005136)
		(width 0.15)
		(layer "F.Cu")
		(net 516)
	)
	(segment
		(start 119.9 90.8)
		(end 118.4 92.3)
		(width 0.15)
		(layer "F.Cu")
		(net 516)
	)
	(segment
		(start 119.537417 84.087417)
		(end 120.8 85.35)
		(width 0.15)
		(layer "F.Cu")
		(net 516)
	)
	(segment
		(start 120.8 86.675)
		(end 119.75 87.725)
		(width 0.15)
		(layer "F.Cu")
		(net 516)
	)
	(segment
		(start 102.03 78.745)
		(end 102.03 75.28)
		(width 0.15)
		(layer "F.Cu")
		(net 516)
	)
	(segment
		(start 102.03 75.28)
		(end 101.097323 74.347323)
		(width 0.15)
		(layer "F.Cu")
		(net 516)
	)
	(segment
		(start 113.25 92.85)
		(end 113.25 94.35)
		(width 0.15)
		(layer "F.Cu")
		(net 516)
	)
	(segment
		(start 119.75 87.725)
		(end 119.75 89.35)
		(width 0.15)
		(layer "F.Cu")
		(net 516)
	)
	(segment
		(start 118.4 92.3)
		(end 113.8 92.3)
		(width 0.15)
		(layer "F.Cu")
		(net 516)
	)
	(segment
		(start 119.75 89.35)
		(end 119.9 89.5)
		(width 0.15)
		(layer "F.Cu")
		(net 516)
	)
	(segment
		(start 113.25 94.35)
		(end 113.75 94.85)
		(width 0.15)
		(layer "F.Cu")
		(net 516)
	)
	(segment
		(start 113.8 92.3)
		(end 113.25 92.85)
		(width 0.15)
		(layer "F.Cu")
		(net 516)
	)
	(segment
		(start 102.025 78.75)
		(end 102.03 78.745)
		(width 0.15)
		(layer "F.Cu")
		(net 516)
	)
	(segment
		(start 118.847083 84.087417)
		(end 119.537417 84.087417)
		(width 0.15)
		(layer "F.Cu")
		(net 516)
	)
	(segment
		(start 113.75 94.85)
		(end 114.25 94.85)
		(width 0.15)
		(layer "F.Cu")
		(net 516)
	)
	(segment
		(start 119.9 89.5)
		(end 119.9 90.8)
		(width 0.15)
		(layer "F.Cu")
		(net 516)
	)
	(via
		(at 118.847083 84.087417)
		(size 0.45)
		(drill 0.1)
		(layers "F.Cu" "B.Cu")
		(net 516)
	)
	(via
		(at 102.025 78.75)
		(size 0.45)
		(drill 0.1)
		(layers "F.Cu" "B.Cu")
		(net 516)
	)
	(segment
		(start 113.55 77.7)
		(end 112.425 76.575)
		(width 0.15)
		(layer "In5.Cu")
		(net 516)
	)
	(segment
		(start 117.75 81)
		(end 116.3 79.55)
		(width 0.15)
		(layer "In5.Cu")
		(net 516)
	)
	(segment
		(start 118.51 83.750334)
		(end 118.51 82.16)
		(width 0.15)
		(layer "In5.Cu")
		(net 516)
	)
	(segment
		(start 104.225 76.05)
		(end 102.025 78.25)
		(width 0.15)
		(layer "In5.Cu")
		(net 516)
	)
	(segment
		(start 109.35 75.4)
		(end 107.9 75.4)
		(width 0.15)
		(layer "In5.Cu")
		(net 516)
	)
	(segment
		(start 116.3 78.6)
		(end 115.4 77.7)
		(width 0.15)
		(layer "In5.Cu")
		(net 516)
	)
	(segment
		(start 112.425 76.575)
		(end 110.525 76.575)
		(width 0.15)
		(layer "In5.Cu")
		(net 516)
	)
	(segment
		(start 118.847083 84.087417)
		(end 118.51 83.750334)
		(width 0.15)
		(layer "In5.Cu")
		(net 516)
	)
	(segment
		(start 110.525 76.575)
		(end 109.35 75.4)
		(width 0.15)
		(layer "In5.Cu")
		(net 516)
	)
	(segment
		(start 118.51 82.16)
		(end 117.75 81.4)
		(width 0.15)
		(layer "In5.Cu")
		(net 516)
	)
	(segment
		(start 115.4 77.7)
		(end 113.55 77.7)
		(width 0.15)
		(layer "In5.Cu")
		(net 516)
	)
	(segment
		(start 116.3 79.55)
		(end 116.3 78.6)
		(width 0.15)
		(layer "In5.Cu")
		(net 516)
	)
	(segment
		(start 107.9 75.4)
		(end 107.25 76.05)
		(width 0.15)
		(layer "In5.Cu")
		(net 516)
	)
	(segment
		(start 117.75 81.4)
		(end 117.75 81)
		(width 0.15)
		(layer "In5.Cu")
		(net 516)
	)
	(segment
		(start 102.025 78.25)
		(end 102.025 78.75)
		(width 0.15)
		(layer "In5.Cu")
		(net 516)
	)
	(segment
		(start 107.25 76.05)
		(end 104.225 76.05)
		(width 0.15)
		(layer "In5.Cu")
		(net 516)
	)
	(segment
		(start 121.36 86.26)
		(end 121.62 86.52)
		(width 0.15)
		(layer "F.Cu")
		(net 517)
	)
	(segment
		(start 114.35 93.25)
		(end 114.25 93.35)
		(width 0.15)
		(layer "F.Cu")
		(net 517)
	)
	(segment
		(start 120.66 88.59)
		(end 120.66 88.96)
		(width 0.15)
		(layer "F.Cu")
		(net 517)
	)
	(segment
		(start 118.5 83.65)
		(end 119.55 83.65)
		(width 0.15)
		(layer "F.Cu")
		(net 517)
	)
	(segment
		(start 102.575 78.475)
		(end 102.55 78.45)
		(width 0.15)
		(layer "F.Cu")
		(net 517)
	)
	(segment
		(start 102.55 78.45)
		(end 102.55 74.975)
		(width 0.15)
		(layer "F.Cu")
		(net 517)
	)
	(segment
		(start 118.06 84.13)
		(end 118.06 84.09)
		(width 0.15)
		(layer "F.Cu")
		(net 517)
	)
	(segment
		(start 121.36 85.46)
		(end 121.36 86.26)
		(width 0.15)
		(layer "F.Cu")
		(net 517)
	)
	(segment
		(start 120.8 89.1)
		(end 120.8 91.22)
		(width 0.15)
		(layer "F.Cu")
		(net 517)
	)
	(segment
		(start 121.8 87.95)
		(end 121.3 87.95)
		(width 0.15)
		(layer "F.Cu")
		(net 517)
	)
	(segment
		(start 122.03 86.52)
		(end 122.3 86.79)
		(width 0.15)
		(layer "F.Cu")
		(net 517)
	)
	(segment
		(start 119.55 83.65)
		(end 121.36 85.46)
		(width 0.15)
		(layer "F.Cu")
		(net 517)
	)
	(segment
		(start 118.06 84.09)
		(end 118.5 83.65)
		(width 0.15)
		(layer "F.Cu")
		(net 517)
	)
	(segment
		(start 102.55 74.975)
		(end 101.597323 74.022323)
		(width 0.15)
		(layer "F.Cu")
		(net 517)
	)
	(segment
		(start 122.3 87.45)
		(end 121.8 87.95)
		(width 0.15)
		(layer "F.Cu")
		(net 517)
	)
	(segment
		(start 120.8 91.22)
		(end 118.77 93.25)
		(width 0.15)
		(layer "F.Cu")
		(net 517)
	)
	(segment
		(start 101.597323 74.022323)
		(end 101.597323 72.005136)
		(width 0.15)
		(layer "F.Cu")
		(net 517)
	)
	(segment
		(start 121.62 86.52)
		(end 122.03 86.52)
		(width 0.15)
		(layer "F.Cu")
		(net 517)
	)
	(segment
		(start 121.3 87.95)
		(end 120.66 88.59)
		(width 0.15)
		(layer "F.Cu")
		(net 517)
	)
	(segment
		(start 114.25 93.35)
		(end 114.25 93.65)
		(width 0.15)
		(layer "F.Cu")
		(net 517)
	)
	(segment
		(start 120.66 88.96)
		(end 120.8 89.1)
		(width 0.15)
		(layer "F.Cu")
		(net 517)
	)
	(segment
		(start 118.77 93.25)
		(end 114.35 93.25)
		(width 0.15)
		(layer "F.Cu")
		(net 517)
	)
	(segment
		(start 122.3 86.79)
		(end 122.3 87.45)
		(width 0.15)
		(layer "F.Cu")
		(net 517)
	)
	(via
		(at 118.06 84.13)
		(size 0.45)
		(drill 0.1)
		(layers "F.Cu" "B.Cu")
		(net 517)
	)
	(via
		(at 102.575 78.475)
		(size 0.45)
		(drill 0.1)
		(layers "F.Cu" "B.Cu")
		(net 517)
	)
	(segment
		(start 118.06 82.11)
		(end 118.06 84.13)
		(width 0.15)
		(layer "In5.Cu")
		(net 517)
	)
	(segment
		(start 108.02 75.7)
		(end 109.2 75.7)
		(width 0.15)
		(layer "In5.Cu")
		(net 517)
	)
	(segment
		(start 117.45 81.15)
		(end 117.45 81.5)
		(width 0.15)
		(layer "In5.Cu")
		(net 517)
	)
	(segment
		(start 115.275 77.975)
		(end 116 78.7)
		(width 0.15)
		(layer "In5.Cu")
		(net 517)
	)
	(segment
		(start 107.37 76.35)
		(end 108.02 75.7)
		(width 0.15)
		(layer "In5.Cu")
		(net 517)
	)
	(segment
		(start 117.45 81.5)
		(end 118.06 82.11)
		(width 0.15)
		(layer "In5.Cu")
		(net 517)
	)
	(segment
		(start 102.575 78.225)
		(end 104.45 76.35)
		(width 0.15)
		(layer "In5.Cu")
		(net 517)
	)
	(segment
		(start 116 79.7)
		(end 117.45 81.15)
		(width 0.15)
		(layer "In5.Cu")
		(net 517)
	)
	(segment
		(start 102.575 78.475)
		(end 102.575 78.225)
		(width 0.15)
		(layer "In5.Cu")
		(net 517)
	)
	(segment
		(start 113.425 77.975)
		(end 115.275 77.975)
		(width 0.15)
		(layer "In5.Cu")
		(net 517)
	)
	(segment
		(start 110.35 76.85)
		(end 112.3 76.85)
		(width 0.15)
		(layer "In5.Cu")
		(net 517)
	)
	(segment
		(start 104.45 76.35)
		(end 107.37 76.35)
		(width 0.15)
		(layer "In5.Cu")
		(net 517)
	)
	(segment
		(start 116 78.7)
		(end 116 79.7)
		(width 0.15)
		(layer "In5.Cu")
		(net 517)
	)
	(segment
		(start 109.2 75.7)
		(end 110.35 76.85)
		(width 0.15)
		(layer "In5.Cu")
		(net 517)
	)
	(segment
		(start 112.3 76.85)
		(end 113.425 77.975)
		(width 0.15)
		(layer "In5.Cu")
		(net 517)
	)
	(segment
		(start 90.1 120.285)
		(end 90.1 119.515)
		(width 0.155)
		(layer "F.Cu")
		(net 518)
	)
	(segment
		(start 90.1 119.515)
		(end 90.1 118.95)
		(width 0.155)
		(layer "F.Cu")
		(net 518)
	)
	(segment
		(start 91.55 121.4)
		(end 90.95 120.8)
		(width 0.155)
		(layer "F.Cu")
		(net 518)
	)
	(segment
		(start 90.1 120.5)
		(end 90.1 120.285)
		(width 0.155)
		(layer "F.Cu")
		(net 518)
	)
	(segment
		(start 90.95 120.8)
		(end 90.4 120.8)
		(width 0.155)
		(layer "F.Cu")
		(net 518)
	)
	(segment
		(start 90.4 120.8)
		(end 90.1 120.5)
		(width 0.155)
		(layer "F.Cu")
		(net 518)
	)
	(segment
		(start 91.55 122)
		(end 91.55 121.4)
		(width 0.155)
		(layer "F.Cu")
		(net 518)
	)
	(segment
		(start 90.1 117.955)
		(end 90.305 117.75)
		(width 0.155)
		(layer "F.Cu")
		(net 518)
	)
	(segment
		(start 90.1 118.95)
		(end 90.1 117.955)
		(width 0.155)
		(layer "F.Cu")
		(net 518)
	)
	(via
		(at 90.1 118.95)
		(size 0.45)
		(drill 0.1)
		(layers "F.Cu" "B.Cu")
		(net 518)
	)
	(segment
		(start 90.1 118.95)
		(end 90.1 118.685)
		(width 0.155)
		(layer "B.Cu")
		(net 518)
	)
	(segment
		(start 90.1 118.685)
		(end 89.9 118.485)
		(width 0.155)
		(layer "B.Cu")
		(net 518)
	)
	(segment
		(start 91.95 121.35)
		(end 91.1 120.5)
		(width 0.155)
		(layer "F.Cu")
		(net 519)
	)
	(segment
		(start 91.1 118.95)
		(end 91.1 117.96)
		(width 0.155)
		(layer "F.Cu")
		(net 519)
	)
	(segment
		(start 91.1 120.5)
		(end 91.1 120.285)
		(width 0.155)
		(layer "F.Cu")
		(net 519)
	)
	(segment
		(start 91.1 120.285)
		(end 91.1 119.515)
		(width 0.155)
		(layer "F.Cu")
		(net 519)
	)
	(segment
		(start 91.1 119.515)
		(end 91.1 118.95)
		(width 0.155)
		(layer "F.Cu")
		(net 519)
	)
	(segment
		(start 91.1 117.96)
		(end 90.89 117.75)
		(width 0.155)
		(layer "F.Cu")
		(net 519)
	)
	(segment
		(start 91.95 122)
		(end 91.95 121.35)
		(width 0.155)
		(layer "F.Cu")
		(net 519)
	)
	(via
		(at 91.1 118.95)
		(size 0.45)
		(drill 0.1)
		(layers "F.Cu" "B.Cu")
		(net 519)
	)
	(segment
		(start 91.1 118.685)
		(end 91.3 118.485)
		(width 0.155)
		(layer "B.Cu")
		(net 519)
	)
	(segment
		(start 91.1 118.95)
		(end 91.1 118.685)
		(width 0.155)
		(layer "B.Cu")
		(net 519)
	)
	(segment
		(start 91.6 120.285)
		(end 91.6 119.515)
		(width 0.2)
		(layer "F.Cu")
		(net 520)
	)
	(segment
		(start 92.35 122)
		(end 92.35 121.25)
		(width 0.155)
		(layer "F.Cu")
		(net 520)
	)
	(segment
		(start 92.0492 118.6)
		(end 92.0492 118.9508)
		(width 0.2)
		(layer "F.Cu")
		(net 520)
	)
	(segment
		(start 91.6 119.4)
		(end 91.6 119.515)
		(width 0.2)
		(layer "F.Cu")
		(net 520)
	)
	(segment
		(start 92.35 121.25)
		(end 91.6 120.5)
		(width 0.155)
		(layer "F.Cu")
		(net 520)
	)
	(segment
		(start 91.6 120.5)
		(end 91.6 120.285)
		(width 0.155)
		(layer "F.Cu")
		(net 520)
	)
	(segment
		(start 92.0492 118.9508)
		(end 91.6 119.4)
		(width 0.2)
		(layer "F.Cu")
		(net 520)
	)
	(segment
		(start 93.225 121.49)
		(end 93.225 121.391778)
		(width 0.125)
		(layer "F.Cu")
		(net 521)
	)
	(segment
		(start 93.1 118.883222)
		(end 93.1 118.675)
		(width 0.125)
		(layer "F.Cu")
		(net 521)
	)
	(segment
		(start 93.1 118.675)
		(end 93.025 118.6)
		(width 0.125)
		(layer "F.Cu")
		(net 521)
	)
	(segment
		(start 93.225 121.391778)
		(end 92.75 120.916778)
		(width 0.125)
		(layer "F.Cu")
		(net 521)
	)
	(segment
		(start 92.625 119.515)
		(end 92.75 119.39)
		(width 0.125)
		(layer "F.Cu")
		(net 521)
	)
	(segment
		(start 92.75 120.41)
		(end 92.625 120.285)
		(width 0.125)
		(layer "F.Cu")
		(net 521)
	)
	(segment
		(start 93.15 121.95)
		(end 93.15 121.565)
		(width 0.125)
		(layer "F.Cu")
		(net 521)
	)
	(segment
		(start 92.75 119.233222)
		(end 93.1 118.883222)
		(width 0.125)
		(layer "F.Cu")
		(net 521)
	)
	(segment
		(start 92.75 120.916778)
		(end 92.75 120.41)
		(width 0.125)
		(layer "F.Cu")
		(net 521)
	)
	(segment
		(start 92.75 119.39)
		(end 92.75 119.233222)
		(width 0.125)
		(layer "F.Cu")
		(net 521)
	)
	(segment
		(start 92.625 119.515)
		(end 92.625 120.285)
		(width 0.125)
		(layer "F.Cu")
		(net 521)
	)
	(segment
		(start 93.15 121.565)
		(end 93.225 121.49)
		(width 0.125)
		(layer "F.Cu")
		(net 521)
	)
	(segment
		(start 93.55 121.565)
		(end 93.475 121.49)
		(width 0.125)
		(layer "F.Cu")
		(net 522)
	)
	(segment
		(start 93 120.41)
		(end 93.125 120.285)
		(width 0.125)
		(layer "F.Cu")
		(net 522)
	)
	(segment
		(start 93 120.813222)
		(end 93 120.41)
		(width 0.125)
		(layer "F.Cu")
		(net 522)
	)
	(segment
		(start 93.125 119.515)
		(end 93.125 119.275)
		(width 0.125)
		(layer "F.Cu")
		(net 522)
	)
	(segment
		(start 93.35 119.05)
		(end 93.35 118.675)
		(width 0.125)
		(layer "F.Cu")
		(net 522)
	)
	(segment
		(start 93.35 118.675)
		(end 93.425 118.6)
		(width 0.125)
		(layer "F.Cu")
		(net 522)
	)
	(segment
		(start 93.55 121.95)
		(end 93.55 121.565)
		(width 0.125)
		(layer "F.Cu")
		(net 522)
	)
	(segment
		(start 93.125 119.275)
		(end 93.35 119.05)
		(width 0.125)
		(layer "F.Cu")
		(net 522)
	)
	(segment
		(start 93.125 119.515)
		(end 93.125 120.285)
		(width 0.125)
		(layer "F.Cu")
		(net 522)
	)
	(segment
		(start 93.475 121.288222)
		(end 93 120.813222)
		(width 0.125)
		(layer "F.Cu")
		(net 522)
	)
	(segment
		(start 93.475 121.49)
		(end 93.475 121.288222)
		(width 0.125)
		(layer "F.Cu")
		(net 522)
	)
	(segment
		(start 94.35 121.565)
		(end 94.35 121.95)
		(width 0.125)
		(layer "F.Cu")
		(net 523)
	)
	(segment
		(start 94.425 121.49)
		(end 94.35 121.565)
		(width 0.125)
		(layer "F.Cu")
		(net 523)
	)
	(segment
		(start 94.25 120.41)
		(end 94.25 120.796778)
		(width 0.125)
		(layer "F.Cu")
		(net 523)
	)
	(segment
		(start 94.125 119.515)
		(end 94.125 119.201778)
		(width 0.125)
		(layer "F.Cu")
		(net 523)
	)
	(segment
		(start 94.125 119.515)
		(end 94.125 120.285)
		(width 0.125)
		(layer "F.Cu")
		(net 523)
	)
	(segment
		(start 94.125 119.201778)
		(end 93.9 118.976778)
		(width 0.125)
		(layer "F.Cu")
		(net 523)
	)
	(segment
		(start 93.9 118.675)
		(end 93.825 118.6)
		(width 0.125)
		(layer "F.Cu")
		(net 523)
	)
	(segment
		(start 93.9 118.976778)
		(end 93.9 118.675)
		(width 0.125)
		(layer "F.Cu")
		(net 523)
	)
	(segment
		(start 94.425 120.971778)
		(end 94.425 121.49)
		(width 0.125)
		(layer "F.Cu")
		(net 523)
	)
	(segment
		(start 94.125 120.285)
		(end 94.25 120.41)
		(width 0.125)
		(layer "F.Cu")
		(net 523)
	)
	(segment
		(start 94.25 120.796778)
		(end 94.425 120.971778)
		(width 0.125)
		(layer "F.Cu")
		(net 523)
	)
	(segment
		(start 94.625 119.348222)
		(end 94.15 118.873222)
		(width 0.125)
		(layer "F.Cu")
		(net 524)
	)
	(segment
		(start 94.15 118.873222)
		(end 94.15 118.675)
		(width 0.125)
		(layer "F.Cu")
		(net 524)
	)
	(segment
		(start 94.75 121.565)
		(end 94.75 121.95)
		(width 0.125)
		(layer "F.Cu")
		(net 524)
	)
	(segment
		(start 94.625 119.515)
		(end 94.625 120.285)
		(width 0.125)
		(layer "F.Cu")
		(net 524)
	)
	(segment
		(start 94.5 120.693222)
		(end 94.675 120.868222)
		(width 0.125)
		(layer "F.Cu")
		(net 524)
	)
	(segment
		(start 94.675 120.868222)
		(end 94.675 121.49)
		(width 0.125)
		(layer "F.Cu")
		(net 524)
	)
	(segment
		(start 94.5 120.41)
		(end 94.5 120.693222)
		(width 0.125)
		(layer "F.Cu")
		(net 524)
	)
	(segment
		(start 94.625 120.285)
		(end 94.5 120.41)
		(width 0.125)
		(layer "F.Cu")
		(net 524)
	)
	(segment
		(start 94.675 121.49)
		(end 94.75 121.565)
		(width 0.125)
		(layer "F.Cu")
		(net 524)
	)
	(segment
		(start 94.625 119.515)
		(end 94.625 119.348222)
		(width 0.125)
		(layer "F.Cu")
		(net 524)
	)
	(segment
		(start 94.15 118.675)
		(end 94.225 118.6)
		(width 0.125)
		(layer "F.Cu")
		(net 524)
	)
	(segment
		(start 95.625 121.49)
		(end 95.55 121.565)
		(width 0.125)
		(layer "F.Cu")
		(net 525)
	)
	(segment
		(start 96.15 118.793222)
		(end 96.15 118.675)
		(width 0.125)
		(layer "F.Cu")
		(net 525)
	)
	(segment
		(start 95.625 121.038222)
		(end 95.625 121.49)
		(width 0.125)
		(layer "F.Cu")
		(net 525)
	)
	(segment
		(start 96.15 118.675)
		(end 96.075 118.6)
		(width 0.125)
		(layer "F.Cu")
		(net 525)
	)
	(segment
		(start 95.8 120.863222)
		(end 95.625 121.038222)
		(width 0.125)
		(layer "F.Cu")
		(net 525)
	)
	(segment
		(start 95.8 119.39)
		(end 95.8 119.143222)
		(width 0.125)
		(layer "F.Cu")
		(net 525)
	)
	(segment
		(start 95.55 121.565)
		(end 95.55 121.95)
		(width 0.125)
		(layer "F.Cu")
		(net 525)
	)
	(segment
		(start 95.8 120.41)
		(end 95.8 120.863222)
		(width 0.125)
		(layer "F.Cu")
		(net 525)
	)
	(segment
		(start 95.675 119.515)
		(end 95.675 120.285)
		(width 0.125)
		(layer "F.Cu")
		(net 525)
	)
	(segment
		(start 95.675 120.285)
		(end 95.8 120.41)
		(width 0.125)
		(layer "F.Cu")
		(net 525)
	)
	(segment
		(start 95.675 119.515)
		(end 95.8 119.39)
		(width 0.125)
		(layer "F.Cu")
		(net 525)
	)
	(segment
		(start 95.8 119.143222)
		(end 96.15 118.793222)
		(width 0.125)
		(layer "F.Cu")
		(net 525)
	)
	(segment
		(start 96.175 119.515)
		(end 96.175 120.285)
		(width 0.125)
		(layer "F.Cu")
		(net 526)
	)
	(segment
		(start 96.05 119.39)
		(end 96.05 119.246778)
		(width 0.125)
		(layer "F.Cu")
		(net 526)
	)
	(segment
		(start 95.875 121.141778)
		(end 95.875 121.49)
		(width 0.125)
		(layer "F.Cu")
		(net 526)
	)
	(segment
		(start 96.05 119.246778)
		(end 96.4 118.896778)
		(width 0.125)
		(layer "F.Cu")
		(net 526)
	)
	(segment
		(start 96.175 120.285)
		(end 96.05 120.41)
		(width 0.125)
		(layer "F.Cu")
		(net 526)
	)
	(segment
		(start 96.175 119.515)
		(end 96.05 119.39)
		(width 0.125)
		(layer "F.Cu")
		(net 526)
	)
	(segment
		(start 95.95 121.565)
		(end 95.95 121.95)
		(width 0.125)
		(layer "F.Cu")
		(net 526)
	)
	(segment
		(start 95.875 121.49)
		(end 95.95 121.565)
		(width 0.125)
		(layer "F.Cu")
		(net 526)
	)
	(segment
		(start 96.4 118.896778)
		(end 96.4 118.675)
		(width 0.125)
		(layer "F.Cu")
		(net 526)
	)
	(segment
		(start 96.05 120.966778)
		(end 95.875 121.141778)
		(width 0.125)
		(layer "F.Cu")
		(net 526)
	)
	(segment
		(start 96.05 120.41)
		(end 96.05 120.966778)
		(width 0.125)
		(layer "F.Cu")
		(net 526)
	)
	(segment
		(start 96.4 118.675)
		(end 96.475 118.6)
		(width 0.125)
		(layer "F.Cu")
		(net 526)
	)
	(segment
		(start 96.825 121.258222)
		(end 97.3 120.783222)
		(width 0.125)
		(layer "F.Cu")
		(net 527)
	)
	(segment
		(start 96.95 118.976778)
		(end 96.95 118.675)
		(width 0.125)
		(layer "F.Cu")
		(net 527)
	)
	(segment
		(start 96.825 121.49)
		(end 96.825 121.258222)
		(width 0.125)
		(layer "F.Cu")
		(net 527)
	)
	(segment
		(start 97.175 119.515)
		(end 97.175 119.201778)
		(width 0.125)
		(layer "F.Cu")
		(net 527)
	)
	(segment
		(start 97.175 119.201778)
		(end 96.95 118.976778)
		(width 0.125)
		(layer "F.Cu")
		(net 527)
	)
	(segment
		(start 96.75 121.565)
		(end 96.825 121.49)
		(width 0.125)
		(layer "F.Cu")
		(net 527)
	)
	(segment
		(start 97.175 119.515)
		(end 97.175 120.285)
		(width 0.125)
		(layer "F.Cu")
		(net 527)
	)
	(segment
		(start 97.3 120.41)
		(end 97.175 120.285)
		(width 0.125)
		(layer "F.Cu")
		(net 527)
	)
	(segment
		(start 96.95 118.675)
		(end 96.875 118.6)
		(width 0.125)
		(layer "F.Cu")
		(net 527)
	)
	(segment
		(start 96.75 121.95)
		(end 96.75 121.565)
		(width 0.125)
		(layer "F.Cu")
		(net 527)
	)
	(segment
		(start 97.3 120.783222)
		(end 97.3 120.41)
		(width 0.125)
		(layer "F.Cu")
		(net 527)
	)
	(segment
		(start 97.15 121.95)
		(end 97.15 121.565)
		(width 0.125)
		(layer "F.Cu")
		(net 528)
	)
	(segment
		(start 97.075 121.49)
		(end 97.075 121.361778)
		(width 0.125)
		(layer "F.Cu")
		(net 528)
	)
	(segment
		(start 97.15 121.565)
		(end 97.075 121.49)
		(width 0.125)
		(layer "F.Cu")
		(net 528)
	)
	(segment
		(start 97.2 118.675)
		(end 97.275 118.6)
		(width 0.125)
		(layer "F.Cu")
		(net 528)
	)
	(segment
		(start 97.675 119.515)
		(end 97.675 120.285)
		(width 0.125)
		(layer "F.Cu")
		(net 528)
	)
	(segment
		(start 97.2 118.873222)
		(end 97.2 118.675)
		(width 0.125)
		(layer "F.Cu")
		(net 528)
	)
	(segment
		(start 97.675 119.348222)
		(end 97.2 118.873222)
		(width 0.125)
		(layer "F.Cu")
		(net 528)
	)
	(segment
		(start 97.675 119.515)
		(end 97.675 119.348222)
		(width 0.125)
		(layer "F.Cu")
		(net 528)
	)
	(segment
		(start 97.55 120.41)
		(end 97.675 120.285)
		(width 0.125)
		(layer "F.Cu")
		(net 528)
	)
	(segment
		(start 97.075 121.361778)
		(end 97.55 120.886778)
		(width 0.125)
		(layer "F.Cu")
		(net 528)
	)
	(segment
		(start 97.55 120.886778)
		(end 97.55 120.41)
		(width 0.125)
		(layer "F.Cu")
		(net 528)
	)
	(segment
		(start 89.6 119.515)
		(end 89.6 120.285)
		(width 0.155)
		(layer "F.Cu")
		(net 529)
	)
	(segment
		(start 89.6 120.5)
		(end 90.35 121.25)
		(width 0.155)
		(layer "F.Cu")
		(net 529)
	)
	(segment
		(start 85.88 114.81)
		(end 85.88 114.8)
		(width 0.2)
		(layer "F.Cu")
		(net 529)
	)
	(segment
		(start 90.35 121.25)
		(end 90.35 122)
		(width 0.155)
		(layer "F.Cu")
		(net 529)
	)
	(segment
		(start 89.6 120.285)
		(end 89.6 120.5)
		(width 0.155)
		(layer "F.Cu")
		(net 529)
	)
	(segment
		(start 87.05 114.685)
		(end 86 114.685)
		(width 0.2)
		(layer "F.Cu")
		(net 529)
	)
	(segment
		(start 89.6 119.515)
		(end 89.115 119.515)
		(width 0.155)
		(layer "F.Cu")
		(net 529)
	)
	(segment
		(start 89.115 119.515)
		(end 89.1 119.5)
		(width 0.155)
		(layer "F.Cu")
		(net 529)
	)
	(segment
		(start 86.7 115.4)
		(end 86.47 115.4)
		(width 0.2)
		(layer "F.Cu")
		(net 529)
	)
	(segment
		(start 85.885 114.8)
		(end 85.885 115.8)
		(width 0.2)
		(layer "F.Cu")
		(net 529)
	)
	(segment
		(start 86.47 115.4)
		(end 85.88 114.81)
		(width 0.2)
		(layer "F.Cu")
		(net 529)
	)
	(via
		(at 89.1 119.5)
		(size 0.45)
		(drill 0.1)
		(layers "F.Cu" "B.Cu")
		(net 529)
	)
	(via
		(at 86.7 115.4)
		(size 0.45)
		(drill 0.1)
		(layers "F.Cu" "B.Cu")
		(net 529)
	)
	(segment
		(start 88 116.7)
		(end 86.7 115.4)
		(width 0.125)
		(layer "In5.Cu")
		(net 529)
	)
	(segment
		(start 89 119.6)
		(end 88.3 119.6)
		(width 0.125)
		(layer "In5.Cu")
		(net 529)
	)
	(segment
		(start 88.3 119.6)
		(end 88 119.3)
		(width 0.125)
		(layer "In5.Cu")
		(net 529)
	)
	(segment
		(start 88 119.3)
		(end 88 116.7)
		(width 0.125)
		(layer "In5.Cu")
		(net 529)
	)
	(segment
		(start 89.1 119.5)
		(end 89 119.6)
		(width 0.125)
		(layer "In5.Cu")
		(net 529)
	)
	(segment
		(start 58.155 79.69)
		(end 58.415 79.95)
		(width 0.155)
		(layer "B.Cu")
		(net 530)
	)
	(segment
		(start 55.42 77.72)
		(end 55.25 77.55)
		(width 0.15)
		(layer "B.Cu")
		(net 530)
	)
	(segment
		(start 55.25 77.55)
		(end 55.25 76.35)
		(width 0.15)
		(layer "B.Cu")
		(net 530)
	)
	(segment
		(start 55.815 76.2)
		(end 56.03 75.985)
		(width 0.15)
		(layer "B.Cu")
		(net 530)
	)
	(segment
		(start 57.49 79.69)
		(end 57.429381 79.69)
		(width 0.15)
		(layer "B.Cu")
		(net 530)
	)
	(segment
		(start 56.03 75.985)
		(end 56.03 74.53)
		(width 0.15)
		(layer "B.Cu")
		(net 530)
	)
	(segment
		(start 55.25 76.35)
		(end 55.4 76.2)
		(width 0.15)
		(layer "B.Cu")
		(net 530)
	)
	(segment
		(start 56.8 78.1)
		(end 56.42 77.72)
		(width 0.15)
		(layer "B.Cu")
		(net 530)
	)
	(segment
		(start 57.429381 79.69)
		(end 56.8 79.060619)
		(width 0.15)
		(layer "B.Cu")
		(net 530)
	)
	(segment
		(start 56.42 77.72)
		(end 55.42 77.72)
		(width 0.15)
		(layer "B.Cu")
		(net 530)
	)
	(segment
		(start 55.4 76.2)
		(end 55.815 76.2)
		(width 0.15)
		(layer "B.Cu")
		(net 530)
	)
	(segment
		(start 57.49 79.69)
		(end 58.155 79.69)
		(width 0.155)
		(layer "B.Cu")
		(net 530)
	)
	(segment
		(start 56.8 79.060619)
		(end 56.8 78.1)
		(width 0.15)
		(layer "B.Cu")
		(net 530)
	)
	(segment
		(start 101.79999 100.49999)
		(end 102.05999 100.49999)
		(width 0.15)
		(layer "B.Cu")
		(net 535)
	)
	(segment
		(start 102.05999 100.49999)
		(end 103.11 101.55)
		(width 0.15)
		(layer "B.Cu")
		(net 535)
	)
	(segment
		(start 102.775 102.55)
		(end 102.475 102.25)
		(width 0.15)
		(layer "B.Cu")
		(net 536)
	)
	(segment
		(start 103.2242 102.55)
		(end 102.775 102.55)
		(width 0.15)
		(layer "B.Cu")
		(net 536)
	)
	(segment
		(start 102.475 102.25)
		(end 102.475 101.325)
		(width 0.15)
		(layer "B.Cu")
		(net 536)
	)
	(segment
		(start 102.475 101.325)
		(end 102.14999 100.99999)
		(width 0.15)
		(layer "B.Cu")
		(net 536)
	)
	(segment
		(start 102.14999 100.99999)
		(end 101.79999 100.99999)
		(width 0.15)
		(layer "B.Cu")
		(net 536)
	)
	(segment
		(start 101.79999 102.22499)
		(end 103.075 103.5)
		(width 0.15)
		(layer "B.Cu")
		(net 537)
	)
	(segment
		(start 101.79999 101.5)
		(end 101.79999 102.22499)
		(width 0.15)
		(layer "B.Cu")
		(net 537)
	)
	(segment
		(start 102.14999 103.12499)
		(end 102.14999 103.5)
		(width 0.15)
		(layer "B.Cu")
		(net 538)
	)
	(segment
		(start 101.3 102.8)
		(end 101.825 102.8)
		(width 0.15)
		(layer "B.Cu")
		(net 538)
	)
	(segment
		(start 101.14999 102.64999)
		(end 101.3 102.8)
		(width 0.15)
		(layer "B.Cu")
		(net 538)
	)
	(segment
		(start 101.14999 102.14999)
		(end 101.14999 102.64999)
		(width 0.15)
		(layer "B.Cu")
		(net 538)
	)
	(segment
		(start 101.825 102.8)
		(end 102.14999 103.12499)
		(width 0.15)
		(layer "B.Cu")
		(net 538)
	)
	(segment
		(start 101.14999 103.29999)
		(end 100.65 102.8)
		(width 0.15)
		(layer "B.Cu")
		(net 539)
	)
	(segment
		(start 100.65 102.8)
		(end 100.65 102.14999)
		(width 0.15)
		(layer "B.Cu")
		(net 539)
	)
	(segment
		(start 56.605 105.85)
		(end 56.605 106.195)
		(width 0.15)
		(layer "F.Cu")
		(net 540)
	)
	(segment
		(start 53.1 106.6)
		(end 52.2 107.5)
		(width 0.15)
		(layer "F.Cu")
		(net 540)
	)
	(segment
		(start 52.2 107.5)
		(end 52.2 111.5)
		(width 0.15)
		(layer "F.Cu")
		(net 540)
	)
	(segment
		(start 52.525 111.825)
		(end 53.55 111.825)
		(width 0.15)
		(layer "F.Cu")
		(net 540)
	)
	(segment
		(start 56.605 106.195)
		(end 56.2 106.6)
		(width 0.15)
		(layer "F.Cu")
		(net 540)
	)
	(segment
		(start 52.2 111.5)
		(end 52.525 111.825)
		(width 0.15)
		(layer "F.Cu")
		(net 540)
	)
	(segment
		(start 56.2 106.6)
		(end 53.1 106.6)
		(width 0.15)
		(layer "F.Cu")
		(net 540)
	)
	(segment
		(start 57.19 106.21)
		(end 56.4 107)
		(width 0.15)
		(layer "F.Cu")
		(net 541)
	)
	(segment
		(start 52.775 110.575)
		(end 53.55 110.575)
		(width 0.15)
		(layer "F.Cu")
		(net 541)
	)
	(segment
		(start 52.5 107.7)
		(end 52.5 110.3)
		(width 0.15)
		(layer "F.Cu")
		(net 541)
	)
	(segment
		(start 53.2 107)
		(end 52.5 107.7)
		(width 0.15)
		(layer "F.Cu")
		(net 541)
	)
	(segment
		(start 52.5 110.3)
		(end 52.775 110.575)
		(width 0.15)
		(layer "F.Cu")
		(net 541)
	)
	(segment
		(start 57.19 105.85)
		(end 57.19 106.21)
		(width 0.15)
		(layer "F.Cu")
		(net 541)
	)
	(segment
		(start 56.4 107)
		(end 53.2 107)
		(width 0.15)
		(layer "F.Cu")
		(net 541)
	)
	(segment
		(start 100.14999 103.5)
		(end 100.14999 102.14999)
		(width 0.15)
		(layer "B.Cu")
		(net 542)
	)
	(segment
		(start 99.14999 103.25001)
		(end 99.65 102.75)
		(width 0.15)
		(layer "B.Cu")
		(net 543)
	)
	(segment
		(start 99.65 102.75)
		(end 99.65 102.14999)
		(width 0.15)
		(layer "B.Cu")
		(net 543)
	)
	(segment
		(start 99.15 102.6)
		(end 98.25 103.5)
		(width 0.15)
		(layer "B.Cu")
		(net 544)
	)
	(segment
		(start 98.25 103.5)
		(end 98.14999 103.5)
		(width 0.15)
		(layer "B.Cu")
		(net 544)
	)
	(segment
		(start 99.15 102.14999)
		(end 99.15 102.6)
		(width 0.15)
		(layer "B.Cu")
		(net 544)
	)
	(segment
		(start 91 111.65)
		(end 91 111.95)
		(width 0.15)
		(layer "B.Cu")
		(net 545)
	)
	(segment
		(start 89.75 111.35)
		(end 89.9 111.5)
		(width 0.15)
		(layer "B.Cu")
		(net 545)
	)
	(segment
		(start 90.85 111.5)
		(end 91 111.65)
		(width 0.15)
		(layer "B.Cu")
		(net 545)
	)
	(segment
		(start 89.9 111.5)
		(end 90.85 111.5)
		(width 0.15)
		(layer "B.Cu")
		(net 545)
	)
	(segment
		(start 89.75 110.9)
		(end 89.75 111.35)
		(width 0.15)
		(layer "B.Cu")
		(net 545)
	)
	(segment
		(start 90.25 110.9)
		(end 91.05 110.9)
		(width 0.15)
		(layer "B.Cu")
		(net 546)
	)
	(segment
		(start 91.05 110.9)
		(end 91.4 111.25)
		(width 0.15)
		(layer "B.Cu")
		(net 546)
	)
	(segment
		(start 91.4 111.25)
		(end 91.4 111.95)
		(width 0.15)
		(layer "B.Cu")
		(net 546)
	)
	(segment
		(start 69.9 102.8)
		(end 68.65 104.05)
		(width 0.15)
		(layer "F.Cu")
		(net 549)
	)
	(segment
		(start 60.15 105.965)
		(end 61.115 105)
		(width 0.125)
		(layer "F.Cu")
		(net 549)
	)
	(segment
		(start 62.065 104.05)
		(end 61.115 105)
		(width 0.15)
		(layer "F.Cu")
		(net 549)
	)
	(segment
		(start 68.65 104.05)
		(end 62.065 104.05)
		(width 0.15)
		(layer "F.Cu")
		(net 549)
	)
	(segment
		(start 60.15 106.065)
		(end 60.15 105.965)
		(width 0.125)
		(layer "F.Cu")
		(net 549)
	)
	(segment
		(start 70.6 102.8)
		(end 69.9 102.8)
		(width 0.15)
		(layer "F.Cu")
		(net 549)
	)
	(via
		(at 70.6 102.8)
		(size 0.45)
		(drill 0.1)
		(layers "F.Cu" "B.Cu")
		(net 549)
	)
	(segment
		(start 70.35 102.8)
		(end 70.05 102.5)
		(width 0.15)
		(layer "B.Cu")
		(net 549)
	)
	(segment
		(start 70.05 102.5)
		(end 69.65 102.5)
		(width 0.15)
		(layer "B.Cu")
		(net 549)
	)
	(segment
		(start 70.6 102.8)
		(end 70.35 102.8)
		(width 0.15)
		(layer "B.Cu")
		(net 549)
	)
	(segment
		(start 36.715 119.785)
		(end 35.049998 121.450002)
		(width 0.15)
		(layer "B.Cu")
		(net 551)
	)
	(segment
		(start 41.2 119.785)
		(end 36.715 119.785)
		(width 0.15)
		(layer "B.Cu")
		(net 551)
	)
	(segment
		(start 43.06 119.785)
		(end 42.2 119.785)
		(width 0.15)
		(layer "B.Cu")
		(net 552)
	)
	(segment
		(start 45.790002 121.576396)
		(end 44.851396 121.576396)
		(width 0.15)
		(layer "B.Cu")
		(net 552)
	)
	(segment
		(start 44.851396 121.576396)
		(end 43.06 119.785)
		(width 0.15)
		(layer "B.Cu")
		(net 552)
	)
	(segment
		(start 70.6 103.5)
		(end 69.85 103.5)
		(width 0.125)
		(layer "F.Cu")
		(net 553)
	)
	(segment
		(start 69.4 105.85)
		(end 68.5 106.75)
		(width 0.125)
		(layer "F.Cu")
		(net 553)
	)
	(segment
		(start 69.85 103.5)
		(end 69.4 103.95)
		(width 0.125)
		(layer "F.Cu")
		(net 553)
	)
	(segment
		(start 65.85 112.68)
		(end 65.785 112.615)
		(width 0.125)
		(layer "F.Cu")
		(net 553)
	)
	(segment
		(start 65.785 112.615)
		(end 65.85 112.55)
		(width 0.125)
		(layer "F.Cu")
		(net 553)
	)
	(segment
		(start 66.65 107)
		(end 66.65 109.7)
		(width 0.125)
		(layer "F.Cu")
		(net 553)
	)
	(segment
		(start 65.85 115.5)
		(end 65.535 115.815)
		(width 0.125)
		(layer "F.Cu")
		(net 553)
	)
	(segment
		(start 65.85 110.5)
		(end 65.85 112.55)
		(width 0.125)
		(layer "F.Cu")
		(net 553)
	)
	(segment
		(start 65.85 112.75)
		(end 65.85 112.68)
		(width 0.125)
		(layer "F.Cu")
		(net 553)
	)
	(segment
		(start 65.85 112.55)
		(end 65.85 112.75)
		(width 0.125)
		(layer "F.Cu")
		(net 553)
	)
	(segment
		(start 66.9 106.75)
		(end 66.65 107)
		(width 0.125)
		(layer "F.Cu")
		(net 553)
	)
	(segment
		(start 66.65 109.7)
		(end 65.85 110.5)
		(width 0.125)
		(layer "F.Cu")
		(net 553)
	)
	(segment
		(start 65.05 112.615)
		(end 65.785 112.615)
		(width 0.125)
		(layer "F.Cu")
		(net 553)
	)
	(segment
		(start 69.4 103.95)
		(end 69.4 105.85)
		(width 0.125)
		(layer "F.Cu")
		(net 553)
	)
	(segment
		(start 65.85 112.75)
		(end 65.85 115.5)
		(width 0.125)
		(layer "F.Cu")
		(net 553)
	)
	(segment
		(start 68.5 106.75)
		(end 66.9 106.75)
		(width 0.125)
		(layer "F.Cu")
		(net 553)
	)
	(via
		(at 70.6 103.5)
		(size 0.45)
		(drill 0.1)
		(layers "F.Cu" "B.Cu")
		(net 553)
	)
	(segment
		(start 70 102.9)
		(end 69.65 102.9)
		(width 0.15)
		(layer "B.Cu")
		(net 553)
	)
	(segment
		(start 70.6 103.5)
		(end 70 102.9)
		(width 0.15)
		(layer "B.Cu")
		(net 553)
	)
	(segment
		(start 98.645 105.5)
		(end 98.645 104.857895)
		(width 0.15)
		(layer "F.Cu")
		(net 554)
	)
	(segment
		(start 97.846396 104.059291)
		(end 97.846396 104.037868)
		(width 0.15)
		(layer "F.Cu")
		(net 554)
	)
	(segment
		(start 98.645 104.857895)
		(end 97.846396 104.059291)
		(width 0.15)
		(layer "F.Cu")
		(net 554)
	)
	(via
		(at 98.645 105.5)
		(size 0.45)
		(drill 0.1)
		(layers "F.Cu" "B.Cu")
		(net 554)
	)
	(segment
		(start 104.4 125.3)
		(end 106.7 123)
		(width 0.15)
		(layer "B.Cu")
		(net 554)
	)
	(segment
		(start 126.7 123)
		(end 127.7 122)
		(width 0.15)
		(layer "B.Cu")
		(net 554)
	)
	(segment
		(start 146.9 101.5)
		(end 143.15 101.5)
		(width 0.15)
		(layer "B.Cu")
		(net 554)
	)
	(segment
		(start 143.64 119.36)
		(end 147.15 119.36)
		(width 0.15)
		(layer "B.Cu")
		(net 554)
	)
	(segment
		(start 97.3 124.3)
		(end 98.3 125.3)
		(width 0.15)
		(layer "B.Cu")
		(net 554)
	)
	(segment
		(start 127.7 122)
		(end 136.87 122)
		(width 0.15)
		(layer "B.Cu")
		(net 554)
	)
	(segment
		(start 147.15 119.36)
		(end 147.92 118.59)
		(width 0.15)
		(layer "B.Cu")
		(net 554)
	)
	(segment
		(start 147.92 102.52)
		(end 146.9 101.5)
		(width 0.15)
		(layer "B.Cu")
		(net 554)
	)
	(segment
		(start 98.3 125.3)
		(end 104.4 125.3)
		(width 0.15)
		(layer "B.Cu")
		(net 554)
	)
	(segment
		(start 141.6 121.4)
		(end 143.64 119.36)
		(width 0.15)
		(layer "B.Cu")
		(net 554)
	)
	(segment
		(start 106.7 123)
		(end 126.7 123)
		(width 0.15)
		(layer "B.Cu")
		(net 554)
	)
	(segment
		(start 97.687333 104.962667)
		(end 97.3 105.35)
		(width 0.15)
		(layer "B.Cu")
		(net 554)
	)
	(segment
		(start 98.114749 104.962667)
		(end 97.687333 104.962667)
		(width 0.15)
		(layer "B.Cu")
		(net 554)
	)
	(segment
		(start 147.92 118.59)
		(end 147.92 102.52)
		(width 0.15)
		(layer "B.Cu")
		(net 554)
	)
	(segment
		(start 98.645 105.492918)
		(end 98.114749 104.962667)
		(width 0.15)
		(layer "B.Cu")
		(net 554)
	)
	(segment
		(start 98.645 105.5)
		(end 98.645 105.492918)
		(width 0.15)
		(layer "B.Cu")
		(net 554)
	)
	(segment
		(start 137.47 121.4)
		(end 141.6 121.4)
		(width 0.15)
		(layer "B.Cu")
		(net 554)
	)
	(segment
		(start 97.3 105.35)
		(end 97.3 124.3)
		(width 0.15)
		(layer "B.Cu")
		(net 554)
	)
	(segment
		(start 136.87 122)
		(end 137.47 121.4)
		(width 0.15)
		(layer "B.Cu")
		(net 554)
	)
	(segment
		(start 90.8 114.9)
		(end 90.8 113.9)
		(width 0.155)
		(layer "F.Cu")
		(net 555)
	)
	(segment
		(start 88.4 105.15)
		(end 88.4 104.5)
		(width 0.155)
		(layer "F.Cu")
		(net 555)
	)
	(segment
		(start 90.95 115.75)
		(end 90.895 115.805)
		(width 0.15)
		(layer "F.Cu")
		(net 555)
	)
	(segment
		(start 87.69 99.19)
		(end 87.69 101.09)
		(width 0.15)
		(layer "F.Cu")
		(net 555)
	)
	(segment
		(start 85.875 92.925)
		(end 85.875 97.375)
		(width 0.15)
		(layer "F.Cu")
		(net 555)
	)
	(segment
		(start 89.4 106.15)
		(end 88.4 105.15)
		(width 0.155)
		(layer "F.Cu")
		(net 555)
	)
	(segment
		(start 89.4 112.5)
		(end 89.4 106.15)
		(width 0.155)
		(layer "F.Cu")
		(net 555)
	)
	(segment
		(start 90.8 113.9)
		(end 89.4 112.5)
		(width 0.155)
		(layer "F.Cu")
		(net 555)
	)
	(segment
		(start 89.95 90)
		(end 89.6 90.35)
		(width 0.15)
		(layer "F.Cu")
		(net 555)
	)
	(segment
		(start 88.45 90.35)
		(end 85.875 92.925)
		(width 0.15)
		(layer "F.Cu")
		(net 555)
	)
	(segment
		(start 87.69 101.09)
		(end 88.4 101.8)
		(width 0.15)
		(layer "F.Cu")
		(net 555)
	)
	(segment
		(start 88.4 101.8)
		(end 88.4 104.5)
		(width 0.15)
		(layer "F.Cu")
		(net 555)
	)
	(segment
		(start 90.895 115.805)
		(end 90.895 116.25)
		(width 0.15)
		(layer "F.Cu")
		(net 555)
	)
	(segment
		(start 90.95 115.05)
		(end 90.95 115.75)
		(width 0.15)
		(layer "F.Cu")
		(net 555)
	)
	(segment
		(start 89.95 89.185)
		(end 89.95 90)
		(width 0.15)
		(layer "F.Cu")
		(net 555)
	)
	(segment
		(start 90.95 115.05)
		(end 90.8 114.9)
		(width 0.155)
		(layer "F.Cu")
		(net 555)
	)
	(segment
		(start 85.875 97.375)
		(end 87.69 99.19)
		(width 0.15)
		(layer "F.Cu")
		(net 555)
	)
	(segment
		(start 89.6 90.35)
		(end 88.45 90.35)
		(width 0.15)
		(layer "F.Cu")
		(net 555)
	)
	(via
		(at 90.95 115.05)
		(size 0.45)
		(drill 0.1)
		(layers "F.Cu" "B.Cu")
		(net 555)
	)
	(segment
		(start 90.95 114.605)
		(end 90.745 114.4)
		(width 0.15)
		(layer "B.Cu")
		(net 555)
	)
	(segment
		(start 90.95 115.05)
		(end 91.3 115.4)
		(width 0.155)
		(layer "B.Cu")
		(net 555)
	)
	(segment
		(start 90.95 115.05)
		(end 90.95 114.605)
		(width 0.15)
		(layer "B.Cu")
		(net 555)
	)
	(segment
		(start 91.3 115.4)
		(end 91.3 115.615)
		(width 0.155)
		(layer "B.Cu")
		(net 555)
	)
	(segment
		(start 96.965 90.2)
		(end 96.615 89.85)
		(width 0.125)
		(layer "B.Cu")
		(net 556)
	)
	(segment
		(start 94.541778 90.325)
		(end 93.1325 90.325)
		(width 0.125)
		(layer "B.Cu")
		(net 556)
	)
	(segment
		(start 96.615 89.85)
		(end 95.016778 89.85)
		(width 0.125)
		(layer "B.Cu")
		(net 556)
	)
	(segment
		(start 93.1325 90.325)
		(end 93.0075 90.45)
		(width 0.125)
		(layer "B.Cu")
		(net 556)
	)
	(segment
		(start 95.016778 89.85)
		(end 94.541778 90.325)
		(width 0.125)
		(layer "B.Cu")
		(net 556)
	)
	(segment
		(start 98.031854 105.480813)
		(end 98.031854 104.781854)
		(width 0.15)
		(layer "F.Cu")
		(net 559)
	)
	(segment
		(start 97.570711 104.320711)
		(end 97.563553 104.320711)
		(width 0.15)
		(layer "F.Cu")
		(net 559)
	)
	(segment
		(start 98.031854 104.781854)
		(end 97.570711 104.320711)
		(width 0.15)
		(layer "F.Cu")
		(net 559)
	)
	(via
		(at 98.031854 105.480813)
		(size 0.45)
		(drill 0.1)
		(layers "F.Cu" "B.Cu")
		(net 559)
	)
	(segment
		(start 141.38 121.12)
		(end 143.49 119.01)
		(width 0.15)
		(layer "B.Cu")
		(net 559)
	)
	(segment
		(start 126.6 122.7)
		(end 127.6 121.7)
		(width 0.15)
		(layer "B.Cu")
		(net 559)
	)
	(segment
		(start 98.031854 105.480813)
		(end 97.919187 105.480813)
		(width 0.15)
		(layer "B.Cu")
		(net 559)
	)
	(segment
		(start 146.7 102)
		(end 143.15 102)
		(width 0.15)
		(layer "B.Cu")
		(net 559)
	)
	(segment
		(start 97.6 105.8)
		(end 97.6 124.2)
		(width 0.15)
		(layer "B.Cu")
		(net 559)
	)
	(segment
		(start 146.98 119.01)
		(end 147.57 118.42)
		(width 0.15)
		(layer "B.Cu")
		(net 559)
	)
	(segment
		(start 98.4 125)
		(end 104.3 125)
		(width 0.15)
		(layer "B.Cu")
		(net 559)
	)
	(segment
		(start 127.6 121.7)
		(end 136.78 121.7)
		(width 0.15)
		(layer "B.Cu")
		(net 559)
	)
	(segment
		(start 106.6 122.7)
		(end 126.6 122.7)
		(width 0.15)
		(layer "B.Cu")
		(net 559)
	)
	(segment
		(start 147.57 118.42)
		(end 147.57 102.87)
		(width 0.15)
		(layer "B.Cu")
		(net 559)
	)
	(segment
		(start 97.919187 105.480813)
		(end 97.6 105.8)
		(width 0.15)
		(layer "B.Cu")
		(net 559)
	)
	(segment
		(start 97.6 124.2)
		(end 98.4 125)
		(width 0.15)
		(layer "B.Cu")
		(net 559)
	)
	(segment
		(start 143.49 119.01)
		(end 146.98 119.01)
		(width 0.15)
		(layer "B.Cu")
		(net 559)
	)
	(segment
		(start 147.57 102.87)
		(end 146.7 102)
		(width 0.15)
		(layer "B.Cu")
		(net 559)
	)
	(segment
		(start 104.3 125)
		(end 106.6 122.7)
		(width 0.15)
		(layer "B.Cu")
		(net 559)
	)
	(segment
		(start 137.36 121.12)
		(end 141.38 121.12)
		(width 0.15)
		(layer "B.Cu")
		(net 559)
	)
	(segment
		(start 136.78 121.7)
		(end 137.36 121.12)
		(width 0.15)
		(layer "B.Cu")
		(net 559)
	)
	(segment
		(start 97.95 106)
		(end 97.568816 105.618816)
		(width 0.15)
		(layer "F.Cu")
		(net 560)
	)
	(segment
		(start 97.568816 105.618816)
		(end 97.568816 104.891658)
		(width 0.15)
		(layer "F.Cu")
		(net 560)
	)
	(segment
		(start 97.568816 104.891658)
		(end 97.280711 104.603553)
		(width 0.15)
		(layer "F.Cu")
		(net 560)
	)
	(segment
		(start 98.308191 106)
		(end 97.95 106)
		(width 0.15)
		(layer "F.Cu")
		(net 560)
	)
	(via
		(at 98.308191 106)
		(size 0.45)
		(drill 0.1)
		(layers "F.Cu" "B.Cu")
		(net 560)
	)
	(segment
		(start 147.17 103.17)
		(end 146.5 102.5)
		(width 0.15)
		(layer "B.Cu")
		(net 560)
	)
	(segment
		(start 143.36 118.64)
		(end 146.74 118.64)
		(width 0.15)
		(layer "B.Cu")
		(net 560)
	)
	(segment
		(start 97.9 106.408191)
		(end 97.9 124.1)
		(width 0.15)
		(layer "B.Cu")
		(net 560)
	)
	(segment
		(start 127.5 121.4)
		(end 136.69 121.4)
		(width 0.15)
		(layer "B.Cu")
		(net 560)
	)
	(segment
		(start 146.5 102.5)
		(end 143.15 102.5)
		(width 0.15)
		(layer "B.Cu")
		(net 560)
	)
	(segment
		(start 147.17 118.21)
		(end 147.17 103.17)
		(width 0.15)
		(layer "B.Cu")
		(net 560)
	)
	(segment
		(start 106.5 122.4)
		(end 126.5 122.4)
		(width 0.15)
		(layer "B.Cu")
		(net 560)
	)
	(segment
		(start 146.74 118.64)
		(end 147.17 118.21)
		(width 0.15)
		(layer "B.Cu")
		(net 560)
	)
	(segment
		(start 141.16 120.84)
		(end 143.36 118.64)
		(width 0.15)
		(layer "B.Cu")
		(net 560)
	)
	(segment
		(start 137.25 120.84)
		(end 141.16 120.84)
		(width 0.15)
		(layer "B.Cu")
		(net 560)
	)
	(segment
		(start 98.308191 106)
		(end 97.9 106.408191)
		(width 0.15)
		(layer "B.Cu")
		(net 560)
	)
	(segment
		(start 136.69 121.4)
		(end 137.25 120.84)
		(width 0.15)
		(layer "B.Cu")
		(net 560)
	)
	(segment
		(start 126.5 122.4)
		(end 127.5 121.4)
		(width 0.15)
		(layer "B.Cu")
		(net 560)
	)
	(segment
		(start 97.9 124.1)
		(end 98.5 124.7)
		(width 0.15)
		(layer "B.Cu")
		(net 560)
	)
	(segment
		(start 98.5 124.7)
		(end 104.2 124.7)
		(width 0.15)
		(layer "B.Cu")
		(net 560)
	)
	(segment
		(start 104.2 124.7)
		(end 106.5 122.4)
		(width 0.15)
		(layer "B.Cu")
		(net 560)
	)
	(segment
		(start 110.375 90.505)
		(end 110.2 90.68)
		(width 0.15)
		(layer "B.Cu")
		(net 561)
	)
	(segment
		(start 111.615 91.52)
		(end 111.615 90.52)
		(width 0.15)
		(layer "B.Cu")
		(net 561)
	)
	(segment
		(start 111.6 90.505)
		(end 110.375 90.505)
		(width 0.15)
		(layer "B.Cu")
		(net 561)
	)
	(segment
		(start 110.2 90.68)
		(end 110.2 91.07)
		(width 0.15)
		(layer "B.Cu")
		(net 561)
	)
	(segment
		(start 105.2 115.515)
		(end 104.2 115.515)
		(width 0.15)
		(layer "F.Cu")
		(net 562)
	)
	(segment
		(start 104.225 114.7)
		(end 104.225 115.49)
		(width 0.125)
		(layer "F.Cu")
		(net 562)
	)
	(segment
		(start 104.2 115.515)
		(end 103.2 115.515)
		(width 0.15)
		(layer "F.Cu")
		(net 562)
	)
	(segment
		(start 104.225 115.49)
		(end 104.2 115.515)
		(width 0.125)
		(layer "F.Cu")
		(net 562)
	)
	(via
		(at 91.43 105.54)
		(size 0.45)
		(drill 0.1)
		(layers "F.Cu" "B.Cu")
		(net 562)
	)
	(via
		(at 104.225 114.7)
		(size 0.45)
		(drill 0.1)
		(layers "F.Cu" "B.Cu")
		(net 562)
	)
	(segment
		(start 92.075 107.975)
		(end 91.825 107.725)
		(width 0.15)
		(layer "In5.Cu")
		(net 562)
	)
	(segment
		(start 91.825 107.725)
		(end 91.825 107.723959)
		(width 0.15)
		(layer "In5.Cu")
		(net 562)
	)
	(segment
		(start 91.576041 107.475)
		(end 91.575 107.475)
		(width 0.15)
		(layer "In5.Cu")
		(net 562)
	)
	(segment
		(start 91.575 107.475)
		(end 91 106.9)
		(width 0.15)
		(layer "In5.Cu")
		(net 562)
	)
	(segment
		(start 91.41 105.54)
		(end 91.43 105.54)
		(width 0.15)
		(layer "In5.Cu")
		(net 562)
	)
	(segment
		(start 104.225 114.7)
		(end 104.225 114.175)
		(width 0.15)
		(layer "In5.Cu")
		(net 562)
	)
	(segment
		(start 91 105.95)
		(end 91.41 105.54)
		(width 0.15)
		(layer "In5.Cu")
		(net 562)
	)
	(segment
		(start 104.1 114.05)
		(end 98.5 114.05)
		(width 0.15)
		(layer "In5.Cu")
		(net 562)
	)
	(segment
		(start 104.225 114.175)
		(end 104.1 114.05)
		(width 0.15)
		(layer "In5.Cu")
		(net 562)
	)
	(segment
		(start 91 106.9)
		(end 91 105.95)
		(width 0.15)
		(layer "In5.Cu")
		(net 562)
	)
	(segment
		(start 91.825 107.723959)
		(end 91.576041 107.475)
		(width 0.15)
		(layer "In5.Cu")
		(net 562)
	)
	(segment
		(start 92.425 107.975)
		(end 92.075 107.975)
		(width 0.15)
		(layer "In5.Cu")
		(net 562)
	)
	(segment
		(start 98.5 114.05)
		(end 92.425 107.975)
		(width 0.15)
		(layer "In5.Cu")
		(net 562)
	)
	(segment
		(start 91.43 105.54)
		(end 90.46 105.54)
		(width 0.15)
		(layer "B.Cu")
		(net 562)
	)
	(segment
		(start 90.335 105.665)
		(end 90.335 105.95)
		(width 0.15)
		(layer "B.Cu")
		(net 562)
	)
	(segment
		(start 90.46 105.54)
		(end 90.335 105.665)
		(width 0.15)
		(layer "B.Cu")
		(net 562)
	)
	(segment
		(start 97.25 105.8)
		(end 97.25 105.138528)
		(width 0.15)
		(layer "F.Cu")
		(net 563)
	)
	(segment
		(start 97.25 105.138528)
		(end 96.997868 104.886396)
		(width 0.15)
		(layer "F.Cu")
		(net 563)
	)
	(segment
		(start 98.6 106.55)
		(end 98 106.55)
		(width 0.15)
		(layer "F.Cu")
		(net 563)
	)
	(segment
		(start 98 106.55)
		(end 97.25 105.8)
		(width 0.15)
		(layer "F.Cu")
		(net 563)
	)
	(via
		(at 98.6 106.55)
		(size 0.45)
		(drill 0.1)
		(layers "F.Cu" "B.Cu")
		(net 563)
	)
	(segment
		(start 140.84 120.56)
		(end 143.17 118.23)
		(width 0.15)
		(layer "B.Cu")
		(net 563)
	)
	(segment
		(start 106.4 122.1)
		(end 126.4 122.1)
		(width 0.15)
		(layer "B.Cu")
		(net 563)
	)
	(segment
		(start 98.6 106.55)
		(end 98.2 106.95)
		(width 0.15)
		(layer "B.Cu")
		(net 563)
	)
	(segment
		(start 146.78 103.38)
		(end 146.4 103)
		(width 0.15)
		(layer "B.Cu")
		(net 563)
	)
	(segment
		(start 146.4 103)
		(end 143.15 103)
		(width 0.15)
		(layer "B.Cu")
		(net 563)
	)
	(segment
		(start 146.44 118.23)
		(end 146.78 117.89)
		(width 0.15)
		(layer "B.Cu")
		(net 563)
	)
	(segment
		(start 104.1 124.4)
		(end 106.4 122.1)
		(width 0.15)
		(layer "B.Cu")
		(net 563)
	)
	(segment
		(start 136.6 121.1)
		(end 137.14 120.56)
		(width 0.15)
		(layer "B.Cu")
		(net 563)
	)
	(segment
		(start 98.6 124.4)
		(end 104.1 124.4)
		(width 0.15)
		(layer "B.Cu")
		(net 563)
	)
	(segment
		(start 126.4 122.1)
		(end 127.4 121.1)
		(width 0.15)
		(layer "B.Cu")
		(net 563)
	)
	(segment
		(start 98.2 124)
		(end 98.6 124.4)
		(width 0.15)
		(layer "B.Cu")
		(net 563)
	)
	(segment
		(start 98.2 106.95)
		(end 98.2 124)
		(width 0.15)
		(layer "B.Cu")
		(net 563)
	)
	(segment
		(start 137.14 120.56)
		(end 140.84 120.56)
		(width 0.15)
		(layer "B.Cu")
		(net 563)
	)
	(segment
		(start 127.4 121.1)
		(end 136.6 121.1)
		(width 0.15)
		(layer "B.Cu")
		(net 563)
	)
	(segment
		(start 146.78 117.89)
		(end 146.78 103.38)
		(width 0.15)
		(layer "B.Cu")
		(net 563)
	)
	(segment
		(start 143.17 118.23)
		(end 146.44 118.23)
		(width 0.15)
		(layer "B.Cu")
		(net 563)
	)
	(segment
		(start 102.2 116.485)
		(end 102.2 117)
		(width 0.5)
		(layer "F.Cu")
		(net 564)
	)
	(segment
		(start 102.354 117.154)
		(end 102.354 117.951)
		(width 0.5)
		(layer "F.Cu")
		(net 564)
	)
	(segment
		(start 102.2 117)
		(end 102.354 117.154)
		(width 0.5)
		(layer "F.Cu")
		(net 564)
	)
	(segment
		(start 48.0125 87.6375)
		(end 47.385 87.6375)
		(width 0.15)
		(layer "B.Cu")
		(net 565)
	)
	(segment
		(start 48.2125 87.4375)
		(end 48.0125 87.6375)
		(width 0.15)
		(layer "B.Cu")
		(net 565)
	)
	(segment
		(start 48.875 87.4375)
		(end 48.2125 87.4375)
		(width 0.15)
		(layer "B.Cu")
		(net 565)
	)
	(segment
		(start 48.07 88.23)
		(end 48.2125 88.0875)
		(width 0.15)
		(layer "B.Cu")
		(net 566)
	)
	(segment
		(start 47.385 88.6375)
		(end 47.8225 88.6375)
		(width 0.15)
		(layer "B.Cu")
		(net 566)
	)
	(segment
		(start 48.07 88.39)
		(end 48.07 88.23)
		(width 0.15)
		(layer "B.Cu")
		(net 566)
	)
	(segment
		(start 47.8225 88.6375)
		(end 48.07 88.39)
		(width 0.15)
		(layer "B.Cu")
		(net 566)
	)
	(segment
		(start 48.2125 88.0875)
		(end 48.875 88.0875)
		(width 0.15)
		(layer "B.Cu")
		(net 566)
	)
	(segment
		(start 48.2875 86.7875)
		(end 48.1 86.6)
		(width 0.15)
		(layer "B.Cu")
		(net 567)
	)
	(segment
		(start 48.1 86.6)
		(end 47.4225 86.6)
		(width 0.15)
		(layer "B.Cu")
		(net 567)
	)
	(segment
		(start 48.875 86.7875)
		(end 48.2875 86.7875)
		(width 0.15)
		(layer "B.Cu")
		(net 567)
	)
	(segment
		(start 51.2 90.31)
		(end 50.75 90.76)
		(width 0.15)
		(layer "B.Cu")
		(net 568)
	)
	(segment
		(start 51.2 89.7625)
		(end 51.2 90.31)
		(width 0.15)
		(layer "B.Cu")
		(net 568)
	)
	(segment
		(start 50.75 90.76)
		(end 50.75 91.35)
		(width 0.15)
		(layer "B.Cu")
		(net 568)
	)
	(segment
		(start 47.385 89.6375)
		(end 47.8225 89.6375)
		(width 0.15)
		(layer "B.Cu")
		(net 569)
	)
	(segment
		(start 47.8225 89.6375)
		(end 48.05 89.41)
		(width 0.15)
		(layer "B.Cu")
		(net 569)
	)
	(segment
		(start 48.3015 88.7385)
		(end 48.875 88.7385)
		(width 0.15)
		(layer "B.Cu")
		(net 569)
	)
	(segment
		(start 48.05 88.99)
		(end 48.3015 88.7385)
		(width 0.15)
		(layer "B.Cu")
		(net 569)
	)
	(segment
		(start 48.05 89.41)
		(end 48.05 88.99)
		(width 0.15)
		(layer "B.Cu")
		(net 569)
	)
	(segment
		(start 51.85 89.7625)
		(end 51.85 91.065)
		(width 0.15)
		(layer "B.Cu")
		(net 570)
	)
	(segment
		(start 51.2 85.1125)
		(end 51.2 84.6)
		(width 0.13)
		(layer "B.Cu")
		(net 571)
	)
	(segment
		(start 50.54 83.94)
		(end 50.54 83.92)
		(width 0.13)
		(layer "B.Cu")
		(net 571)
	)
	(segment
		(start 51.2 84.6)
		(end 50.54 83.94)
		(width 0.13)
		(layer "B.Cu")
		(net 571)
	)
	(segment
		(start 53.527 87.4375)
		(end 54.6325 87.4375)
		(width 0.13)
		(layer "B.Cu")
		(net 572)
	)
	(segment
		(start 54.6325 87.4375)
		(end 54.645 87.45)
		(width 0.13)
		(layer "B.Cu")
		(net 572)
	)
	(segment
		(start 54.3325 86.7875)
		(end 53.527 86.7875)
		(width 0.13)
		(layer "B.Cu")
		(net 573)
	)
	(segment
		(start 54.645 86.475)
		(end 54.3325 86.7875)
		(width 0.13)
		(layer "B.Cu")
		(net 573)
	)
	(segment
		(start 53.527 88.0895)
		(end 54.3095 88.0895)
		(width 0.13)
		(layer "B.Cu")
		(net 574)
	)
	(segment
		(start 54.3095 88.0895)
		(end 54.645 88.425)
		(width 0.13)
		(layer "B.Cu")
		(net 574)
	)
	(segment
		(start 108.93 97.16)
		(end 108.92 97.15)
		(width 0.15)
		(layer "F.Cu")
		(net 575)
	)
	(segment
		(start 108.93 97.48)
		(end 108.93 97.16)
		(width 0.15)
		(layer "F.Cu")
		(net 575)
	)
	(segment
		(start 108.7796 97.6304)
		(end 108.93 97.48)
		(width 0.15)
		(layer "F.Cu")
		(net 575)
	)
	(segment
		(start 108.3907 97.6304)
		(end 108.7796 97.6304)
		(width 0.15)
		(layer "F.Cu")
		(net 575)
	)
	(via
		(at 108.92 97.15)
		(size 0.45)
		(drill 0.1)
		(layers "F.Cu" "B.Cu")
		(net 575)
	)
	(via
		(at 88.61 71.52)
		(size 0.45)
		(drill 0.1)
		(layers "F.Cu" "B.Cu")
		(net 575)
	)
	(segment
		(start 96.7 86.8)
		(end 97.1 87.2)
		(width 0.125)
		(layer "In5.Cu")
		(net 575)
	)
	(segment
		(start 78.1 75.25)
		(end 78.1 77.1)
		(width 0.125)
		(layer "In5.Cu")
		(net 575)
	)
	(segment
		(start 78.55 77.55)
		(end 82.25 77.55)
		(width 0.125)
		(layer "In5.Cu")
		(net 575)
	)
	(segment
		(start 96.7 81.5)
		(end 96.7 86.8)
		(width 0.125)
		(layer "In5.Cu")
		(net 575)
	)
	(segment
		(start 87.92 72.21)
		(end 79.59 72.21)
		(width 0.125)
		(layer "In5.Cu")
		(net 575)
	)
	(segment
		(start 97.1 87.2)
		(end 97.1 94.2)
		(width 0.125)
		(layer "In5.Cu")
		(net 575)
	)
	(segment
		(start 108.665 96.895)
		(end 108.92 97.15)
		(width 0.125)
		(layer "In5.Cu")
		(net 575)
	)
	(segment
		(start 96.8 94.5)
		(end 96.8 97.85)
		(width 0.125)
		(layer "In5.Cu")
		(net 575)
	)
	(segment
		(start 98.8 99.85)
		(end 103.75 99.85)
		(width 0.125)
		(layer "In5.Cu")
		(net 575)
	)
	(segment
		(start 97.1 94.2)
		(end 96.8 94.5)
		(width 0.125)
		(layer "In5.Cu")
		(net 575)
	)
	(segment
		(start 94.6 79.4)
		(end 96.7 81.5)
		(width 0.125)
		(layer "In5.Cu")
		(net 575)
	)
	(segment
		(start 79.59 72.21)
		(end 78.45 73.35)
		(width 0.125)
		(layer "In5.Cu")
		(net 575)
	)
	(segment
		(start 82.25 77.55)
		(end 82.83 78.13)
		(width 0.125)
		(layer "In5.Cu")
		(net 575)
	)
	(segment
		(start 82.99 79.4)
		(end 94.6 79.4)
		(width 0.125)
		(layer "In5.Cu")
		(net 575)
	)
	(segment
		(start 78.45 73.35)
		(end 78.45 74.9)
		(width 0.125)
		(layer "In5.Cu")
		(net 575)
	)
	(segment
		(start 78.45 74.9)
		(end 78.1 75.25)
		(width 0.125)
		(layer "In5.Cu")
		(net 575)
	)
	(segment
		(start 96.8 97.85)
		(end 98.8 99.85)
		(width 0.125)
		(layer "In5.Cu")
		(net 575)
	)
	(segment
		(start 88.61 71.52)
		(end 87.92 72.21)
		(width 0.125)
		(layer "In5.Cu")
		(net 575)
	)
	(segment
		(start 106.2 97.1)
		(end 106.405 96.895)
		(width 0.125)
		(layer "In5.Cu")
		(net 575)
	)
	(segment
		(start 82.83 78.13)
		(end 82.83 79.24)
		(width 0.125)
		(layer "In5.Cu")
		(net 575)
	)
	(segment
		(start 103.75 99.85)
		(end 106.2 97.4)
		(width 0.125)
		(layer "In5.Cu")
		(net 575)
	)
	(segment
		(start 82.83 79.24)
		(end 82.99 79.4)
		(width 0.125)
		(layer "In5.Cu")
		(net 575)
	)
	(segment
		(start 78.1 77.1)
		(end 78.55 77.55)
		(width 0.125)
		(layer "In5.Cu")
		(net 575)
	)
	(segment
		(start 106.2 97.4)
		(end 106.2 97.1)
		(width 0.125)
		(layer "In5.Cu")
		(net 575)
	)
	(segment
		(start 106.405 96.895)
		(end 108.665 96.895)
		(width 0.125)
		(layer "In5.Cu")
		(net 575)
	)
	(segment
		(start 90.75 71.75)
		(end 88.84 71.75)
		(width 0.15)
		(layer "B.Cu")
		(net 575)
	)
	(segment
		(start 88.84 71.75)
		(end 88.61 71.52)
		(width 0.15)
		(layer "B.Cu")
		(net 575)
	)
	(segment
		(start 95.505 73.55)
		(end 95.505 72.505)
		(width 0.15)
		(layer "B.Cu")
		(net 575)
	)
	(segment
		(start 91.125 72.125)
		(end 90.75 71.75)
		(width 0.15)
		(layer "B.Cu")
		(net 575)
	)
	(segment
		(start 95.125 72.125)
		(end 91.125 72.125)
		(width 0.15)
		(layer "B.Cu")
		(net 575)
	)
	(segment
		(start 95.505 72.505)
		(end 95.125 72.125)
		(width 0.15)
		(layer "B.Cu")
		(net 575)
	)
	(segment
		(start 87.05 113.715)
		(end 86.065 113.715)
		(width 0.15)
		(layer "F.Cu")
		(net 576)
	)
	(segment
		(start 109.117164 97.893878)
		(end 108.974242 98.0368)
		(width 0.15)
		(layer "F.Cu")
		(net 577)
	)
	(segment
		(start 108.974242 98.0368)
		(end 108.3907 98.0368)
		(width 0.15)
		(layer "F.Cu")
		(net 577)
	)
	(via
		(at 109.117164 97.893878)
		(size 0.45)
		(drill 0.1)
		(layers "F.Cu" "B.Cu")
		(net 577)
	)
	(via
		(at 84.59 69.87)
		(size 0.45)
		(drill 0.1)
		(layers "F.Cu" "B.Cu")
		(net 577)
	)
	(segment
		(start 108.675 98.425)
		(end 107.25 99.85)
		(width 0.125)
		(layer "In5.Cu")
		(net 577)
	)
	(segment
		(start 84.59 70.01)
		(end 84.59 69.87)
		(width 0.125)
		(layer "In5.Cu")
		(net 577)
	)
	(segment
		(start 103.85 100.15)
		(end 98.7 100.15)
		(width 0.125)
		(layer "In5.Cu")
		(net 577)
	)
	(segment
		(start 98.7 100.15)
		(end 96.5 97.95)
		(width 0.125)
		(layer "In5.Cu")
		(net 577)
	)
	(segment
		(start 96.4 81.6)
		(end 94.5 79.7)
		(width 0.125)
		(layer "In5.Cu")
		(net 577)
	)
	(segment
		(start 79.4 71.88)
		(end 83.43 71.88)
		(width 0.125)
		(layer "In5.Cu")
		(net 577)
	)
	(segment
		(start 77.8 77.2)
		(end 77.8 75.1)
		(width 0.125)
		(layer "In5.Cu")
		(net 577)
	)
	(segment
		(start 84.05 71.26)
		(end 84.05 70.55)
		(width 0.125)
		(layer "In5.Cu")
		(net 577)
	)
	(segment
		(start 96.5 97.95)
		(end 96.5 94.4)
		(width 0.125)
		(layer "In5.Cu")
		(net 577)
	)
	(segment
		(start 78.51 77.91)
		(end 77.8 77.2)
		(width 0.125)
		(layer "In5.Cu")
		(net 577)
	)
	(segment
		(start 96.8 94.1)
		(end 96.8 87.3)
		(width 0.125)
		(layer "In5.Cu")
		(net 577)
	)
	(segment
		(start 82.79 79.7)
		(end 82.42 79.33)
		(width 0.125)
		(layer "In5.Cu")
		(net 577)
	)
	(segment
		(start 78.09 73.19)
		(end 79.4 71.88)
		(width 0.125)
		(layer "In5.Cu")
		(net 577)
	)
	(segment
		(start 109.117164 97.893878)
		(end 108.956122 97.893878)
		(width 0.125)
		(layer "In5.Cu")
		(net 577)
	)
	(segment
		(start 107.25 99.85)
		(end 104.15 99.85)
		(width 0.125)
		(layer "In5.Cu")
		(net 577)
	)
	(segment
		(start 96.5 94.4)
		(end 96.8 94.1)
		(width 0.125)
		(layer "In5.Cu")
		(net 577)
	)
	(segment
		(start 104.15 99.85)
		(end 103.85 100.15)
		(width 0.125)
		(layer "In5.Cu")
		(net 577)
	)
	(segment
		(start 82.42 79.33)
		(end 82.42 78.27)
		(width 0.125)
		(layer "In5.Cu")
		(net 577)
	)
	(segment
		(start 96.4 86.9)
		(end 96.4 81.6)
		(width 0.125)
		(layer "In5.Cu")
		(net 577)
	)
	(segment
		(start 77.8 75.1)
		(end 78.09 74.81)
		(width 0.125)
		(layer "In5.Cu")
		(net 577)
	)
	(segment
		(start 96.8 87.3)
		(end 96.4 86.9)
		(width 0.125)
		(layer "In5.Cu")
		(net 577)
	)
	(segment
		(start 84.05 70.55)
		(end 84.59 70.01)
		(width 0.125)
		(layer "In5.Cu")
		(net 577)
	)
	(segment
		(start 78.09 74.81)
		(end 78.09 73.19)
		(width 0.125)
		(layer "In5.Cu")
		(net 577)
	)
	(segment
		(start 83.43 71.88)
		(end 84.05 71.26)
		(width 0.125)
		(layer "In5.Cu")
		(net 577)
	)
	(segment
		(start 94.5 79.7)
		(end 82.79 79.7)
		(width 0.125)
		(layer "In5.Cu")
		(net 577)
	)
	(segment
		(start 82.06 77.91)
		(end 78.51 77.91)
		(width 0.125)
		(layer "In5.Cu")
		(net 577)
	)
	(segment
		(start 108.956122 97.893878)
		(end 108.675 98.175)
		(width 0.125)
		(layer "In5.Cu")
		(net 577)
	)
	(segment
		(start 108.675 98.175)
		(end 108.675 98.425)
		(width 0.125)
		(layer "In5.Cu")
		(net 577)
	)
	(segment
		(start 82.42 78.27)
		(end 82.06 77.91)
		(width 0.125)
		(layer "In5.Cu")
		(net 577)
	)
	(segment
		(start 95.325 71.725)
		(end 91.225 71.725)
		(width 0.15)
		(layer "B.Cu")
		(net 577)
	)
	(segment
		(start 96.005 72.405)
		(end 95.325 71.725)
		(width 0.15)
		(layer "B.Cu")
		(net 577)
	)
	(segment
		(start 91.225 71.725)
		(end 90.95 71.45)
		(width 0.15)
		(layer "B.Cu")
		(net 577)
	)
	(segment
		(start 84.88 69.58)
		(end 84.59 69.87)
		(width 0.15)
		(layer "B.Cu")
		(net 577)
	)
	(segment
		(start 87.38 69.58)
		(end 84.88 69.58)
		(width 0.15)
		(layer "B.Cu")
		(net 577)
	)
	(segment
		(start 96.005 73.55)
		(end 96.005 72.405)
		(width 0.15)
		(layer "B.Cu")
		(net 577)
	)
	(segment
		(start 90.95 71.45)
		(end 89.25 71.45)
		(width 0.15)
		(layer "B.Cu")
		(net 577)
	)
	(segment
		(start 89.25 71.45)
		(end 87.38 69.58)
		(width 0.15)
		(layer "B.Cu")
		(net 577)
	)
	(segment
		(start 146.65 95.95)
		(end 146.85 95.75)
		(width 0.15)
		(layer "F.Cu")
		(net 578)
	)
	(segment
		(start 146 95.95)
		(end 146.65 95.95)
		(width 0.15)
		(layer "F.Cu")
		(net 578)
	)
	(segment
		(start 146.85 95.75)
		(end 147.35 95.75)
		(width 0.15)
		(layer "F.Cu")
		(net 578)
	)
	(segment
		(start 141.5 96.75)
		(end 140.44 96.75)
		(width 0.15)
		(layer "F.Cu")
		(net 579)
	)
	(segment
		(start 139.22 97.97)
		(end 137.85 97.97)
		(width 0.15)
		(layer "F.Cu")
		(net 579)
	)
	(segment
		(start 139.22 97.97)
		(end 140.44 96.75)
		(width 0.15)
		(layer "F.Cu")
		(net 579)
	)
	(segment
		(start 147.35 96.3)
		(end 147.35 96.65)
		(width 0.15)
		(layer "F.Cu")
		(net 580)
	)
	(segment
		(start 147.2 96.8)
		(end 146.05 96.8)
		(width 0.15)
		(layer "F.Cu")
		(net 580)
	)
	(segment
		(start 147.35 96.65)
		(end 147.2 96.8)
		(width 0.15)
		(layer "F.Cu")
		(net 580)
	)
	(segment
		(start 146 98.35)
		(end 146.65 98.35)
		(width 0.15)
		(layer "F.Cu")
		(net 581)
	)
	(segment
		(start 146.9 98.6)
		(end 147.4 98.6)
		(width 0.15)
		(layer "F.Cu")
		(net 581)
	)
	(segment
		(start 146.65 98.35)
		(end 146.9 98.6)
		(width 0.15)
		(layer "F.Cu")
		(net 581)
	)
	(segment
		(start 146 99.95)
		(end 146.65 99.95)
		(width 0.15)
		(layer "F.Cu")
		(net 582)
	)
	(segment
		(start 146.65 99.95)
		(end 146.95 99.65)
		(width 0.15)
		(layer "F.Cu")
		(net 582)
	)
	(segment
		(start 146.95 99.65)
		(end 147.4 99.65)
		(width 0.15)
		(layer "F.Cu")
		(net 582)
	)
	(segment
		(start 146 99.15)
		(end 147.4 99.15)
		(width 0.15)
		(layer "F.Cu")
		(net 583)
	)
	(segment
		(start 141.5 98.35)
		(end 139.45 98.35)
		(width 0.15)
		(layer "F.Cu")
		(net 584)
	)
	(segment
		(start 139.3 98.5)
		(end 137.85 98.5)
		(width 0.15)
		(layer "F.Cu")
		(net 584)
	)
	(segment
		(start 139.45 98.35)
		(end 139.3 98.5)
		(width 0.15)
		(layer "F.Cu")
		(net 584)
	)
	(segment
		(start 140.85 100.75)
		(end 141.5 100.75)
		(width 0.15)
		(layer "F.Cu")
		(net 585)
	)
	(segment
		(start 139.75 101.5)
		(end 140.1 101.5)
		(width 0.15)
		(layer "F.Cu")
		(net 585)
	)
	(segment
		(start 140.1 101.5)
		(end 140.85 100.75)
		(width 0.15)
		(layer "F.Cu")
		(net 585)
	)
	(segment
		(start 146 100.75)
		(end 147.25 100.75)
		(width 0.15)
		(layer "F.Cu")
		(net 586)
	)
	(segment
		(start 147.4 100.6)
		(end 147.4 100.2)
		(width 0.15)
		(layer "F.Cu")
		(net 586)
	)
	(segment
		(start 147.25 100.75)
		(end 147.4 100.6)
		(width 0.15)
		(layer "F.Cu")
		(net 586)
	)
	(segment
		(start 140.65 101.55)
		(end 141.5 101.55)
		(width 0.15)
		(layer "F.Cu")
		(net 587)
	)
	(segment
		(start 140.15 102.05)
		(end 140.65 101.55)
		(width 0.15)
		(layer "F.Cu")
		(net 587)
	)
	(segment
		(start 139.75 102.05)
		(end 140.15 102.05)
		(width 0.15)
		(layer "F.Cu")
		(net 587)
	)
	(segment
		(start 146.9 101.725)
		(end 146.725 101.55)
		(width 0.15)
		(layer "F.Cu")
		(net 588)
	)
	(segment
		(start 146.918 102.318)
		(end 146.9 102.3)
		(width 0.15)
		(layer "F.Cu")
		(net 588)
	)
	(segment
		(start 147.4 102.318)
		(end 146.918 102.318)
		(width 0.15)
		(layer "F.Cu")
		(net 588)
	)
	(segment
		(start 146.725 101.55)
		(end 146 101.55)
		(width 0.15)
		(layer "F.Cu")
		(net 588)
	)
	(segment
		(start 146.9 102.3)
		(end 146.9 101.725)
		(width 0.15)
		(layer "F.Cu")
		(net 588)
	)
	(segment
		(start 141.5 103.15)
		(end 140.85 103.15)
		(width 0.15)
		(layer "F.Cu")
		(net 589)
	)
	(segment
		(start 140.25 102.55)
		(end 139.75 102.55)
		(width 0.15)
		(layer "F.Cu")
		(net 589)
	)
	(segment
		(start 140.85 103.15)
		(end 140.25 102.55)
		(width 0.15)
		(layer "F.Cu")
		(net 589)
	)
	(segment
		(start 146.65 103.15)
		(end 146.952 102.848)
		(width 0.15)
		(layer "F.Cu")
		(net 590)
	)
	(segment
		(start 146.952 102.848)
		(end 147.4 102.848)
		(width 0.15)
		(layer "F.Cu")
		(net 590)
	)
	(segment
		(start 146 103.15)
		(end 146.65 103.15)
		(width 0.15)
		(layer "F.Cu")
		(net 590)
	)
	(segment
		(start 139.75 103.1)
		(end 140.2 103.1)
		(width 0.15)
		(layer "F.Cu")
		(net 591)
	)
	(segment
		(start 140.6 103.95)
		(end 141.5 103.95)
		(width 0.15)
		(layer "F.Cu")
		(net 591)
	)
	(segment
		(start 140.4 103.75)
		(end 140.6 103.95)
		(width 0.15)
		(layer "F.Cu")
		(net 591)
	)
	(segment
		(start 140.2 103.1)
		(end 140.4 103.3)
		(width 0.15)
		(layer "F.Cu")
		(net 591)
	)
	(segment
		(start 140.4 103.3)
		(end 140.4 103.75)
		(width 0.15)
		(layer "F.Cu")
		(net 591)
	)
	(segment
		(start 147.16 103.39)
		(end 147.4 103.39)
		(width 0.15)
		(layer "F.Cu")
		(net 592)
	)
	(segment
		(start 146 103.95)
		(end 146.6 103.95)
		(width 0.15)
		(layer "F.Cu")
		(net 592)
	)
	(segment
		(start 146.6 103.95)
		(end 147.16 103.39)
		(width 0.15)
		(layer "F.Cu")
		(net 592)
	)
	(segment
		(start 140.15 105.35)
		(end 140.75 104.75)
		(width 0.15)
		(layer "F.Cu")
		(net 593)
	)
	(segment
		(start 139.7 105.35)
		(end 140.15 105.35)
		(width 0.15)
		(layer "F.Cu")
		(net 593)
	)
	(segment
		(start 140.75 104.75)
		(end 141.5 104.75)
		(width 0.15)
		(layer "F.Cu")
		(net 593)
	)
	(segment
		(start 147.4 103.92)
		(end 147.18 103.92)
		(width 0.15)
		(layer "F.Cu")
		(net 594)
	)
	(segment
		(start 146.9 104.6)
		(end 146.75 104.75)
		(width 0.15)
		(layer "F.Cu")
		(net 594)
	)
	(segment
		(start 146.9 104.2)
		(end 146.9 104.6)
		(width 0.15)
		(layer "F.Cu")
		(net 594)
	)
	(segment
		(start 146.75 104.75)
		(end 146 104.75)
		(width 0.15)
		(layer "F.Cu")
		(net 594)
	)
	(segment
		(start 147.18 103.92)
		(end 146.9 104.2)
		(width 0.15)
		(layer "F.Cu")
		(net 594)
	)
	(segment
		(start 140.45 105.85)
		(end 139.7 105.85)
		(width 0.15)
		(layer "F.Cu")
		(net 595)
	)
	(segment
		(start 141.5 105.55)
		(end 140.75 105.55)
		(width 0.15)
		(layer "F.Cu")
		(net 595)
	)
	(segment
		(start 140.75 105.55)
		(end 140.45 105.85)
		(width 0.15)
		(layer "F.Cu")
		(net 595)
	)
	(segment
		(start 140.4 107.6)
		(end 139.585 107.6)
		(width 0.15)
		(layer "F.Cu")
		(net 596)
	)
	(segment
		(start 141.5 107.95)
		(end 140.75 107.95)
		(width 0.15)
		(layer "F.Cu")
		(net 596)
	)
	(segment
		(start 140.75 107.95)
		(end 140.4 107.6)
		(width 0.15)
		(layer "F.Cu")
		(net 596)
	)
	(segment
		(start 147 108.4)
		(end 147.1 108.5)
		(width 0.15)
		(layer "F.Cu")
		(net 597)
	)
	(segment
		(start 147 108.2)
		(end 147 108.4)
		(width 0.15)
		(layer "F.Cu")
		(net 597)
	)
	(segment
		(start 146.75 107.95)
		(end 147 108.2)
		(width 0.15)
		(layer "F.Cu")
		(net 597)
	)
	(segment
		(start 147.1 108.5)
		(end 147.515 108.5)
		(width 0.15)
		(layer "F.Cu")
		(net 597)
	)
	(segment
		(start 146 107.95)
		(end 146.75 107.95)
		(width 0.15)
		(layer "F.Cu")
		(net 597)
	)
	(segment
		(start 139.585 108.6)
		(end 141.35 108.6)
		(width 0.15)
		(layer "F.Cu")
		(net 598)
	)
	(segment
		(start 141.35 108.6)
		(end 141.5 108.75)
		(width 0.15)
		(layer "F.Cu")
		(net 598)
	)
	(segment
		(start 147.515 109.5)
		(end 147.1 109.5)
		(width 0.15)
		(layer "F.Cu")
		(net 599)
	)
	(segment
		(start 147.1 109.5)
		(end 146.9 109.3)
		(width 0.15)
		(layer "F.Cu")
		(net 599)
	)
	(segment
		(start 146.9 108.9)
		(end 146.75 108.75)
		(width 0.15)
		(layer "F.Cu")
		(net 599)
	)
	(segment
		(start 146.75 108.75)
		(end 146 108.75)
		(width 0.15)
		(layer "F.Cu")
		(net 599)
	)
	(segment
		(start 146.9 109.3)
		(end 146.9 108.9)
		(width 0.15)
		(layer "F.Cu")
		(net 599)
	)
	(segment
		(start 146.9 110.3)
		(end 146.9 109.8)
		(width 0.15)
		(layer "F.Cu")
		(net 600)
	)
	(segment
		(start 147.1 110.5)
		(end 146.9 110.3)
		(width 0.15)
		(layer "F.Cu")
		(net 600)
	)
	(segment
		(start 146.65 109.55)
		(end 146 109.55)
		(width 0.15)
		(layer "F.Cu")
		(net 600)
	)
	(segment
		(start 147.515 110.5)
		(end 147.1 110.5)
		(width 0.15)
		(layer "F.Cu")
		(net 600)
	)
	(segment
		(start 146.9 109.8)
		(end 146.65 109.55)
		(width 0.15)
		(layer "F.Cu")
		(net 600)
	)
	(segment
		(start 146.35 110.35)
		(end 147.5 111.5)
		(width 0.15)
		(layer "F.Cu")
		(net 601)
	)
	(segment
		(start 109.1032 98.4432)
		(end 108.3907 98.4432)
		(width 0.15)
		(layer "F.Cu")
		(net 602)
	)
	(segment
		(start 109.13 98.47)
		(end 109.1032 98.4432)
		(width 0.15)
		(layer "F.Cu")
		(net 602)
	)
	(via
		(at 109.13 98.47)
		(size 0.45)
		(drill 0.1)
		(layers "F.Cu" "B.Cu")
		(net 602)
	)
	(via
		(at 84.05 69.66)
		(size 0.45)
		(drill 0.1)
		(layers "F.Cu" "B.Cu")
		(net 602)
	)
	(segment
		(start 81.75 80)
		(end 94.4 80)
		(width 0.125)
		(layer "In5.Cu")
		(net 602)
	)
	(segment
		(start 81.38 79.63)
		(end 81.75 80)
		(width 0.125)
		(layer "In5.Cu")
		(net 602)
	)
	(segment
		(start 77.13 74.68)
		(end 77.5 75.05)
		(width 0.125)
		(layer "In5.Cu")
		(net 602)
	)
	(segment
		(start 107.4 100.2)
		(end 109.13 98.47)
		(width 0.125)
		(layer "In5.Cu")
		(net 602)
	)
	(segment
		(start 78.34 78.16)
		(end 80.84 78.16)
		(width 0.125)
		(layer "In5.Cu")
		(net 602)
	)
	(segment
		(start 79.64 69.66)
		(end 77.13 72.17)
		(width 0.125)
		(layer "In5.Cu")
		(net 602)
	)
	(segment
		(start 99.15 101)
		(end 103.45 101)
		(width 0.125)
		(layer "In5.Cu")
		(net 602)
	)
	(segment
		(start 96.5 94)
		(end 96.2 94.3)
		(width 0.125)
		(layer "In5.Cu")
		(net 602)
	)
	(segment
		(start 80.84 78.16)
		(end 81.38 78.7)
		(width 0.125)
		(layer "In5.Cu")
		(net 602)
	)
	(segment
		(start 96.2 94.3)
		(end 96.2 98.05)
		(width 0.125)
		(layer "In5.Cu")
		(net 602)
	)
	(segment
		(start 84.05 69.66)
		(end 79.64 69.66)
		(width 0.125)
		(layer "In5.Cu")
		(net 602)
	)
	(segment
		(start 77.13 72.17)
		(end 77.13 74.68)
		(width 0.125)
		(layer "In5.Cu")
		(net 602)
	)
	(segment
		(start 96.1 81.7)
		(end 96.1 87.077727)
		(width 0.125)
		(layer "In5.Cu")
		(net 602)
	)
	(segment
		(start 77.5 77.32)
		(end 78.34 78.16)
		(width 0.125)
		(layer "In5.Cu")
		(net 602)
	)
	(segment
		(start 77.5 75.05)
		(end 77.5 77.32)
		(width 0.125)
		(layer "In5.Cu")
		(net 602)
	)
	(segment
		(start 96.5 87.477727)
		(end 96.5 94)
		(width 0.125)
		(layer "In5.Cu")
		(net 602)
	)
	(segment
		(start 104.25 100.2)
		(end 107.4 100.2)
		(width 0.125)
		(layer "In5.Cu")
		(net 602)
	)
	(segment
		(start 96.1 87.077727)
		(end 96.5 87.477727)
		(width 0.125)
		(layer "In5.Cu")
		(net 602)
	)
	(segment
		(start 94.4 80)
		(end 96.1 81.7)
		(width 0.125)
		(layer "In5.Cu")
		(net 602)
	)
	(segment
		(start 103.45 101)
		(end 104.25 100.2)
		(width 0.125)
		(layer "In5.Cu")
		(net 602)
	)
	(segment
		(start 96.2 98.05)
		(end 99.15 101)
		(width 0.125)
		(layer "In5.Cu")
		(net 602)
	)
	(segment
		(start 81.38 78.7)
		(end 81.38 79.63)
		(width 0.125)
		(layer "In5.Cu")
		(net 602)
	)
	(segment
		(start 96.505 72.205)
		(end 95.65 71.35)
		(width 0.15)
		(layer "B.Cu")
		(net 602)
	)
	(segment
		(start 89.4 71.15)
		(end 87.49 69.24)
		(width 0.15)
		(layer "B.Cu")
		(net 602)
	)
	(segment
		(start 87.49 69.24)
		(end 84.47 69.24)
		(width 0.15)
		(layer "B.Cu")
		(net 602)
	)
	(segment
		(start 84.47 69.24)
		(end 84.05 69.66)
		(width 0.15)
		(layer "B.Cu")
		(net 602)
	)
	(segment
		(start 95.65 71.35)
		(end 91.3 71.35)
		(width 0.15)
		(layer "B.Cu")
		(net 602)
	)
	(segment
		(start 96.505 73.55)
		(end 96.505 72.205)
		(width 0.15)
		(layer "B.Cu")
		(net 602)
	)
	(segment
		(start 91.3 71.35)
		(end 91.1 71.15)
		(width 0.15)
		(layer "B.Cu")
		(net 602)
	)
	(segment
		(start 91.1 71.15)
		(end 89.4 71.15)
		(width 0.15)
		(layer "B.Cu")
		(net 602)
	)
	(segment
		(start 108.17 98.84)
		(end 108.48 98.84)
		(width 0.15)
		(layer "F.Cu")
		(net 603)
	)
	(segment
		(start 108.71 99.07)
		(end 109.15 99.07)
		(width 0.15)
		(layer "F.Cu")
		(net 603)
	)
	(segment
		(start 108.48 98.84)
		(end 108.71 99.07)
		(width 0.15)
		(layer "F.Cu")
		(net 603)
	)
	(via
		(at 91.15 69.75)
		(size 0.45)
		(drill 0.1)
		(layers "F.Cu" "B.Cu")
		(net 603)
	)
	(via
		(at 109.15 99.07)
		(size 0.45)
		(drill 0.1)
		(layers "F.Cu" "B.Cu")
		(net 603)
	)
	(segment
		(start 96.2 93.9)
		(end 96.2 87.548959)
		(width 0.15)
		(layer "In5.Cu")
		(net 603)
	)
	(segment
		(start 91.15 69.75)
		(end 90.82 69.42)
		(width 0.15)
		(layer "In5.Cu")
		(net 603)
	)
	(segment
		(start 78.225 78.425)
		(end 80.725 78.425)
		(width 0.125)
		(layer "In5.Cu")
		(net 603)
	)
	(segment
		(start 109.15 99.15)
		(end 107.8 100.5)
		(width 0.15)
		(layer "In5.Cu")
		(net 603)
	)
	(segment
		(start 96.1 98.35)
		(end 95.9 98.15)
		(width 0.15)
		(layer "In5.Cu")
		(net 603)
	)
	(segment
		(start 107.8 100.5)
		(end 104.4 100.5)
		(width 0.15)
		(layer "In5.Cu")
		(net 603)
	)
	(segment
		(start 84.52 69.23)
		(end 79.57 69.23)
		(width 0.15)
		(layer "In5.Cu")
		(net 603)
	)
	(segment
		(start 77.2 75.14)
		(end 77.08 75.02)
		(width 0.125)
		(layer "In5.Cu")
		(net 603)
	)
	(segment
		(start 96.35 99.5)
		(end 96.1 99.25)
		(width 0.15)
		(layer "In5.Cu")
		(net 603)
	)
	(segment
		(start 84.71 69.42)
		(end 84.52 69.23)
		(width 0.15)
		(layer "In5.Cu")
		(net 603)
	)
	(segment
		(start 97.2 99.5)
		(end 96.35 99.5)
		(width 0.15)
		(layer "In5.Cu")
		(net 603)
	)
	(segment
		(start 95.9 98.15)
		(end 95.9 94.2)
		(width 0.15)
		(layer "In5.Cu")
		(net 603)
	)
	(segment
		(start 95.8 87.148959)
		(end 95.8 81.8)
		(width 0.15)
		(layer "In5.Cu")
		(net 603)
	)
	(segment
		(start 81.1 78.8)
		(end 81.1 79.95)
		(width 0.125)
		(layer "In5.Cu")
		(net 603)
	)
	(segment
		(start 81.1 79.95)
		(end 81.45 80.3)
		(width 0.125)
		(layer "In5.Cu")
		(net 603)
	)
	(segment
		(start 96.2 87.548959)
		(end 95.8 87.148959)
		(width 0.15)
		(layer "In5.Cu")
		(net 603)
	)
	(segment
		(start 94.3 80.3)
		(end 82.1 80.3)
		(width 0.15)
		(layer "In5.Cu")
		(net 603)
	)
	(segment
		(start 79.57 69.23)
		(end 76.8 72)
		(width 0.15)
		(layer "In5.Cu")
		(net 603)
	)
	(segment
		(start 76.8 74.74)
		(end 77.08 75.02)
		(width 0.15)
		(layer "In5.Cu")
		(net 603)
	)
	(segment
		(start 104.4 100.5)
		(end 102.55 102.35)
		(width 0.15)
		(layer "In5.Cu")
		(net 603)
	)
	(segment
		(start 109.15 99.07)
		(end 109.15 99.15)
		(width 0.15)
		(layer "In5.Cu")
		(net 603)
	)
	(segment
		(start 90.82 69.42)
		(end 84.71 69.42)
		(width 0.15)
		(layer "In5.Cu")
		(net 603)
	)
	(segment
		(start 76.8 72)
		(end 76.8 74.74)
		(width 0.15)
		(layer "In5.Cu")
		(net 603)
	)
	(segment
		(start 102.55 102.35)
		(end 100.05 102.35)
		(width 0.15)
		(layer "In5.Cu")
		(net 603)
	)
	(segment
		(start 77.2 77.4)
		(end 78.225 78.425)
		(width 0.125)
		(layer "In5.Cu")
		(net 603)
	)
	(segment
		(start 96.1 99.25)
		(end 96.1 98.35)
		(width 0.15)
		(layer "In5.Cu")
		(net 603)
	)
	(segment
		(start 80.725 78.425)
		(end 81.1 78.8)
		(width 0.125)
		(layer "In5.Cu")
		(net 603)
	)
	(segment
		(start 95.9 94.2)
		(end 96.2 93.9)
		(width 0.15)
		(layer "In5.Cu")
		(net 603)
	)
	(segment
		(start 95.8 81.8)
		(end 94.3 80.3)
		(width 0.15)
		(layer "In5.Cu")
		(net 603)
	)
	(segment
		(start 81.45 80.3)
		(end 82.1 80.3)
		(width 0.125)
		(layer "In5.Cu")
		(net 603)
	)
	(segment
		(start 77.2 75.14)
		(end 77.2 77.4)
		(width 0.125)
		(layer "In5.Cu")
		(net 603)
	)
	(segment
		(start 100.05 102.35)
		(end 97.2 99.5)
		(width 0.15)
		(layer "In5.Cu")
		(net 603)
	)
	(segment
		(start 95.85 71)
		(end 97.005 72.155)
		(width 0.15)
		(layer "B.Cu")
		(net 603)
	)
	(segment
		(start 91.45 71)
		(end 95.85 71)
		(width 0.15)
		(layer "B.Cu")
		(net 603)
	)
	(segment
		(start 91.15 69.75)
		(end 91.15 70.7)
		(width 0.15)
		(layer "B.Cu")
		(net 603)
	)
	(segment
		(start 91.15 70.7)
		(end 91.45 71)
		(width 0.15)
		(layer "B.Cu")
		(net 603)
	)
	(segment
		(start 97.005 72.155)
		(end 97.005 73.55)
		(width 0.15)
		(layer "B.Cu")
		(net 603)
	)
	(segment
		(start 91.8 110.5)
		(end 91.8 111.95)
		(width 0.15)
		(layer "B.Cu")
		(net 604)
	)
	(segment
		(start 90.9 110.25)
		(end 91.55 110.25)
		(width 0.15)
		(layer "B.Cu")
		(net 604)
	)
	(segment
		(start 91.55 110.25)
		(end 91.8 110.5)
		(width 0.15)
		(layer "B.Cu")
		(net 604)
	)
	(segment
		(start 92.2 110.1)
		(end 92.2 111.95)
		(width 0.15)
		(layer "B.Cu")
		(net 605)
	)
	(segment
		(start 91.85 109.75)
		(end 92.2 110.1)
		(width 0.15)
		(layer "B.Cu")
		(net 605)
	)
	(segment
		(start 90.9 109.75)
		(end 91.85 109.75)
		(width 0.15)
		(layer "B.Cu")
		(net 605)
	)
	(segment
		(start 147.26 106.41)
		(end 146.8 105.95)
		(width 0.15)
		(layer "F.Cu")
		(net 606)
	)
	(segment
		(start 147.4 106.41)
		(end 147.26 106.41)
		(width 0.15)
		(layer "F.Cu")
		(net 606)
	)
	(segment
		(start 146.65 105.55)
		(end 146 105.55)
		(width 0.15)
		(layer "F.Cu")
		(net 606)
	)
	(segment
		(start 146.8 105.95)
		(end 146.8 105.7)
		(width 0.15)
		(layer "F.Cu")
		(net 606)
	)
	(segment
		(start 146.8 105.7)
		(end 146.65 105.55)
		(width 0.15)
		(layer "F.Cu")
		(net 606)
	)
	(segment
		(start 139.7 106.4)
		(end 141.35 106.4)
		(width 0.15)
		(layer "F.Cu")
		(net 607)
	)
	(segment
		(start 141.35 106.4)
		(end 141.45 106.3)
		(width 0.15)
		(layer "F.Cu")
		(net 607)
	)
	(segment
		(start 147.19 106.94)
		(end 147.4 106.94)
		(width 0.15)
		(layer "F.Cu")
		(net 608)
	)
	(segment
		(start 146.6 106.35)
		(end 147.19 106.94)
		(width 0.15)
		(layer "F.Cu")
		(net 608)
	)
	(segment
		(start 146 106.35)
		(end 146.6 106.35)
		(width 0.15)
		(layer "F.Cu")
		(net 608)
	)
	(segment
		(start 106.9495 108.561926)
		(end 107.201931 108.309495)
		(width 0.155)
		(layer "F.Cu")
		(net 609)
	)
	(segment
		(start 106.461926 109.6495)
		(end 106.9495 109.161926)
		(width 0.155)
		(layer "F.Cu")
		(net 609)
	)
	(segment
		(start 107.201931 108.309495)
		(end 107.624443 108.309495)
		(width 0.155)
		(layer "F.Cu")
		(net 609)
	)
	(segment
		(start 107.624443 108.309495)
		(end 107.659948 108.345)
		(width 0.155)
		(layer "F.Cu")
		(net 609)
	)
	(segment
		(start 105.990438 109.6495)
		(end 106.461926 109.6495)
		(width 0.155)
		(layer "F.Cu")
		(net 609)
	)
	(segment
		(start 106.9495 109.161926)
		(end 106.9495 108.561926)
		(width 0.155)
		(layer "F.Cu")
		(net 609)
	)
	(segment
		(start 105.639938 110)
		(end 105.990438 109.6495)
		(width 0.155)
		(layer "F.Cu")
		(net 609)
	)
	(segment
		(start 106.383074 106.6945)
		(end 105.990438 106.6945)
		(width 0.155)
		(layer "F.Cu")
		(net 610)
	)
	(segment
		(start 107.689938 107.145)
		(end 107.314937 107.145)
		(width 0.155)
		(layer "F.Cu")
		(net 610)
	)
	(segment
		(start 107.264437 107.0945)
		(end 106.783074 107.0945)
		(width 0.155)
		(layer "F.Cu")
		(net 610)
	)
	(segment
		(start 107.314937 107.145)
		(end 107.264437 107.0945)
		(width 0.155)
		(layer "F.Cu")
		(net 610)
	)
	(segment
		(start 105.990438 106.6945)
		(end 105.639938 107.045)
		(width 0.155)
		(layer "F.Cu")
		(net 610)
	)
	(segment
		(start 106.783074 107.0945)
		(end 106.383074 106.6945)
		(width 0.155)
		(layer "F.Cu")
		(net 610)
	)
	(segment
		(start 106.6505 108.438074)
		(end 107.078079 108.010495)
		(width 0.155)
		(layer "F.Cu")
		(net 611)
	)
	(segment
		(start 106.6505 109.038074)
		(end 106.6505 108.438074)
		(width 0.155)
		(layer "F.Cu")
		(net 611)
	)
	(segment
		(start 106.338074 109.3505)
		(end 106.6505 109.038074)
		(width 0.155)
		(layer "F.Cu")
		(net 611)
	)
	(segment
		(start 105.639938 109)
		(end 105.990438 109.3505)
		(width 0.155)
		(layer "F.Cu")
		(net 611)
	)
	(segment
		(start 105.990438 109.3505)
		(end 106.338074 109.3505)
		(width 0.155)
		(layer "F.Cu")
		(net 611)
	)
	(segment
		(start 107.078079 108.010495)
		(end 107.624443 108.010495)
		(width 0.155)
		(layer "F.Cu")
		(net 611)
	)
	(segment
		(start 107.624443 108.010495)
		(end 107.689938 107.945)
		(width 0.155)
		(layer "F.Cu")
		(net 611)
	)
	(segment
		(start 107.314937 106.745)
		(end 107.264437 106.7955)
		(width 0.155)
		(layer "F.Cu")
		(net 612)
	)
	(segment
		(start 107.689938 106.745)
		(end 107.314937 106.745)
		(width 0.155)
		(layer "F.Cu")
		(net 612)
	)
	(segment
		(start 107.264437 106.7955)
		(end 106.906926 106.7955)
		(width 0.155)
		(layer "F.Cu")
		(net 612)
	)
	(segment
		(start 106.906926 106.7955)
		(end 106.506926 106.3955)
		(width 0.155)
		(layer "F.Cu")
		(net 612)
	)
	(segment
		(start 106.506926 106.3955)
		(end 105.990438 106.3955)
		(width 0.155)
		(layer "F.Cu")
		(net 612)
	)
	(segment
		(start 105.990438 106.3955)
		(end 105.639938 106.045)
		(width 0.155)
		(layer "F.Cu")
		(net 612)
	)
	(segment
		(start 53.8 122.15)
		(end 52.85 122.15)
		(width 0.155)
		(layer "F.Cu")
		(net 613)
	)
	(via
		(at 52.85 122.15)
		(size 0.45)
		(drill 0.1)
		(layers "F.Cu" "B.Cu")
		(net 613)
	)
	(via
		(at 53.8 122.15)
		(size 0.45)
		(drill 0.1)
		(layers "F.Cu" "B.Cu")
		(net 613)
	)
	(segment
		(start 53.85 120.65)
		(end 53.9 120.6)
		(width 0.155)
		(layer "B.Cu")
		(net 613)
	)
	(segment
		(start 53.9 118.615)
		(end 53.9 118.202499)
		(width 0.155)
		(layer "B.Cu")
		(net 613)
	)
	(segment
		(start 52.85 122.15)
		(end 52.85 121.11)
		(width 0.155)
		(layer "B.Cu")
		(net 613)
	)
	(segment
		(start 53.5495 117.851999)
		(end 53.5495 117.6355)
		(width 0.155)
		(layer "B.Cu")
		(net 613)
	)
	(segment
		(start 53.9 119.385)
		(end 53.9 118.615)
		(width 0.155)
		(layer "B.Cu")
		(net 613)
	)
	(segment
		(start 53.85 122.1)
		(end 53.85 120.65)
		(width 0.155)
		(layer "B.Cu")
		(net 613)
	)
	(segment
		(start 53.9 118.202499)
		(end 53.5495 117.851999)
		(width 0.155)
		(layer "B.Cu")
		(net 613)
	)
	(segment
		(start 54.9 117.285)
		(end 53.9 117.285)
		(width 0.2)
		(layer "B.Cu")
		(net 613)
	)
	(segment
		(start 53.8 122.15)
		(end 53.85 122.1)
		(width 0.155)
		(layer "B.Cu")
		(net 613)
	)
	(segment
		(start 53.5495 117.6355)
		(end 53.9 117.285)
		(width 0.155)
		(layer "B.Cu")
		(net 613)
	)
	(segment
		(start 53.9 120.6)
		(end 53.9 119.385)
		(width 0.155)
		(layer "B.Cu")
		(net 613)
	)
	(segment
		(start 69.1005 110.756969)
		(end 69.1005 110.536926)
		(width 0.155)
		(layer "F.Cu")
		(net 614)
	)
	(segment
		(start 69 110.857469)
		(end 69.1005 110.756969)
		(width 0.155)
		(layer "F.Cu")
		(net 614)
	)
	(segment
		(start 68.1005 107.768074)
		(end 68.598074 107.2705)
		(width 0.155)
		(layer "F.Cu")
		(net 614)
	)
	(segment
		(start 69 111.752469)
		(end 69 110.982469)
		(width 0.155)
		(layer "F.Cu")
		(net 614)
	)
	(segment
		(start 68.4755 109.236926)
		(end 68.1005 108.861926)
		(width 0.155)
		(layer "F.Cu")
		(net 614)
	)
	(segment
		(start 68.598074 107.2705)
		(end 69.631926 107.2705)
		(width 0.155)
		(layer "F.Cu")
		(net 614)
	)
	(segment
		(start 69 111.752469)
		(end 69 112.16497)
		(width 0.155)
		(layer "F.Cu")
		(net 614)
	)
	(segment
		(start 69.1005 110.536926)
		(end 68.4755 109.911926)
		(width 0.155)
		(layer "F.Cu")
		(net 614)
	)
	(segment
		(start 68.1005 108.861926)
		(end 68.1005 107.768074)
		(width 0.155)
		(layer "F.Cu")
		(net 614)
	)
	(segment
		(start 69.1005 112.8525)
		(end 68.953 113)
		(width 0.155)
		(layer "F.Cu")
		(net 614)
	)
	(segment
		(start 70.081926 107.7205)
		(end 70.718074 107.7205)
		(width 0.155)
		(layer "F.Cu")
		(net 614)
	)
	(segment
		(start 70.920605 107.517969)
		(end 71.7995 107.517969)
		(width 0.155)
		(layer "F.Cu")
		(net 614)
	)
	(segment
		(start 68.4755 109.911926)
		(end 68.4755 109.236926)
		(width 0.155)
		(layer "F.Cu")
		(net 614)
	)
	(segment
		(start 69.1005 112.26547)
		(end 69.1005 112.8525)
		(width 0.155)
		(layer "F.Cu")
		(net 614)
	)
	(segment
		(start 71.7995 107.517969)
		(end 71.85 107.467469)
		(width 0.155)
		(layer "F.Cu")
		(net 614)
	)
	(segment
		(start 70.718074 107.7205)
		(end 70.920605 107.517969)
		(width 0.155)
		(layer "F.Cu")
		(net 614)
	)
	(segment
		(start 69.631926 107.2705)
		(end 70.081926 107.7205)
		(width 0.155)
		(layer "F.Cu")
		(net 614)
	)
	(segment
		(start 69 112.16497)
		(end 69.1005 112.26547)
		(width 0.155)
		(layer "F.Cu")
		(net 614)
	)
	(via
		(at 68.953 113)
		(size 0.45)
		(drill 0.1)
		(layers "F.Cu" "B.Cu")
		(net 614)
	)
	(segment
		(start 71.111718 111.526)
		(end 69.538282 111.526)
		(width 0.16)
		(layer "In3.Cu")
		(net 614)
	)
	(segment
		(start 73.686718 115.251)
		(end 71.949 113.513282)
		(width 0.16)
		(layer "In3.Cu")
		(net 614)
	)
	(segment
		(start 69.538282 111.526)
		(end 69.101 111.963282)
		(width 0.16)
		(layer "In3.Cu")
		(net 614)
	)
	(segment
		(start 74.88492 121)
		(end 77.4 121)
		(width 0.16)
		(layer "In3.Cu")
		(net 614)
	)
	(segment
		(start 78.3 118.110718)
		(end 79.149 117.261718)
		(width 0.16)
		(layer "In3.Cu")
		(net 614)
	)
	(segment
		(start 78.3 120.1)
		(end 78.3 118.110718)
		(width 0.16)
		(layer "In3.Cu")
		(net 614)
	)
	(segment
		(start 71.949 113.513282)
		(end 71.949 112.363282)
		(width 0.16)
		(layer "In3.Cu")
		(net 614)
	)
	(segment
		(start 79.149 117.261718)
		(end 79.149 116.338282)
		(width 0.16)
		(layer "In3.Cu")
		(net 614)
	)
	(segment
		(start 73.94992 120.065)
		(end 74.88492 121)
		(width 0.16)
		(layer "In3.Cu")
		(net 614)
	)
	(segment
		(start 69.101 112.852)
		(end 68.953 113)
		(width 0.16)
		(layer "In3.Cu")
		(net 614)
	)
	(segment
		(start 79.149 116.338282)
		(end 78.061718 115.251)
		(width 0.16)
		(layer "In3.Cu")
		(net 614)
	)
	(segment
		(start 77.4 121)
		(end 78.3 120.1)
		(width 0.16)
		(layer "In3.Cu")
		(net 614)
	)
	(segment
		(start 78.061718 115.251)
		(end 73.686718 115.251)
		(width 0.16)
		(layer "In3.Cu")
		(net 614)
	)
	(segment
		(start 71.949 112.363282)
		(end 71.111718 111.526)
		(width 0.16)
		(layer "In3.Cu")
		(net 614)
	)
	(segment
		(start 69.101 111.963282)
		(end 69.101 112.852)
		(width 0.16)
		(layer "In3.Cu")
		(net 614)
	)
	(segment
		(start 74.265 120.38008)
		(end 73.94992 120.065)
		(width 0.155)
		(layer "B.Cu")
		(net 614)
	)
	(segment
		(start 74.265 121.1)
		(end 74.265 120.38008)
		(width 0.155)
		(layer "B.Cu")
		(net 614)
	)
	(segment
		(start 68.3995 107.891926)
		(end 68.721926 107.5695)
		(width 0.155)
		(layer "F.Cu")
		(net 615)
	)
	(segment
		(start 68.7745 109.788074)
		(end 68.7745 109.113074)
		(width 0.155)
		(layer "F.Cu")
		(net 615)
	)
	(segment
		(start 69.958074 108.0195)
		(end 70.841926 108.0195)
		(width 0.155)
		(layer "F.Cu")
		(net 615)
	)
	(segment
		(start 70.841926 108.0195)
		(end 71.044457 107.816969)
		(width 0.155)
		(layer "F.Cu")
		(net 615)
	)
	(segment
		(start 68.7745 109.113074)
		(end 68.3995 108.738074)
		(width 0.155)
		(layer "F.Cu")
		(net 615)
	)
	(segment
		(start 75.49992 117.20008)
		(end 75.5 117.2)
		(width 0.15)
		(layer "F.Cu")
		(net 615)
	)
	(segment
		(start 75.49992 118.115)
		(end 75.49992 117.20008)
		(width 0.15)
		(layer "F.Cu")
		(net 615)
	)
	(segment
		(start 69.3995 112.26547)
		(end 69.3995 112.8525)
		(width 0.155)
		(layer "F.Cu")
		(net 615)
	)
	(segment
		(start 69.3995 112.8525)
		(end 69.547 113)
		(width 0.155)
		(layer "F.Cu")
		(net 615)
	)
	(segment
		(start 69.508074 107.5695)
		(end 69.958074 108.0195)
		(width 0.155)
		(layer "F.Cu")
		(net 615)
	)
	(segment
		(start 69.5 110.857469)
		(end 69.3995 110.756969)
		(width 0.155)
		(layer "F.Cu")
		(net 615)
	)
	(segment
		(start 69.5 111.752469)
		(end 69.5 110.982469)
		(width 0.155)
		(layer "F.Cu")
		(net 615)
	)
	(segment
		(start 71.7995 107.816969)
		(end 71.85 107.867469)
		(width 0.155)
		(layer "F.Cu")
		(net 615)
	)
	(segment
		(start 68.721926 107.5695)
		(end 69.508074 107.5695)
		(width 0.155)
		(layer "F.Cu")
		(net 615)
	)
	(segment
		(start 69.5 111.752469)
		(end 69.5 112.16497)
		(width 0.155)
		(layer "F.Cu")
		(net 615)
	)
	(segment
		(start 69.5 112.16497)
		(end 69.3995 112.26547)
		(width 0.155)
		(layer "F.Cu")
		(net 615)
	)
	(segment
		(start 68.3995 108.738074)
		(end 68.3995 107.891926)
		(width 0.155)
		(layer "F.Cu")
		(net 615)
	)
	(segment
		(start 71.044457 107.816969)
		(end 71.7995 107.816969)
		(width 0.155)
		(layer "F.Cu")
		(net 615)
	)
	(segment
		(start 69.3995 110.413074)
		(end 68.7745 109.788074)
		(width 0.155)
		(layer "F.Cu")
		(net 615)
	)
	(segment
		(start 69.3995 110.756969)
		(end 69.3995 110.413074)
		(width 0.155)
		(layer "F.Cu")
		(net 615)
	)
	(via
		(at 75.5 117.2)
		(size 0.45)
		(drill 0.1)
		(layers "F.Cu" "B.Cu")
		(net 615)
	)
	(via
		(at 69.547 113)
		(size 0.45)
		(drill 0.1)
		(layers "F.Cu" "B.Cu")
		(net 615)
	)
	(segment
		(start 75.5 117.2)
		(end 76.2 117.2)
		(width 0.16)
		(layer "In3.Cu")
		(net 615)
	)
	(segment
		(start 78.851 117.138282)
		(end 78.851 116.461718)
		(width 0.16)
		(layer "In3.Cu")
		(net 615)
	)
	(segment
		(start 78.851 116.461718)
		(end 77.938282 115.549)
		(width 0.16)
		(layer "In3.Cu")
		(net 615)
	)
	(segment
		(start 71.651 112.486718)
		(end 70.988282 111.824)
		(width 0.16)
		(layer "In3.Cu")
		(net 615)
	)
	(segment
		(start 69.399 112.852)
		(end 69.547 113)
		(width 0.16)
		(layer "In3.Cu")
		(net 615)
	)
	(segment
		(start 73.563282 115.549)
		(end 71.651 113.636718)
		(width 0.16)
		(layer "In3.Cu")
		(net 615)
	)
	(segment
		(start 71.651 113.636718)
		(end 71.651 112.486718)
		(width 0.16)
		(layer "In3.Cu")
		(net 615)
	)
	(segment
		(start 69.399 112.086718)
		(end 69.399 112.852)
		(width 0.16)
		(layer "In3.Cu")
		(net 615)
	)
	(segment
		(start 78.089282 117.9)
		(end 78.851 117.138282)
		(width 0.16)
		(layer "In3.Cu")
		(net 615)
	)
	(segment
		(start 69.661718 111.824)
		(end 69.399 112.086718)
		(width 0.16)
		(layer "In3.Cu")
		(net 615)
	)
	(segment
		(start 70.988282 111.824)
		(end 69.661718 111.824)
		(width 0.16)
		(layer "In3.Cu")
		(net 615)
	)
	(segment
		(start 76.9 117.9)
		(end 78.089282 117.9)
		(width 0.16)
		(layer "In3.Cu")
		(net 615)
	)
	(segment
		(start 76.2 117.2)
		(end 76.9 117.9)
		(width 0.16)
		(layer "In3.Cu")
		(net 615)
	)
	(segment
		(start 77.938282 115.549)
		(end 73.563282 115.549)
		(width 0.16)
		(layer "In3.Cu")
		(net 615)
	)
	(segment
		(start 75.23 116.93)
		(end 75.5 117.2)
		(width 0.155)
		(layer "B.Cu")
		(net 615)
	)
	(segment
		(start 75.23 116.485)
		(end 75.23 116.93)
		(width 0.155)
		(layer "B.Cu")
		(net 615)
	)
	(segment
		(start 126.3932 86.475)
		(end 124.575 86.475)
		(width 0.2)
		(layer "F.Cu")
		(net 616)
	)
	(segment
		(start 128.815 91.25)
		(end 128.565001 91.499999)
		(width 0.2)
		(layer "F.Cu")
		(net 616)
	)
	(segment
		(start 124.575 86.475)
		(end 124.5 86.4)
		(width 0.2)
		(layer "F.Cu")
		(net 616)
	)
	(segment
		(start 128.118199 91.499999)
		(end 127.225 90.6068)
		(width 0.2)
		(layer "F.Cu")
		(net 616)
	)
	(segment
		(start 128.565001 91.499999)
		(end 128.118199 91.499999)
		(width 0.2)
		(layer "F.Cu")
		(net 616)
	)
	(segment
		(start 127.225 90.6068)
		(end 127.225 87.3068)
		(width 0.2)
		(layer "F.Cu")
		(net 616)
	)
	(segment
		(start 127.225 87.3068)
		(end 126.3932 86.475)
		(width 0.2)
		(layer "F.Cu")
		(net 616)
	)
	(segment
		(start 124.525 86.925)
		(end 124.5 86.9)
		(width 0.2)
		(layer "F.Cu")
		(net 617)
	)
	(segment
		(start 126.775 87.4932)
		(end 126.2068 86.925)
		(width 0.2)
		(layer "F.Cu")
		(net 617)
	)
	(segment
		(start 127.931801 91.950001)
		(end 126.775 90.7932)
		(width 0.2)
		(layer "F.Cu")
		(net 617)
	)
	(segment
		(start 126.2068 86.925)
		(end 124.525 86.925)
		(width 0.2)
		(layer "F.Cu")
		(net 617)
	)
	(segment
		(start 128.815 92.2)
		(end 128.565001 91.950001)
		(width 0.2)
		(layer "F.Cu")
		(net 617)
	)
	(segment
		(start 126.775 90.7932)
		(end 126.775 87.4932)
		(width 0.2)
		(layer "F.Cu")
		(net 617)
	)
	(segment
		(start 128.565001 91.950001)
		(end 127.931801 91.950001)
		(width 0.2)
		(layer "F.Cu")
		(net 617)
	)
	(segment
		(start 132.3495 96.5495)
		(end 132.3495 96.4995)
		(width 0.155)
		(layer "F.Cu")
		(net 618)
	)
	(segment
		(start 133.261926 97.9505)
		(end 132.661926 97.9505)
		(width 0.155)
		(layer "F.Cu")
		(net 618)
	)
	(segment
		(start 132.661926 97.9505)
		(end 132.3495 97.638074)
		(width 0.155)
		(layer "F.Cu")
		(net 618)
	)
	(segment
		(start 136.061926 99.4005)
		(end 135.711926 99.0505)
		(width 0.155)
		(layer "F.Cu")
		(net 618)
	)
	(segment
		(start 132.3495 97.638074)
		(end 132.3495 97.3495)
		(width 0.155)
		(layer "F.Cu")
		(net 618)
	)
	(segment
		(start 134.361926 99.0505)
		(end 133.261926 97.9505)
		(width 0.155)
		(layer "F.Cu")
		(net 618)
	)
	(segment
		(start 141.5 99.15)
		(end 140.674999 99.15)
		(width 0.155)
		(layer "F.Cu")
		(net 618)
	)
	(segment
		(start 132.5495 97.1495)
		(end 132.568883 97.1495)
		(width 0.155)
		(layer "F.Cu")
		(net 618)
	)
	(segment
		(start 132.3495 96.4995)
		(end 132.3495 96.361926)
		(width 0.155)
		(layer "F.Cu")
		(net 618)
	)
	(segment
		(start 133.0525 95.8495)
		(end 133.2 95.997)
		(width 0.155)
		(layer "F.Cu")
		(net 618)
	)
	(segment
		(start 132.861926 95.8495)
		(end 133.0525 95.8495)
		(width 0.155)
		(layer "F.Cu")
		(net 618)
	)
	(segment
		(start 140.674999 99.15)
		(end 140.424499 99.4005)
		(width 0.155)
		(layer "F.Cu")
		(net 618)
	)
	(segment
		(start 135.711926 99.0505)
		(end 134.361926 99.0505)
		(width 0.155)
		(layer "F.Cu")
		(net 618)
	)
	(segment
		(start 132.568883 96.7495)
		(end 132.5495 96.7495)
		(width 0.155)
		(layer "F.Cu")
		(net 618)
	)
	(segment
		(start 140.424499 99.4005)
		(end 136.061926 99.4005)
		(width 0.155)
		(layer "F.Cu")
		(net 618)
	)
	(segment
		(start 132.3495 96.361926)
		(end 132.861926 95.8495)
		(width 0.155)
		(layer "F.Cu")
		(net 618)
	)
	(via
		(at 133.2 95.997)
		(size 0.45)
		(drill 0.1)
		(layers "F.Cu" "B.Cu")
		(net 618)
	)
	(arc
		(start 132.3495 97.3495)
		(mid 132.408079 97.208079)
		(end 132.5495 97.1495)
		(width 0.155)
		(layer "F.Cu")
		(net 618)
	)
	(arc
		(start 132.5495 96.7495)
		(mid 132.408079 96.690921)
		(end 132.3495 96.5495)
		(width 0.155)
		(layer "F.Cu")
		(net 618)
	)
	(arc
		(start 132.568883 97.1495)
		(mid 132.710304 97.090921)
		(end 132.768883 96.9495)
		(width 0.155)
		(layer "F.Cu")
		(net 618)
	)
	(arc
		(start 132.768883 96.9495)
		(mid 132.710304 96.808079)
		(end 132.568883 96.7495)
		(width 0.155)
		(layer "F.Cu")
		(net 618)
	)
	(segment
		(start 131.638074 94.6995)
		(end 131.288074 94.6995)
		(width 0.155)
		(layer "B.Cu")
		(net 618)
	)
	(segment
		(start 133.0525 95.8495)
		(end 132.788074 95.8495)
		(width 0.155)
		(layer "B.Cu")
		(net 618)
	)
	(segment
		(start 130.9505 94.0355)
		(end 130.6 93.685)
		(width 0.155)
		(layer "B.Cu")
		(net 618)
	)
	(segment
		(start 131.288074 94.6995)
		(end 130.9505 94.361926)
		(width 0.155)
		(layer "B.Cu")
		(net 618)
	)
	(segment
		(start 132.788074 95.8495)
		(end 131.638074 94.6995)
		(width 0.155)
		(layer "B.Cu")
		(net 618)
	)
	(segment
		(start 133.2 95.997)
		(end 133.0525 95.8495)
		(width 0.155)
		(layer "B.Cu")
		(net 618)
	)
	(segment
		(start 130.9505 94.361926)
		(end 130.9505 94.0355)
		(width 0.155)
		(layer "B.Cu")
		(net 618)
	)
	(segment
		(start 132.0505 97.761926)
		(end 132.0505 96.238074)
		(width 0.155)
		(layer "F.Cu")
		(net 619)
	)
	(segment
		(start 133.0525 95.5505)
		(end 133.2 95.403)
		(width 0.155)
		(layer "F.Cu")
		(net 619)
	)
	(segment
		(start 134.238074 99.3495)
		(end 133.138074 98.2495)
		(width 0.155)
		(layer "F.Cu")
		(net 619)
	)
	(segment
		(start 140.674999 99.95)
		(end 140.424499 99.6995)
		(width 0.155)
		(layer "F.Cu")
		(net 619)
	)
	(segment
		(start 135.588074 99.3495)
		(end 134.238074 99.3495)
		(width 0.155)
		(layer "F.Cu")
		(net 619)
	)
	(segment
		(start 140.424499 99.6995)
		(end 135.938074 99.6995)
		(width 0.155)
		(layer "F.Cu")
		(net 619)
	)
	(segment
		(start 133.138074 98.2495)
		(end 132.538074 98.2495)
		(width 0.155)
		(layer "F.Cu")
		(net 619)
	)
	(segment
		(start 132.0505 96.238074)
		(end 132.738074 95.5505)
		(width 0.155)
		(layer "F.Cu")
		(net 619)
	)
	(segment
		(start 132.538074 98.2495)
		(end 132.0505 97.761926)
		(width 0.155)
		(layer "F.Cu")
		(net 619)
	)
	(segment
		(start 141.5 99.95)
		(end 140.674999 99.95)
		(width 0.155)
		(layer "F.Cu")
		(net 619)
	)
	(segment
		(start 135.938074 99.6995)
		(end 135.588074 99.3495)
		(width 0.155)
		(layer "F.Cu")
		(net 619)
	)
	(segment
		(start 132.738074 95.5505)
		(end 133.0525 95.5505)
		(width 0.155)
		(layer "F.Cu")
		(net 619)
	)
	(via
		(at 133.2 95.403)
		(size 0.45)
		(drill 0.1)
		(layers "F.Cu" "B.Cu")
		(net 619)
	)
	(segment
		(start 132.911926 95.5505)
		(end 131.761926 94.4005)
		(width 0.155)
		(layer "B.Cu")
		(net 619)
	)
	(segment
		(start 131.761926 94.4005)
		(end 131.411926 94.4005)
		(width 0.155)
		(layer "B.Cu")
		(net 619)
	)
	(segment
		(start 131.2495 94.0355)
		(end 131.6 93.685)
		(width 0.155)
		(layer "B.Cu")
		(net 619)
	)
	(segment
		(start 131.2495 94.238074)
		(end 131.2495 94.0355)
		(width 0.155)
		(layer "B.Cu")
		(net 619)
	)
	(segment
		(start 131.411926 94.4005)
		(end 131.2495 94.238074)
		(width 0.155)
		(layer "B.Cu")
		(net 619)
	)
	(segment
		(start 133.2 95.403)
		(end 133.0525 95.5505)
		(width 0.155)
		(layer "B.Cu")
		(net 619)
	)
	(segment
		(start 133.0525 95.5505)
		(end 132.911926 95.5505)
		(width 0.155)
		(layer "B.Cu")
		(net 619)
	)
	(segment
		(start 102.95 89.315)
		(end 102.015 89.315)
		(width 0.15)
		(layer "F.Cu")
		(net 621)
	)
	(segment
		(start 102.015 89.315)
		(end 101.95 89.25)
		(width 0.15)
		(layer "F.Cu")
		(net 621)
	)
	(segment
		(start 101.95 88.135)
		(end 101.95 89.25)
		(width 0.15)
		(layer "F.Cu")
		(net 621)
	)
	(segment
		(start 101.125 95.475)
		(end 100.65 95)
		(width 0.15)
		(layer "F.Cu")
		(net 622)
	)
	(segment
		(start 101.95 95.475)
		(end 101.125 95.475)
		(width 0.15)
		(layer "F.Cu")
		(net 622)
	)
	(segment
		(start 100.65 95)
		(end 100.65 89.75)
		(width 0.15)
		(layer "F.Cu")
		(net 622)
	)
	(via
		(at 101.95 95.475)
		(size 0.45)
		(drill 0.1)
		(layers "F.Cu" "B.Cu")
		(net 622)
	)
	(segment
		(start 94.45 95.55)
		(end 101.875 95.55)
		(width 0.15)
		(layer "B.Cu")
		(net 622)
	)
	(segment
		(start 94.25 95.05)
		(end 94.25 95.35)
		(width 0.15)
		(layer "B.Cu")
		(net 622)
	)
	(segment
		(start 94.25 95.35)
		(end 94.45 95.55)
		(width 0.15)
		(layer "B.Cu")
		(net 622)
	)
	(segment
		(start 93.65 94.45)
		(end 94.25 95.05)
		(width 0.15)
		(layer "B.Cu")
		(net 622)
	)
	(segment
		(start 101.875 95.55)
		(end 101.95 95.475)
		(width 0.15)
		(layer "B.Cu")
		(net 622)
	)
	(segment
		(start 93.0075 94.45)
		(end 93.65 94.45)
		(width 0.15)
		(layer "B.Cu")
		(net 622)
	)
	(segment
		(start 92.05 102.65)
		(end 92.05 103.1)
		(width 0.125)
		(layer "F.Cu")
		(net 623)
	)
	(segment
		(start 91.75 102.35)
		(end 92.05 102.65)
		(width 0.125)
		(layer "F.Cu")
		(net 623)
	)
	(segment
		(start 93.4 101.85)
		(end 93.4 102.874106)
		(width 0.125)
		(layer "F.Cu")
		(net 623)
	)
	(segment
		(start 93.4 102.874106)
		(end 94.262947 103.737053)
		(width 0.125)
		(layer "F.Cu")
		(net 623)
	)
	(segment
		(start 91.9 103.25)
		(end 91.9 105.405894)
		(width 0.125)
		(layer "F.Cu")
		(net 623)
	)
	(segment
		(start 91.75 100.2)
		(end 93.4 101.85)
		(width 0.125)
		(layer "F.Cu")
		(net 623)
	)
	(segment
		(start 91.9 105.405894)
		(end 92.247053 105.752947)
		(width 0.125)
		(layer "F.Cu")
		(net 623)
	)
	(segment
		(start 92.05 103.1)
		(end 91.9 103.25)
		(width 0.125)
		(layer "F.Cu")
		(net 623)
	)
	(segment
		(start 88.8 100.2)
		(end 88.15 100.2)
		(width 0.125)
		(layer "F.Cu")
		(net 623)
	)
	(segment
		(start 88.95 103.7)
		(end 89.2 103.45)
		(width 0.125)
		(layer "F.Cu")
		(net 623)
	)
	(segment
		(start 89.357053 104.942947)
		(end 89.357053 104.877053)
		(width 0.125)
		(layer "F.Cu")
		(net 623)
	)
	(segment
		(start 90.95 102.3)
		(end 90.94 102.31)
		(width 0.15)
		(layer "F.Cu")
		(net 623)
	)
	(segment
		(start 89.2 100.6)
		(end 88.8 100.2)
		(width 0.125)
		(layer "F.Cu")
		(net 623)
	)
	(segment
		(start 91.45 102.35)
		(end 91.75 102.35)
		(width 0.125)
		(layer "F.Cu")
		(net 623)
	)
	(segment
		(start 89.2 103.45)
		(end 89.2 100.6)
		(width 0.125)
		(layer "F.Cu")
		(net 623)
	)
	(segment
		(start 91.307053 102.937053)
		(end 91.362947 102.937053)
		(width 0.15)
		(layer "F.Cu")
		(net 623)
	)
	(segment
		(start 90.94 102.31)
		(end 90.94 102.57)
		(width 0.15)
		(layer "F.Cu")
		(net 623)
	)
	(segment
		(start 90.94 102.57)
		(end 91.307053 102.937053)
		(width 0.15)
		(layer "F.Cu")
		(net 623)
	)
	(segment
		(start 89.357053 104.877053)
		(end 88.95 104.47)
		(width 0.125)
		(layer "F.Cu")
		(net 623)
	)
	(segment
		(start 88.95 104.47)
		(end 88.95 103.7)
		(width 0.125)
		(layer "F.Cu")
		(net 623)
	)
	(via
		(at 91.45 102.35)
		(size 0.45)
		(drill 0.1)
		(layers "F.Cu" "B.Cu")
		(net 623)
	)
	(via
		(at 91.75 100.2)
		(size 0.45)
		(drill 0.1)
		(layers "F.Cu" "B.Cu")
		(net 623)
	)
	(via
		(at 89.2 103.45)
		(size 0.45)
		(drill 0.1)
		(layers "F.Cu" "B.Cu")
		(net 623)
	)
	(via
		(at 90.95 102.3)
		(size 0.45)
		(drill 0.1)
		(layers "F.Cu" "B.Cu")
		(net 623)
	)
	(segment
		(start 90.35 102.3)
		(end 89.2 103.45)
		(width 0.125)
		(layer "In5.Cu")
		(net 623)
	)
	(segment
		(start 92.09 101.16)
		(end 90.95 102.3)
		(width 0.125)
		(layer "In5.Cu")
		(net 623)
	)
	(segment
		(start 90.95 102.3)
		(end 90.35 102.3)
		(width 0.125)
		(layer "In5.Cu")
		(net 623)
	)
	(segment
		(start 91 102.35)
		(end 90.95 102.3)
		(width 0.15)
		(layer "In5.Cu")
		(net 623)
	)
	(segment
		(start 92.09 100.54)
		(end 92.09 101.16)
		(width 0.125)
		(layer "In5.Cu")
		(net 623)
	)
	(segment
		(start 91.45 102.35)
		(end 91 102.35)
		(width 0.15)
		(layer "In5.Cu")
		(net 623)
	)
	(segment
		(start 91.75 100.2)
		(end 92.09 100.54)
		(width 0.125)
		(layer "In5.Cu")
		(net 623)
	)
	(segment
		(start 91.45 102.35)
		(end 91.747053 102.647053)
		(width 0.15)
		(layer "B.Cu")
		(net 623)
	)
	(segment
		(start 91.75 100.2)
		(end 92.105894 100.2)
		(width 0.15)
		(layer "B.Cu")
		(net 623)
	)
	(segment
		(start 90.902947 102.252947)
		(end 90.147053 102.252947)
		(width 0.15)
		(layer "B.Cu")
		(net 623)
	)
	(segment
		(start 89.2 103.805894)
		(end 89.2 103.45)
		(width 0.15)
		(layer "B.Cu")
		(net 623)
	)
	(segment
		(start 92.105894 100.2)
		(end 92.152947 100.247053)
		(width 0.15)
		(layer "B.Cu")
		(net 623)
	)
	(segment
		(start 90.95 102.3)
		(end 90.902947 102.252947)
		(width 0.15)
		(layer "B.Cu")
		(net 623)
	)
	(segment
		(start 90.047053 104.652947)
		(end 89.2 103.805894)
		(width 0.15)
		(layer "B.Cu")
		(net 623)
	)
	(segment
		(start 91.747053 102.647053)
		(end 92.052947 102.647053)
		(width 0.15)
		(layer "B.Cu")
		(net 623)
	)
	(segment
		(start 92.9 97.19)
		(end 93.46 96.63)
		(width 0.125)
		(layer "F.Cu")
		(net 624)
	)
	(segment
		(start 92.68 99.05)
		(end 93.03 98.7)
		(width 0.125)
		(layer "F.Cu")
		(net 624)
	)
	(segment
		(start 93.03 97.74)
		(end 92.9 97.61)
		(width 0.125)
		(layer "F.Cu")
		(net 624)
	)
	(segment
		(start 92.85 92.735)
		(end 92.315 92.2)
		(width 0.125)
		(layer "F.Cu")
		(net 624)
	)
	(segment
		(start 92.88 94.52)
		(end 92.85 94.55)
		(width 0.125)
		(layer "F.Cu")
		(net 624)
	)
	(segment
		(start 91.97 99.05)
		(end 92.68 99.05)
		(width 0.125)
		(layer "F.Cu")
		(net 624)
	)
	(segment
		(start 93.32 94.52)
		(end 92.88 94.52)
		(width 0.125)
		(layer "F.Cu")
		(net 624)
	)
	(segment
		(start 92.85 94.55)
		(end 92.85 92.735)
		(width 0.125)
		(layer "F.Cu")
		(net 624)
	)
	(segment
		(start 92.9 97.61)
		(end 92.9 97.19)
		(width 0.125)
		(layer "F.Cu")
		(net 624)
	)
	(segment
		(start 93.03 98.7)
		(end 93.03 97.74)
		(width 0.125)
		(layer "F.Cu")
		(net 624)
	)
	(segment
		(start 93.46 94.66)
		(end 93.32 94.52)
		(width 0.125)
		(layer "F.Cu")
		(net 624)
	)
	(segment
		(start 93.46 96.63)
		(end 93.46 94.66)
		(width 0.125)
		(layer "F.Cu")
		(net 624)
	)
	(via
		(at 91.97 99.05)
		(size 0.45)
		(drill 0.1)
		(layers "F.Cu" "B.Cu")
		(net 624)
	)
	(segment
		(start 92.6 96.85)
		(end 92.6 96.575)
		(width 0.15)
		(layer "B.Cu")
		(net 624)
	)
	(segment
		(start 91.97 99.05)
		(end 91.9 98.98)
		(width 0.15)
		(layer "B.Cu")
		(net 624)
	)
	(segment
		(start 91.315 97.965)
		(end 91.3 97.965)
		(width 0.15)
		(layer "B.Cu")
		(net 624)
	)
	(segment
		(start 91.9 98.55)
		(end 91.315 97.965)
		(width 0.15)
		(layer "B.Cu")
		(net 624)
	)
	(segment
		(start 92.6 96.575)
		(end 93.0075 96.1675)
		(width 0.15)
		(layer "B.Cu")
		(net 624)
	)
	(segment
		(start 91.3 97.965)
		(end 91.485 97.965)
		(width 0.15)
		(layer "B.Cu")
		(net 624)
	)
	(segment
		(start 91.9 98.98)
		(end 91.9 98.55)
		(width 0.15)
		(layer "B.Cu")
		(net 624)
	)
	(segment
		(start 91.485 97.965)
		(end 92.6 96.85)
		(width 0.15)
		(layer "B.Cu")
		(net 624)
	)
	(segment
		(start 93.0075 96.1675)
		(end 93.0075 95.95)
		(width 0.15)
		(layer "B.Cu")
		(net 624)
	)
	(segment
		(start 104.75 118.85)
		(end 104.25 118.85)
		(width 0.15)
		(layer "F.Cu")
		(net 625)
	)
	(segment
		(start 104.25 118.85)
		(end 104.05 118.65)
		(width 0.15)
		(layer "F.Cu")
		(net 625)
	)
	(segment
		(start 103.9 117.95)
		(end 103.3 117.95)
		(width 0.15)
		(layer "F.Cu")
		(net 625)
	)
	(segment
		(start 104.05 118.1)
		(end 103.9 117.95)
		(width 0.15)
		(layer "F.Cu")
		(net 625)
	)
	(segment
		(start 104.05 118.65)
		(end 104.05 118.1)
		(width 0.15)
		(layer "F.Cu")
		(net 625)
	)
	(segment
		(start 64.56 74.35)
		(end 64.56 74.64)
		(width 0.15)
		(layer "B.Cu")
		(net 628)
	)
	(segment
		(start 63.55 75.65)
		(end 63.2 75.65)
		(width 0.15)
		(layer "B.Cu")
		(net 628)
	)
	(segment
		(start 64.56 74.64)
		(end 63.55 75.65)
		(width 0.15)
		(layer "B.Cu")
		(net 628)
	)
	(via
		(at 57.725 78.225)
		(size 0.45)
		(drill 0.1)
		(layers "F.Cu" "B.Cu")
		(net 629)
	)
	(via
		(at 65.25 73.7)
		(size 0.45)
		(drill 0.1)
		(layers "F.Cu" "B.Cu")
		(net 629)
	)
	(segment
		(start 58.3 77.65)
		(end 58.875 77.65)
		(width 0.125)
		(layer "In3.Cu")
		(net 629)
	)
	(segment
		(start 57.725 78.225)
		(end 58.3 77.65)
		(width 0.125)
		(layer "In3.Cu")
		(net 629)
	)
	(segment
		(start 58.875 77.65)
		(end 61.125 75.4)
		(width 0.125)
		(layer "In3.Cu")
		(net 629)
	)
	(segment
		(start 64.55 74.85)
		(end 64.55 73.95)
		(width 0.125)
		(layer "In3.Cu")
		(net 629)
	)
	(segment
		(start 64.8 73.7)
		(end 65.25 73.7)
		(width 0.125)
		(layer "In3.Cu")
		(net 629)
	)
	(segment
		(start 64.55 73.95)
		(end 64.8 73.7)
		(width 0.125)
		(layer "In3.Cu")
		(net 629)
	)
	(segment
		(start 64 75.4)
		(end 64.55 74.85)
		(width 0.125)
		(layer "In3.Cu")
		(net 629)
	)
	(segment
		(start 61.125 75.4)
		(end 64 75.4)
		(width 0.125)
		(layer "In3.Cu")
		(net 629)
	)
	(segment
		(start 65.862 73.85)
		(end 65.4 73.85)
		(width 0.15)
		(layer "B.Cu")
		(net 629)
	)
	(segment
		(start 67.15 74.3)
		(end 67.15 72.67)
		(width 0.15)
		(layer "B.Cu")
		(net 629)
	)
	(segment
		(start 66 74.3)
		(end 65.86 74.16)
		(width 0.15)
		(layer "B.Cu")
		(net 629)
	)
	(segment
		(start 57.299 78.751)
		(end 57.725 78.325)
		(width 0.125)
		(layer "B.Cu")
		(net 629)
	)
	(segment
		(start 57.725 78.325)
		(end 57.725 78.225)
		(width 0.125)
		(layer "B.Cu")
		(net 629)
	)
	(segment
		(start 65.86 74.16)
		(end 65.86 73.85)
		(width 0.15)
		(layer "B.Cu")
		(net 629)
	)
	(segment
		(start 67.15 74.3)
		(end 66 74.3)
		(width 0.15)
		(layer "B.Cu")
		(net 629)
	)
	(segment
		(start 57.299 78.8)
		(end 57.299 78.751)
		(width 0.125)
		(layer "B.Cu")
		(net 629)
	)
	(segment
		(start 65.4 73.85)
		(end 65.25 73.7)
		(width 0.15)
		(layer "B.Cu")
		(net 629)
	)
	(segment
		(start 58.285 107.1)
		(end 59.05 107.865)
		(width 0.15)
		(layer "F.Cu")
		(net 630)
	)
	(segment
		(start 59.15 108.45)
		(end 59.6 108.9)
		(width 0.15)
		(layer "F.Cu")
		(net 630)
	)
	(segment
		(start 59.6 108.9)
		(end 59.6 110.7)
		(width 0.15)
		(layer "F.Cu")
		(net 630)
	)
	(segment
		(start 59.05 107.865)
		(end 59.05 108.45)
		(width 0.15)
		(layer "F.Cu")
		(net 630)
	)
	(segment
		(start 59.05 108.45)
		(end 59.15 108.45)
		(width 0.15)
		(layer "F.Cu")
		(net 630)
	)
	(segment
		(start 59.6 110.7)
		(end 59.15 111.15)
		(width 0.15)
		(layer "F.Cu")
		(net 630)
	)
	(segment
		(start 46.04 74.475)
		(end 45.09 75.425)
		(width 0.15)
		(layer "B.Cu")
		(net 631)
	)
	(segment
		(start 44.69 76.925)
		(end 44.39 77.225)
		(width 0.15)
		(layer "B.Cu")
		(net 631)
	)
	(segment
		(start 44.69 75.425)
		(end 44.69 76.925)
		(width 0.15)
		(layer "B.Cu")
		(net 631)
	)
	(segment
		(start 45.09 75.425)
		(end 44.69 75.425)
		(width 0.15)
		(layer "B.Cu")
		(net 631)
	)
	(segment
		(start 109.1 111.5)
		(end 109.4 111.2)
		(width 0.15)
		(layer "B.Cu")
		(net 632)
	)
	(segment
		(start 109.4 110.515)
		(end 109.185 110.3)
		(width 0.15)
		(layer "B.Cu")
		(net 632)
	)
	(segment
		(start 109.185 110.3)
		(end 109.185 109.265)
		(width 0.15)
		(layer "B.Cu")
		(net 632)
	)
	(segment
		(start 109.4 111.2)
		(end 109.4 110.515)
		(width 0.15)
		(layer "B.Cu")
		(net 632)
	)
	(segment
		(start 109.185 109.265)
		(end 109.2 109.25)
		(width 0.15)
		(layer "B.Cu")
		(net 632)
	)
	(segment
		(start 108.1 111.515)
		(end 109.1 111.515)
		(width 0.15)
		(layer "B.Cu")
		(net 632)
	)
	(segment
		(start 109.1 111.515)
		(end 109.1 111.5)
		(width 0.15)
		(layer "B.Cu")
		(net 632)
	)
	(via
		(at 112.7 90.3)
		(size 0.45)
		(drill 0.1)
		(layers "F.Cu" "B.Cu")
		(net 635)
	)
	(via
		(at 106.3 91.3)
		(size 0.45)
		(drill 0.1)
		(layers "F.Cu" "B.Cu")
		(net 635)
	)
	(segment
		(start 107.3 90.3)
		(end 106.3 91.3)
		(width 0.2)
		(layer "In1.Cu")
		(net 635)
	)
	(segment
		(start 112.7 90.3)
		(end 107.3 90.3)
		(width 0.2)
		(layer "In1.Cu")
		(net 635)
	)
	(segment
		(start 116.775 92.25)
		(end 115.6 92.25)
		(width 0.2)
		(layer "B.Cu")
		(net 635)
	)
	(segment
		(start 116.775 91.75)
		(end 115.45 91.75)
		(width 0.2)
		(layer "B.Cu")
		(net 635)
	)
	(segment
		(start 115.45 91.75)
		(end 115.2 91.5)
		(width 0.2)
		(layer "B.Cu")
		(net 635)
	)
	(segment
		(start 116.775 95.25)
		(end 115.45 95.25)
		(width 0.2)
		(layer "B.Cu")
		(net 635)
	)
	(segment
		(start 115.6 92.25)
		(end 115.2 91.85)
		(width 0.2)
		(layer "B.Cu")
		(net 635)
	)
	(segment
		(start 115.45 78.25)
		(end 115.15 77.95)
		(width 0.2)
		(layer "B.Cu")
		(net 635)
	)
	(segment
		(start 116.775 78.25)
		(end 115.45 78.25)
		(width 0.2)
		(layer "B.Cu")
		(net 635)
	)
	(segment
		(start 114.1 90.3)
		(end 112.7 90.3)
		(width 0.2)
		(layer "B.Cu")
		(net 635)
	)
	(segment
		(start 116.775 92.75)
		(end 115.45 92.75)
		(width 0.2)
		(layer "B.Cu")
		(net 635)
	)
	(segment
		(start 115.45 95.25)
		(end 115.2 95)
		(width 0.2)
		(layer "B.Cu")
		(net 635)
	)
	(segment
		(start 115.2 91.5)
		(end 115.2 91.4)
		(width 0.2)
		(layer "B.Cu")
		(net 635)
	)
	(segment
		(start 115.35 77.75)
		(end 115.15 77.95)
		(width 0.2)
		(layer "B.Cu")
		(net 635)
	)
	(segment
		(start 116.775 93.25)
		(end 115.45 93.25)
		(width 0.2)
		(layer "B.Cu")
		(net 635)
	)
	(segment
		(start 106.485 92.02)
		(end 106.485 91.485)
		(width 0.3)
		(layer "B.Cu")
		(net 635)
	)
	(segment
		(start 115.45 93.25)
		(end 115.2 93)
		(width 0.2)
		(layer "B.Cu")
		(net 635)
	)
	(segment
		(start 116.775 77.75)
		(end 115.35 77.75)
		(width 0.2)
		(layer "B.Cu")
		(net 635)
	)
	(segment
		(start 115.2 91.4)
		(end 114.1 90.3)
		(width 0.2)
		(layer "B.Cu")
		(net 635)
	)
	(segment
		(start 115.2 91.85)
		(end 115.2 91.5)
		(width 0.2)
		(layer "B.Cu")
		(net 635)
	)
	(segment
		(start 106.485 91.485)
		(end 106.3 91.3)
		(width 0.3)
		(layer "B.Cu")
		(net 635)
	)
	(segment
		(start 115.45 92.75)
		(end 115.2 93)
		(width 0.2)
		(layer "B.Cu")
		(net 635)
	)
	(segment
		(start 106.485 92.02)
		(end 107.8 92.02)
		(width 0.3)
		(layer "B.Cu")
		(net 635)
	)
	(segment
		(start 108.15175 96.01)
		(end 107.15175 96.01)
		(width 0.15)
		(layer "B.Cu")
		(net 636)
	)
	(segment
		(start 108.19 96.04825)
		(end 108.15175 96.01)
		(width 0.15)
		(layer "B.Cu")
		(net 636)
	)
	(segment
		(start 108.19 98.84)
		(end 108.19 96.04825)
		(width 0.15)
		(layer "B.Cu")
		(net 636)
	)
	(segment
		(start 61.8 104)
		(end 62.5 103.3)
		(width 0.15)
		(layer "B.Cu")
		(net 639)
	)
	(segment
		(start 59.21 104.12)
		(end 59.33 104)
		(width 0.15)
		(layer "B.Cu")
		(net 639)
	)
	(segment
		(start 59.33 104)
		(end 61.8 104)
		(width 0.15)
		(layer "B.Cu")
		(net 639)
	)
	(segment
		(start 62.5 103.3)
		(end 62.95 103.3)
		(width 0.15)
		(layer "B.Cu")
		(net 639)
	)
	(segment
		(start 78.8 85.4)
		(end 78.7 85.5)
		(width 0.15)
		(layer "F.Cu")
		(net 641)
	)
	(segment
		(start 78.7 85.5)
		(end 78.7 85.3)
		(width 0.15)
		(layer "F.Cu")
		(net 641)
	)
	(segment
		(start 78.625 87.035)
		(end 78.625 87.475)
		(width 0.15)
		(layer "F.Cu")
		(net 641)
	)
	(segment
		(start 73.89 92.37)
		(end 73.22 93.04)
		(width 0.15)
		(layer "F.Cu")
		(net 641)
	)
	(segment
		(start 79.23 85.4)
		(end 78.8 85.4)
		(width 0.15)
		(layer "F.Cu")
		(net 641)
	)
	(segment
		(start 78.8 85.4)
		(end 78.7 85.3)
		(width 0.15)
		(layer "F.Cu")
		(net 641)
	)
	(segment
		(start 78.7 84.79)
		(end 78.63 84.72)
		(width 0.15)
		(layer "F.Cu")
		(net 641)
	)
	(segment
		(start 78.7 85.3)
		(end 78.7 84.79)
		(width 0.15)
		(layer "F.Cu")
		(net 641)
	)
	(segment
		(start 78.7 85.5)
		(end 78.7 86.96)
		(width 0.15)
		(layer "F.Cu")
		(net 641)
	)
	(segment
		(start 78.7 86.96)
		(end 78.625 87.035)
		(width 0.15)
		(layer "F.Cu")
		(net 641)
	)
	(via
		(at 73.22 93.04)
		(size 0.45)
		(drill 0.1)
		(layers "F.Cu" "B.Cu")
		(net 641)
	)
	(via
		(at 78.63 84.72)
		(size 0.45)
		(drill 0.1)
		(layers "F.Cu" "B.Cu")
		(net 641)
	)
	(segment
		(start 74.89 91.37)
		(end 73.22 93.04)
		(width 0.15)
		(layer "In5.Cu")
		(net 641)
	)
	(segment
		(start 78.63 84.72)
		(end 77.59 85.76)
		(width 0.15)
		(layer "In5.Cu")
		(net 641)
	)
	(segment
		(start 76.48 85.76)
		(end 74.89 87.35)
		(width 0.15)
		(layer "In5.Cu")
		(net 641)
	)
	(segment
		(start 77.59 85.76)
		(end 76.48 85.76)
		(width 0.15)
		(layer "In5.Cu")
		(net 641)
	)
	(segment
		(start 74.89 87.35)
		(end 74.89 91.37)
		(width 0.15)
		(layer "In5.Cu")
		(net 641)
	)
	(segment
		(start 79.6525 90.9425)
		(end 80.23 91.52)
		(width 0.15)
		(layer "F.Cu")
		(net 642)
	)
	(segment
		(start 79.47 90.39)
		(end 79.6525 90.5725)
		(width 0.15)
		(layer "F.Cu")
		(net 642)
	)
	(segment
		(start 79.6525 90.5725)
		(end 79.6525 90.9425)
		(width 0.15)
		(layer "F.Cu")
		(net 642)
	)
	(segment
		(start 79.09 90.39)
		(end 79.47 90.39)
		(width 0.15)
		(layer "F.Cu")
		(net 642)
	)
	(segment
		(start 54.95 82.1)
		(end 54.25 82.1)
		(width 0.15)
		(layer "B.Cu")
		(net 644)
	)
	(segment
		(start 53.95 81.8)
		(end 53.75 81.8)
		(width 0.15)
		(layer "B.Cu")
		(net 644)
	)
	(segment
		(start 55.12 82.27)
		(end 54.95 82.1)
		(width 0.15)
		(layer "B.Cu")
		(net 644)
	)
	(segment
		(start 54.25 82.1)
		(end 53.95 81.8)
		(width 0.15)
		(layer "B.Cu")
		(net 644)
	)
	(segment
		(start 54.175 109.560322)
		(end 54.585322 109.15)
		(width 0.15)
		(layer "B.Cu")
		(net 646)
	)
	(segment
		(start 54.585322 109.15)
		(end 56.665 109.15)
		(width 0.15)
		(layer "B.Cu")
		(net 646)
	)
	(segment
		(start 54.175 110.55)
		(end 54.175 109.560322)
		(width 0.15)
		(layer "B.Cu")
		(net 646)
	)
	(segment
		(start 53.725 111.45)
		(end 53.725 111)
		(width 0.15)
		(layer "B.Cu")
		(net 646)
	)
	(segment
		(start 53.725 111)
		(end 54.175 110.55)
		(width 0.15)
		(layer "B.Cu")
		(net 646)
	)
	(segment
		(start 56.665 109.15)
		(end 56.965 109.45)
		(width 0.15)
		(layer "B.Cu")
		(net 646)
	)
	(segment
		(start 55.2 112.925)
		(end 56.49 112.925)
		(width 0.13)
		(layer "B.Cu")
		(net 647)
	)
	(segment
		(start 56.49 112.925)
		(end 56.965 112.45)
		(width 0.13)
		(layer "B.Cu")
		(net 647)
	)
	(segment
		(start 54.45 111.375)
		(end 54.45 109.67423)
		(width 0.15)
		(layer "B.Cu")
		(net 648)
	)
	(segment
		(start 54.375 111.45)
		(end 54.45 111.375)
		(width 0.15)
		(layer "B.Cu")
		(net 648)
	)
	(segment
		(start 54.67423 109.45)
		(end 55.965 109.45)
		(width 0.15)
		(layer "B.Cu")
		(net 648)
	)
	(segment
		(start 54.45 109.67423)
		(end 54.67423 109.45)
		(width 0.15)
		(layer "B.Cu")
		(net 648)
	)
	(segment
		(start 55.965 109.45)
		(end 56.965 110.45)
		(width 0.15)
		(layer "B.Cu")
		(net 648)
	)
	(segment
		(start 56.575 114.225)
		(end 55.2 114.225)
		(width 0.15)
		(layer "B.Cu")
		(net 649)
	)
	(segment
		(start 56.965 113.835)
		(end 56.575 114.225)
		(width 0.15)
		(layer "B.Cu")
		(net 649)
	)
	(segment
		(start 56.965 113.45)
		(end 56.965 113.835)
		(width 0.15)
		(layer "B.Cu")
		(net 649)
	)
	(segment
		(start 40.415 103.691)
		(end 40.565 103.541)
		(width 0.15)
		(layer "F.Cu")
		(net 650)
	)
	(segment
		(start 41.459 105.185)
		(end 41.615 105.029)
		(width 0.15)
		(layer "F.Cu")
		(net 650)
	)
	(segment
		(start 40.565 103.541)
		(end 41.63 103.541)
		(width 0.15)
		(layer "F.Cu")
		(net 650)
	)
	(segment
		(start 41.615 105.029)
		(end 41.615 103.647)
		(width 0.15)
		(layer "F.Cu")
		(net 650)
	)
	(segment
		(start 41.7 102.68)
		(end 41.635 102.745)
		(width 0.15)
		(layer "F.Cu")
		(net 650)
	)
	(segment
		(start 40.415 104.506)
		(end 40.415 103.691)
		(width 0.15)
		(layer "F.Cu")
		(net 650)
	)
	(segment
		(start 39.961 104.511)
		(end 39.15 103.7)
		(width 0.15)
		(layer "F.Cu")
		(net 650)
	)
	(segment
		(start 41.7 102.68)
		(end 41.7 99.45)
		(width 0.15)
		(layer "F.Cu")
		(net 650)
	)
	(segment
		(start 39.15 103.7)
		(end 38.68 103.7)
		(width 0.15)
		(layer "F.Cu")
		(net 650)
	)
	(segment
		(start 41.635 102.745)
		(end 41.635 103.541)
		(width 0.15)
		(layer "F.Cu")
		(net 650)
	)
	(segment
		(start 40.415 104.511)
		(end 39.961 104.511)
		(width 0.15)
		(layer "F.Cu")
		(net 650)
	)
	(segment
		(start 120.55 109.45)
		(end 120.55 111.8586)
		(width 0.15)
		(layer "F.Cu")
		(net 651)
	)
	(segment
		(start 115.6 104.5)
		(end 120.55 109.45)
		(width 0.15)
		(layer "F.Cu")
		(net 651)
	)
	(segment
		(start 113.5 104.5)
		(end 115.6 104.5)
		(width 0.15)
		(layer "F.Cu")
		(net 651)
	)
	(segment
		(start 111.22 89.78)
		(end 111.22 99.12)
		(width 0.15)
		(layer "F.Cu")
		(net 651)
	)
	(segment
		(start 112.15 100.05)
		(end 112.15 102.688908)
		(width 0.15)
		(layer "F.Cu")
		(net 651)
	)
	(segment
		(start 112.35 88.65)
		(end 111.22 89.78)
		(width 0.15)
		(layer "F.Cu")
		(net 651)
	)
	(segment
		(start 113 104)
		(end 113.5 104.5)
		(width 0.15)
		(layer "F.Cu")
		(net 651)
	)
	(segment
		(start 112.15 102.688908)
		(end 113 103.538908)
		(width 0.15)
		(layer "F.Cu")
		(net 651)
	)
	(segment
		(start 113 103.538908)
		(end 113 104)
		(width 0.15)
		(layer "F.Cu")
		(net 651)
	)
	(segment
		(start 111.22 99.12)
		(end 112.15 100.05)
		(width 0.15)
		(layer "F.Cu")
		(net 651)
	)
	(segment
		(start 117 88.65)
		(end 112.35 88.65)
		(width 0.15)
		(layer "F.Cu")
		(net 651)
	)
	(segment
		(start 130.43 101.92)
		(end 128.4 101.92)
		(width 0.15)
		(layer "F.Cu")
		(net 652)
	)
	(segment
		(start 130.55 101.8)
		(end 130.43 101.92)
		(width 0.15)
		(layer "F.Cu")
		(net 652)
	)
	(segment
		(start 118.05 89.65)
		(end 117 89.65)
		(width 0.15)
		(layer "F.Cu")
		(net 652)
	)
	(segment
		(start 118.85 90.45)
		(end 118.05 89.65)
		(width 0.15)
		(layer "F.Cu")
		(net 652)
	)
	(segment
		(start 119.45 90.45)
		(end 118.85 90.45)
		(width 0.15)
		(layer "F.Cu")
		(net 652)
	)
	(segment
		(start 130.55 101.25)
		(end 130.55 101.8)
		(width 0.15)
		(layer "F.Cu")
		(net 652)
	)
	(via
		(at 119.45 90.45)
		(size 0.45)
		(drill 0.1)
		(layers "F.Cu" "B.Cu")
		(net 652)
	)
	(via
		(at 128.4 101.92)
		(size 0.45)
		(drill 0.1)
		(layers "F.Cu" "B.Cu")
		(net 652)
	)
	(segment
		(start 119.9 96.25)
		(end 125.57 101.92)
		(width 0.125)
		(layer "B.Cu")
		(net 652)
	)
	(segment
		(start 119.65 90.45)
		(end 119.9 90.7)
		(width 0.125)
		(layer "B.Cu")
		(net 652)
	)
	(segment
		(start 125.57 101.92)
		(end 128.4 101.92)
		(width 0.125)
		(layer "B.Cu")
		(net 652)
	)
	(segment
		(start 119.9 90.7)
		(end 119.9 96.25)
		(width 0.125)
		(layer "B.Cu")
		(net 652)
	)
	(segment
		(start 119.45 90.45)
		(end 119.65 90.45)
		(width 0.125)
		(layer "B.Cu")
		(net 652)
	)
	(segment
		(start 130.55 105.165)
		(end 130.55 102.65)
		(width 0.15)
		(layer "F.Cu")
		(net 653)
	)
	(segment
		(start 128.9 107.415)
		(end 128.9 106.815)
		(width 0.15)
		(layer "F.Cu")
		(net 653)
	)
	(segment
		(start 128.9 106.815)
		(end 130.55 105.165)
		(width 0.15)
		(layer "F.Cu")
		(net 653)
	)
	(segment
		(start 60.515 121.9)
		(end 59.5 121.9)
		(width 0.15)
		(layer "F.Cu")
		(net 654)
	)
	(segment
		(start 59.3 122.1)
		(end 59.3 122.7)
		(width 0.15)
		(layer "F.Cu")
		(net 654)
	)
	(segment
		(start 59.5 121.9)
		(end 59.3 122.1)
		(width 0.15)
		(layer "F.Cu")
		(net 654)
	)
	(segment
		(start 63.95 107.35)
		(end 63.95 108.75)
		(width 0.15)
		(layer "F.Cu")
		(net 657)
	)
	(segment
		(start 62.085 106)
		(end 62.6 106)
		(width 0.15)
		(layer "F.Cu")
		(net 657)
	)
	(segment
		(start 62.6 106)
		(end 63.95 107.35)
		(width 0.15)
		(layer "F.Cu")
		(net 657)
	)
	(segment
		(start 62.085 105)
		(end 62.085 106)
		(width 0.15)
		(layer "F.Cu")
		(net 657)
	)
	(segment
		(start 140.215 122.215)
		(end 140.215 123)
		(width 0.15)
		(layer "B.Cu")
		(net 658)
	)
	(segment
		(start 140 122)
		(end 140.215 122.215)
		(width 0.15)
		(layer "B.Cu")
		(net 658)
	)
	(segment
		(start 140.58 123.58)
		(end 140.58 124.17)
		(width 0.15)
		(layer "B.Cu")
		(net 658)
	)
	(segment
		(start 140.215 123)
		(end 140.215 123.215)
		(width 0.15)
		(layer "B.Cu")
		(net 658)
	)
	(segment
		(start 140.215 123.215)
		(end 140.58 123.58)
		(width 0.15)
		(layer "B.Cu")
		(net 658)
	)
	(segment
		(start 139.285 122)
		(end 140 122)
		(width 0.15)
		(layer "B.Cu")
		(net 658)
	)
	(segment
		(start 77.097323 73.030136)
		(end 76.652459 73.475)
		(width 0.15)
		(layer "F.Cu")
		(net 659)
	)
	(segment
		(start 77.097323 72.005136)
		(end 77.097323 73.030136)
		(width 0.15)
		(layer "F.Cu")
		(net 659)
	)
	(segment
		(start 130.3 123.05)
		(end 130.3 122.5)
		(width 0.15)
		(layer "F.Cu")
		(net 659)
	)
	(segment
		(start 74 75.35)
		(end 73 75.35)
		(width 0.15)
		(layer "F.Cu")
		(net 659)
	)
	(segment
		(start 74 75.35)
		(end 75.875 73.475)
		(width 0.15)
		(layer "F.Cu")
		(net 659)
	)
	(segment
		(start 76.652459 73.475)
		(end 75.875 73.475)
		(width 0.15)
		(layer "F.Cu")
		(net 659)
	)
	(via
		(at 130.3 122.5)
		(size 0.45)
		(drill 0.1)
		(layers "F.Cu" "B.Cu")
		(net 659)
	)
	(via
		(at 54.281432 74.274878)
		(size 0.45)
		(drill 0.1)
		(layers "F.Cu" "B.Cu")
		(net 659)
	)
	(via
		(at 73 75.35)
		(size 0.45)
		(drill 0.1)
		(layers "F.Cu" "B.Cu")
		(net 659)
	)
	(segment
		(start 64.575 126.675)
		(end 65.1 127.2)
		(width 0.125)
		(layer "In3.Cu")
		(net 659)
	)
	(segment
		(start 52.78094 114.38094)
		(end 60.925 114.38094)
		(width 0.125)
		(layer "In3.Cu")
		(net 659)
	)
	(segment
		(start 64.467837 117.143503)
		(end 64.537758 117.495036)
		(width 0.125)
		(layer "In3.Cu")
		(net 659)
	)
	(segment
		(start 106.75 126.15)
		(end 107.5 126.9)
		(width 0.125)
		(layer "In3.Cu")
		(net 659)
	)
	(segment
		(start 51.95 113.55)
		(end 52.78094 114.38094)
		(width 0.125)
		(layer "In3.Cu")
		(net 659)
	)
	(segment
		(start 51.41 97.64)
		(end 51.95 98.18)
		(width 0.125)
		(layer "In3.Cu")
		(net 659)
	)
	(segment
		(start 65.1 127.2)
		(end 86.7 127.2)
		(width 0.125)
		(layer "In3.Cu")
		(net 659)
	)
	(segment
		(start 64.226639 116.469378)
		(end 64.363797 116.800516)
		(width 0.125)
		(layer "In3.Cu")
		(net 659)
	)
	(segment
		(start 54.1 74.52)
		(end 54.1 79.796446)
		(width 0.125)
		(layer "In3.Cu")
		(net 659)
	)
	(segment
		(start 63.631182 115.578198)
		(end 63.858559 115.855262)
		(width 0.125)
		(layer "In3.Cu")
		(net 659)
	)
	(segment
		(start 64.537758 117.495036)
		(end 64.572885 117.85173)
		(width 0.125)
		(layer "In3.Cu")
		(net 659)
	)
	(segment
		(start 63.858559 115.855262)
		(end 64.057684 116.153279)
		(width 0.125)
		(layer "In3.Cu")
		(net 659)
	)
	(segment
		(start 62.155425 114.592131)
		(end 62.486561 114.729293)
		(width 0.125)
		(layer "In3.Cu")
		(net 659)
	)
	(segment
		(start 51.41 82.486446)
		(end 51.41 97.64)
		(width 0.125)
		(layer "In3.Cu")
		(net 659)
	)
	(segment
		(start 107.5 126.9)
		(end 128.1 126.9)
		(width 0.125)
		(layer "In3.Cu")
		(net 659)
	)
	(segment
		(start 61.10421 114.383029)
		(end 61.460905 114.418161)
		(width 0.125)
		(layer "In3.Cu")
		(net 659)
	)
	(segment
		(start 54.1 79.796446)
		(end 51.41 82.486446)
		(width 0.125)
		(layer "In3.Cu")
		(net 659)
	)
	(segment
		(start 64.575 118.03094)
		(end 64.575 126.675)
		(width 0.125)
		(layer "In3.Cu")
		(net 659)
	)
	(segment
		(start 51.95 98.18)
		(end 51.95 113.55)
		(width 0.125)
		(layer "In3.Cu")
		(net 659)
	)
	(segment
		(start 54.281432 74.274878)
		(end 54.281432 74.338568)
		(width 0.125)
		(layer "In3.Cu")
		(net 659)
	)
	(segment
		(start 62.486561 114.729293)
		(end 62.802659 114.898253)
		(width 0.125)
		(layer "In3.Cu")
		(net 659)
	)
	(segment
		(start 61.460905 114.418161)
		(end 61.812438 114.488086)
		(width 0.125)
		(layer "In3.Cu")
		(net 659)
	)
	(segment
		(start 86.7 127.2)
		(end 87.75 126.15)
		(width 0.125)
		(layer "In3.Cu")
		(net 659)
	)
	(segment
		(start 61.812438 114.488086)
		(end 62.155425 114.592131)
		(width 0.125)
		(layer "In3.Cu")
		(net 659)
	)
	(segment
		(start 130.6 122.8)
		(end 130.3 122.5)
		(width 0.125)
		(layer "In3.Cu")
		(net 659)
	)
	(segment
		(start 87.75 126.15)
		(end 106.75 126.15)
		(width 0.125)
		(layer "In3.Cu")
		(net 659)
	)
	(segment
		(start 64.572885 117.85173)
		(end 64.575 118.03094)
		(width 0.125)
		(layer "In3.Cu")
		(net 659)
	)
	(segment
		(start 62.802659 114.898253)
		(end 63.100673 115.097383)
		(width 0.125)
		(layer "In3.Cu")
		(net 659)
	)
	(segment
		(start 130.6 124.4)
		(end 130.6 122.8)
		(width 0.125)
		(layer "In3.Cu")
		(net 659)
	)
	(segment
		(start 54.281432 74.338568)
		(end 54.1 74.52)
		(width 0.125)
		(layer "In3.Cu")
		(net 659)
	)
	(segment
		(start 128.1 126.9)
		(end 130.6 124.4)
		(width 0.125)
		(layer "In3.Cu")
		(net 659)
	)
	(segment
		(start 64.363797 116.800516)
		(end 64.467837 117.143503)
		(width 0.125)
		(layer "In3.Cu")
		(net 659)
	)
	(segment
		(start 64.057684 116.153279)
		(end 64.226639 116.469378)
		(width 0.125)
		(layer "In3.Cu")
		(net 659)
	)
	(segment
		(start 63.100673 115.097383)
		(end 63.377735 115.324764)
		(width 0.125)
		(layer "In3.Cu")
		(net 659)
	)
	(segment
		(start 63.50594 115.45)
		(end 63.631182 115.578198)
		(width 0.125)
		(layer "In3.Cu")
		(net 659)
	)
	(segment
		(start 60.925 114.38094)
		(end 61.10421 114.383029)
		(width 0.125)
		(layer "In3.Cu")
		(net 659)
	)
	(segment
		(start 63.377735 115.324764)
		(end 63.50594 115.45)
		(width 0.125)
		(layer "In3.Cu")
		(net 659)
	)
	(segment
		(start 55.106554 75.1)
		(end 54.281432 74.274878)
		(width 0.15)
		(layer "In5.Cu")
		(net 659)
	)
	(segment
		(start 73 75.35)
		(end 72.75 75.1)
		(width 0.15)
		(layer "In5.Cu")
		(net 659)
	)
	(segment
		(start 72.75 75.1)
		(end 55.106554 75.1)
		(width 0.15)
		(layer "In5.Cu")
		(net 659)
	)
	(segment
		(start 130.3 123.381)
		(end 130.3 122.5)
		(width 0.15)
		(layer "B.Cu")
		(net 659)
	)
	(segment
		(start 130.15 123.531)
		(end 130.3 123.381)
		(width 0.15)
		(layer "B.Cu")
		(net 659)
	)
	(segment
		(start 74.176041 74.75)
		(end 75.726041 73.2)
		(width 0.15)
		(layer "F.Cu")
		(net 660)
	)
	(segment
		(start 76.597323 73.030136)
		(end 76.427459 73.2)
		(width 0.15)
		(layer "F.Cu")
		(net 660)
	)
	(segment
		(start 76.597323 72.005136)
		(end 76.597323 73.030136)
		(width 0.15)
		(layer "F.Cu")
		(net 660)
	)
	(segment
		(start 76.427459 73.2)
		(end 75.726041 73.2)
		(width 0.15)
		(layer "F.Cu")
		(net 660)
	)
	(segment
		(start 131.25 123.05)
		(end 131.25 122.55)
		(width 0.15)
		(layer "F.Cu")
		(net 660)
	)
	(segment
		(start 74.176041 74.75)
		(end 73 74.75)
		(width 0.15)
		(layer "F.Cu")
		(net 660)
	)
	(segment
		(start 131.25 122.55)
		(end 131.3 122.5)
		(width 0.15)
		(layer "F.Cu")
		(net 660)
	)
	(via
		(at 73 74.75)
		(size 0.45)
		(drill 0.1)
		(layers "F.Cu" "B.Cu")
		(net 660)
	)
	(via
		(at 54.4755 73.734147)
		(size 0.45)
		(drill 0.1)
		(layers "F.Cu" "B.Cu")
		(net 660)
	)
	(via
		(at 131.3 122.5)
		(size 0.45)
		(drill 0.1)
		(layers "F.Cu" "B.Cu")
		(net 660)
	)
	(segment
		(start 131 124.4)
		(end 131 122.8)
		(width 0.125)
		(layer "In3.Cu")
		(net 660)
	)
	(segment
		(start 107.4 127.2)
		(end 128.2 127.2)
		(width 0.125)
		(layer "In3.Cu")
		(net 660)
	)
	(segment
		(start 87.9 126.4)
		(end 106.6 126.4)
		(width 0.125)
		(layer "In3.Cu")
		(net 660)
	)
	(segment
		(start 53.85 79.692892)
		(end 51.11 82.432892)
		(width 0.125)
		(layer "In3.Cu")
		(net 660)
	)
	(segment
		(start 51.11 82.432892)
		(end 51.11 97.84)
		(width 0.125)
		(layer "In3.Cu")
		(net 660)
	)
	(segment
		(start 128.2 127.2)
		(end 131 124.4)
		(width 0.125)
		(layer "In3.Cu")
		(net 660)
	)
	(segment
		(start 63.08868 115.55868)
		(end 63.396321 115.866321)
		(width 0.125)
		(layer "In3.Cu")
		(net 660)
	)
	(segment
		(start 52.58 114.68)
		(end 60.967359 114.68)
		(width 0.125)
		(layer "In3.Cu")
		(net 660)
	)
	(segment
		(start 64.8 127.5)
		(end 86.8 127.5)
		(width 0.125)
		(layer "In3.Cu")
		(net 660)
	)
	(segment
		(start 54.471353 73.73)
		(end 54.17 73.73)
		(width 0.125)
		(layer "In3.Cu")
		(net 660)
	)
	(segment
		(start 131 122.8)
		(end 131.3 122.5)
		(width 0.125)
		(layer "In3.Cu")
		(net 660)
	)
	(segment
		(start 54.4755 73.734147)
		(end 54.471353 73.73)
		(width 0.125)
		(layer "In3.Cu")
		(net 660)
	)
	(segment
		(start 64.275 117.987641)
		(end 64.275 126.975)
		(width 0.125)
		(layer "In3.Cu")
		(net 660)
	)
	(segment
		(start 51.65 98.38)
		(end 51.65 113.75)
		(width 0.125)
		(layer "In3.Cu")
		(net 660)
	)
	(segment
		(start 51.11 97.84)
		(end 51.65 98.38)
		(width 0.125)
		(layer "In3.Cu")
		(net 660)
	)
	(segment
		(start 106.6 126.4)
		(end 107.4 127.2)
		(width 0.125)
		(layer "In3.Cu")
		(net 660)
	)
	(segment
		(start 53.85 74.05)
		(end 53.85 79.692892)
		(width 0.125)
		(layer "In3.Cu")
		(net 660)
	)
	(segment
		(start 54.17 73.73)
		(end 53.85 74.05)
		(width 0.125)
		(layer "In3.Cu")
		(net 660)
	)
	(segment
		(start 51.65 113.75)
		(end 52.58 114.68)
		(width 0.125)
		(layer "In3.Cu")
		(net 660)
	)
	(segment
		(start 86.8 127.5)
		(end 87.9 126.4)
		(width 0.125)
		(layer "In3.Cu")
		(net 660)
	)
	(segment
		(start 64.275 126.975)
		(end 64.8 127.5)
		(width 0.125)
		(layer "In3.Cu")
		(net 660)
	)
	(arc
		(start 63.396321 115.866321)
		(mid 64.046639 116.839591)
		(end 64.275 117.987641)
		(width 0.125)
		(layer "In3.Cu")
		(net 660)
	)
	(arc
		(start 60.967359 114.68)
		(mid 62.11541 114.908362)
		(end 63.08868 115.55868)
		(width 0.125)
		(layer "In3.Cu")
		(net 660)
	)
	(segment
		(start 72.95 74.8)
		(end 73 74.75)
		(width 0.15)
		(layer "In5.Cu")
		(net 660)
	)
	(segment
		(start 54.4755 73.734147)
		(end 55.541353 74.8)
		(width 0.15)
		(layer "In5.Cu")
		(net 660)
	)
	(segment
		(start 55.541353 74.8)
		(end 72.95 74.8)
		(width 0.15)
		(layer "In5.Cu")
		(net 660)
	)
	(segment
		(start 131.15 123.531)
		(end 131.3 123.381)
		(width 0.15)
		(layer "B.Cu")
		(net 660)
	)
	(segment
		(start 131.3 123.381)
		(end 131.3 122.5)
		(width 0.15)
		(layer "B.Cu")
		(net 660)
	)
	(segment
		(start 136.315 124.44)
		(end 136.7 124.825)
		(width 0.15)
		(layer "B.Cu")
		(net 661)
	)
	(segment
		(start 136.315 124.06)
		(end 136.315 124.44)
		(width 0.15)
		(layer "B.Cu")
		(net 661)
	)
	(segment
		(start 136.7 124.825)
		(end 136.7 125.3)
		(width 0.15)
		(layer "B.Cu")
		(net 661)
	)
	(segment
		(start 132.44 125.24)
		(end 132.15 124.95)
		(width 0.3)
		(layer "B.Cu")
		(net 662)
	)
	(segment
		(start 135.95 123.35)
		(end 134.06 125.24)
		(width 0.3)
		(layer "B.Cu")
		(net 662)
	)
	(segment
		(start 138.12 125.47)
		(end 137.285 124.635)
		(width 0.3)
		(layer "B.Cu")
		(net 662)
	)
	(segment
		(start 137.285 124.635)
		(end 137.285 123.61)
		(width 0.3)
		(layer "B.Cu")
		(net 662)
	)
	(segment
		(start 138.48 125.47)
		(end 138.12 125.47)
		(width 0.3)
		(layer "B.Cu")
		(net 662)
	)
	(segment
		(start 134.06 125.24)
		(end 132.44 125.24)
		(width 0.3)
		(layer "B.Cu")
		(net 662)
	)
	(segment
		(start 137.025 123.35)
		(end 135.95 123.35)
		(width 0.3)
		(layer "B.Cu")
		(net 662)
	)
	(segment
		(start 137.285 123.61)
		(end 137.025 123.35)
		(width 0.3)
		(layer "B.Cu")
		(net 662)
	)
	(segment
		(start 132.15 124.95)
		(end 132.15 123.531)
		(width 0.3)
		(layer "B.Cu")
		(net 662)
	)
	(segment
		(start 93.0075 91.45)
		(end 93.1325 91.325)
		(width 0.125)
		(layer "B.Cu")
		(net 663)
	)
	(segment
		(start 94.715 91.575)
		(end 95.065 91.925)
		(width 0.125)
		(layer "B.Cu")
		(net 663)
	)
	(segment
		(start 93.1325 91.325)
		(end 94.038222 91.325)
		(width 0.125)
		(layer "B.Cu")
		(net 663)
	)
	(segment
		(start 94.288222 91.575)
		(end 94.715 91.575)
		(width 0.125)
		(layer "B.Cu")
		(net 663)
	)
	(segment
		(start 94.038222 91.325)
		(end 94.288222 91.575)
		(width 0.125)
		(layer "B.Cu")
		(net 663)
	)
	(segment
		(start 93.1325 92.825)
		(end 93.0075 92.95)
		(width 0.125)
		(layer "B.Cu")
		(net 664)
	)
	(segment
		(start 94.603222 93.1)
		(end 94.328222 92.825)
		(width 0.125)
		(layer "B.Cu")
		(net 664)
	)
	(segment
		(start 94.328222 92.825)
		(end 93.1325 92.825)
		(width 0.125)
		(layer "B.Cu")
		(net 664)
	)
	(segment
		(start 96.965 93.45)
		(end 96.615 93.1)
		(width 0.125)
		(layer "B.Cu")
		(net 664)
	)
	(segment
		(start 96.615 93.1)
		(end 94.603222 93.1)
		(width 0.125)
		(layer "B.Cu")
		(net 664)
	)
	(segment
		(start 94.438222 90.075)
		(end 93.1325 90.075)
		(width 0.125)
		(layer "B.Cu")
		(net 665)
	)
	(segment
		(start 93.1325 90.075)
		(end 93.0075 89.95)
		(width 0.125)
		(layer "B.Cu")
		(net 665)
	)
	(segment
		(start 96.965 89.25)
		(end 96.615 89.6)
		(width 0.125)
		(layer "B.Cu")
		(net 665)
	)
	(segment
		(start 94.913222 89.6)
		(end 94.438222 90.075)
		(width 0.125)
		(layer "B.Cu")
		(net 665)
	)
	(segment
		(start 96.615 89.6)
		(end 94.913222 89.6)
		(width 0.125)
		(layer "B.Cu")
		(net 665)
	)
	(segment
		(start 94.715 91.325)
		(end 95.065 90.975)
		(width 0.125)
		(layer "B.Cu")
		(net 666)
	)
	(segment
		(start 93.1325 91.075)
		(end 94.141778 91.075)
		(width 0.125)
		(layer "B.Cu")
		(net 666)
	)
	(segment
		(start 94.391778 91.325)
		(end 94.715 91.325)
		(width 0.125)
		(layer "B.Cu")
		(net 666)
	)
	(segment
		(start 94.141778 91.075)
		(end 94.391778 91.325)
		(width 0.125)
		(layer "B.Cu")
		(net 666)
	)
	(segment
		(start 93.0075 90.95)
		(end 93.1325 91.075)
		(width 0.125)
		(layer "B.Cu")
		(net 666)
	)
	(segment
		(start 96.615 92.85)
		(end 94.706778 92.85)
		(width 0.125)
		(layer "B.Cu")
		(net 667)
	)
	(segment
		(start 94.431778 92.575)
		(end 93.1325 92.575)
		(width 0.125)
		(layer "B.Cu")
		(net 667)
	)
	(segment
		(start 93.1325 92.575)
		(end 93.0075 92.45)
		(width 0.125)
		(layer "B.Cu")
		(net 667)
	)
	(segment
		(start 94.706778 92.85)
		(end 94.431778 92.575)
		(width 0.125)
		(layer "B.Cu")
		(net 667)
	)
	(segment
		(start 96.965 92.5)
		(end 96.615 92.85)
		(width 0.125)
		(layer "B.Cu")
		(net 667)
	)
	(segment
		(start 90.86 83.15)
		(end 91.233222 83.15)
		(width 0.125)
		(layer "B.Cu")
		(net 668)
	)
	(segment
		(start 91.233222 83.15)
		(end 91.695 83.611778)
		(width 0.125)
		(layer "B.Cu")
		(net 668)
	)
	(segment
		(start 90.51 83.5)
		(end 90.86 83.15)
		(width 0.125)
		(layer "B.Cu")
		(net 668)
	)
	(segment
		(start 91.695 87.3875)
		(end 91.57 87.5125)
		(width 0.125)
		(layer "B.Cu")
		(net 668)
	)
	(segment
		(start 91.695 83.611778)
		(end 91.695 87.3875)
		(width 0.125)
		(layer "B.Cu")
		(net 668)
	)
	(segment
		(start 91.336778 82.9)
		(end 91.945 83.508222)
		(width 0.125)
		(layer "B.Cu")
		(net 669)
	)
	(segment
		(start 91.945 87.3875)
		(end 92.07 87.5125)
		(width 0.125)
		(layer "B.Cu")
		(net 669)
	)
	(segment
		(start 90.51 82.55)
		(end 90.86 82.9)
		(width 0.125)
		(layer "B.Cu")
		(net 669)
	)
	(segment
		(start 90.86 82.9)
		(end 91.336778 82.9)
		(width 0.125)
		(layer "B.Cu")
		(net 669)
	)
	(segment
		(start 91.945 83.508222)
		(end 91.945 87.3875)
		(width 0.125)
		(layer "B.Cu")
		(net 669)
	)
	(segment
		(start 64.305 98.585)
		(end 64.3 98.585)
		(width 0.155)
		(layer "B.Cu")
		(net 670)
	)
	(segment
		(start 64.5 98.78)
		(end 64.305 98.585)
		(width 0.155)
		(layer "B.Cu")
		(net 670)
	)
	(segment
		(start 64.5 99.75)
		(end 64.5 98.78)
		(width 0.155)
		(layer "B.Cu")
		(net 670)
	)
	(segment
		(start 83.01 123.92)
		(end 83.009 123.919)
		(width 0.15)
		(layer "F.Cu")
		(net 671)
	)
	(segment
		(start 83.009 123.919)
		(end 83.009 122.4)
		(width 0.125)
		(layer "F.Cu")
		(net 671)
	)
	(via
		(at 83.01 123.92)
		(size 0.45)
		(drill 0.1)
		(layers "F.Cu" "B.Cu")
		(net 671)
	)
	(segment
		(start 83.27 124.18)
		(end 83.01 123.92)
		(width 0.125)
		(layer "B.Cu")
		(net 671)
	)
	(segment
		(start 83.27 125.2585)
		(end 83.27 124.18)
		(width 0.125)
		(layer "B.Cu")
		(net 671)
	)
	(segment
		(start 83.01 123.92)
		(end 83.01 122.408)
		(width 0.125)
		(layer "B.Cu")
		(net 671)
	)
	(segment
		(start 82.64 125.8885)
		(end 83.27 125.2585)
		(width 0.125)
		(layer "B.Cu")
		(net 671)
	)
	(segment
		(start 62.715 107)
		(end 63.05 107.335)
		(width 0.15)
		(layer "F.Cu")
		(net 672)
	)
	(segment
		(start 63.05 107.335)
		(end 63.05 108.7)
		(width 0.15)
		(layer "F.Cu")
		(net 672)
	)
	(segment
		(start 62.085 107)
		(end 62.715 107)
		(width 0.15)
		(layer "F.Cu")
		(net 672)
	)
	(segment
		(start 66.95 118.065)
		(end 66.5 118.515)
		(width 0.125)
		(layer "F.Cu")
		(net 673)
	)
	(segment
		(start 66.95 116.8)
		(end 66.95 118.065)
		(width 0.125)
		(layer "F.Cu")
		(net 673)
	)
	(segment
		(start 66.95 116.8)
		(end 65.55 116.8)
		(width 0.125)
		(layer "F.Cu")
		(net 673)
	)
	(segment
		(start 65.55 116.8)
		(end 65.535 116.785)
		(width 0.125)
		(layer "F.Cu")
		(net 673)
	)
	(segment
		(start 94.37 95.71)
		(end 93.83 95.17)
		(width 0.125)
		(layer "F.Cu")
		(net 677)
	)
	(segment
		(start 94.37 97.13)
		(end 94.37 95.71)
		(width 0.125)
		(layer "F.Cu")
		(net 677)
	)
	(segment
		(start 93.83 95.17)
		(end 93.83 93.73)
		(width 0.15)
		(layer "F.Cu")
		(net 677)
	)
	(segment
		(start 91.78 99.6)
		(end 92.71 99.6)
		(width 0.125)
		(layer "F.Cu")
		(net 677)
	)
	(segment
		(start 93.83 93.73)
		(end 93.35 93.25)
		(width 0.15)
		(layer "F.Cu")
		(net 677)
	)
	(segment
		(start 93.46 98.85)
		(end 93.46 98.04)
		(width 0.125)
		(layer "F.Cu")
		(net 677)
	)
	(segment
		(start 93.46 98.04)
		(end 94.37 97.13)
		(width 0.125)
		(layer "F.Cu")
		(net 677)
	)
	(segment
		(start 92.71 99.6)
		(end 93.46 98.85)
		(width 0.125)
		(layer "F.Cu")
		(net 677)
	)
	(via
		(at 90.6325 99.15)
		(size 0.45)
		(drill 0.1)
		(layers "F.Cu" "B.Cu")
		(net 677)
	)
	(via
		(at 79.4 110.85)
		(size 0.45)
		(drill 0.1)
		(layers "F.Cu" "B.Cu")
		(net 677)
	)
	(via
		(at 91.78 99.6)
		(size 0.45)
		(drill 0.1)
		(layers "F.Cu" "B.Cu")
		(net 677)
	)
	(via
		(at 67.65 95.13)
		(size 0.45)
		(drill 0.1)
		(layers "F.Cu" "B.Cu")
		(net 677)
	)
	(via
		(at 73.401776 102.619668)
		(size 0.45)
		(drill 0.1)
		(layers "F.Cu" "B.Cu")
		(net 677)
	)
	(segment
		(start 67.86 95.34)
		(end 67.86 96.85)
		(width 0.15)
		(layer "In3.Cu")
		(net 677)
	)
	(segment
		(start 75.3125 105.8125)
		(end 74.225 104.725)
		(width 0.15)
		(layer "In3.Cu")
		(net 677)
	)
	(segment
		(start 67.86 96.85)
		(end 69.01 98)
		(width 0.15)
		(layer "In3.Cu")
		(net 677)
	)
	(segment
		(start 74.225 104.725)
		(end 74.225 103.45)
		(width 0.15)
		(layer "In3.Cu")
		(net 677)
	)
	(segment
		(start 79.4 106.2)
		(end 79.0125 105.8125)
		(width 0.15)
		(layer "In3.Cu")
		(net 677)
	)
	(segment
		(start 79.4 110.85)
		(end 79.4 106.2)
		(width 0.15)
		(layer "In3.Cu")
		(net 677)
	)
	(segment
		(start 67.65 95.13)
		(end 67.86 95.34)
		(width 0.15)
		(layer "In3.Cu")
		(net 677)
	)
	(segment
		(start 79.0125 105.8125)
		(end 75.3125 105.8125)
		(width 0.15)
		(layer "In3.Cu")
		(net 677)
	)
	(segment
		(start 73.325 102.625)
		(end 73.4 102.625)
		(width 0.15)
		(layer "In3.Cu")
		(net 677)
	)
	(segment
		(start 69.01 99.61)
		(end 69.6 100.2)
		(width 0.15)
		(layer "In3.Cu")
		(net 677)
	)
	(segment
		(start 69.01 98)
		(end 69.01 99.61)
		(width 0.15)
		(layer "In3.Cu")
		(net 677)
	)
	(segment
		(start 73.4 102.621444)
		(end 73.401776 102.619668)
		(width 0.15)
		(layer "In3.Cu")
		(net 677)
	)
	(segment
		(start 74.225 103.45)
		(end 73.4 102.625)
		(width 0.15)
		(layer "In3.Cu")
		(net 677)
	)
	(segment
		(start 69.6 100.2)
		(end 70.9 100.2)
		(width 0.15)
		(layer "In3.Cu")
		(net 677)
	)
	(segment
		(start 70.9 100.2)
		(end 73.325 102.625)
		(width 0.15)
		(layer "In3.Cu")
		(net 677)
	)
	(segment
		(start 73.4 102.625)
		(end 73.4 102.621444)
		(width 0.15)
		(layer "In3.Cu")
		(net 677)
	)
	(segment
		(start 87.14 103.55)
		(end 74.325 103.55)
		(width 0.15)
		(layer "In5.Cu")
		(net 677)
	)
	(segment
		(start 74.325 103.55)
		(end 73.4 102.625)
		(width 0.15)
		(layer "In5.Cu")
		(net 677)
	)
	(segment
		(start 90.6325 100.0575)
		(end 87.14 103.55)
		(width 0.15)
		(layer "In5.Cu")
		(net 677)
	)
	(segment
		(start 90.6325 99.15)
		(end 90.6325 100.0575)
		(width 0.15)
		(layer "In5.Cu")
		(net 677)
	)
	(segment
		(start 91.33 99.15)
		(end 91.78 99.6)
		(width 0.15)
		(layer "In5.Cu")
		(net 677)
	)
	(segment
		(start 90.6325 99.15)
		(end 91.33 99.15)
		(width 0.15)
		(layer "In5.Cu")
		(net 677)
	)
	(segment
		(start 79.4 111.935)
		(end 79.095 112.24)
		(width 0.15)
		(layer "B.Cu")
		(net 677)
	)
	(segment
		(start 67.65 95.13)
		(end 67.4 95.38)
		(width 0.125)
		(layer "B.Cu")
		(net 677)
	)
	(segment
		(start 79.4 110.85)
		(end 78.075 110.85)
		(width 0.15)
		(layer "B.Cu")
		(net 677)
	)
	(segment
		(start 74.4 111.6)
		(end 73.975 111.175)
		(width 0.15)
		(layer "B.Cu")
		(net 677)
	)
	(segment
		(start 78.075 110.85)
		(end 77.325 111.6)
		(width 0.15)
		(layer "B.Cu")
		(net 677)
	)
	(segment
		(start 90.6325 97.6675)
		(end 91.57 96.73)
		(width 0.15)
		(layer "B.Cu")
		(net 677)
	)
	(segment
		(start 65.31 96.09)
		(end 64.55 96.85)
		(width 0.125)
		(layer "B.Cu")
		(net 677)
	)
	(segment
		(start 67.4 95.38)
		(end 67.4 95.56)
		(width 0.125)
		(layer "B.Cu")
		(net 677)
	)
	(segment
		(start 66.87 96.09)
		(end 65.31 96.09)
		(width 0.125)
		(layer "B.Cu")
		(net 677)
	)
	(segment
		(start 64.55 97.41)
		(end 63.36 98.6)
		(width 0.125)
		(layer "B.Cu")
		(net 677)
	)
	(segment
		(start 79.4 110.85)
		(end 79.4 111.935)
		(width 0.15)
		(layer "B.Cu")
		(net 677)
	)
	(segment
		(start 91.57 96.73)
		(end 91.57 96.3875)
		(width 0.15)
		(layer "B.Cu")
		(net 677)
	)
	(segment
		(start 79.095 114.3)
		(end 79.625 114.83)
		(width 0.15)
		(layer "B.Cu")
		(net 677)
	)
	(segment
		(start 90.6325 99.15)
		(end 90.6325 97.6675)
		(width 0.15)
		(layer "B.Cu")
		(net 677)
	)
	(segment
		(start 67.4 95.56)
		(end 66.87 96.09)
		(width 0.125)
		(layer "B.Cu")
		(net 677)
	)
	(segment
		(start 64.55 96.85)
		(end 64.55 97.41)
		(width 0.125)
		(layer "B.Cu")
		(net 677)
	)
	(segment
		(start 79.095 112.24)
		(end 79.095 114.3)
		(width 0.15)
		(layer "B.Cu")
		(net 677)
	)
	(segment
		(start 77.325 111.6)
		(end 74.4 111.6)
		(width 0.15)
		(layer "B.Cu")
		(net 677)
	)
	(segment
		(start 73.975 111.175)
		(end 73.975 111.11)
		(width 0.15)
		(layer "B.Cu")
		(net 677)
	)
	(segment
		(start 94.3 87.15)
		(end 94.1 87.35)
		(width 0.125)
		(layer "B.Cu")
		(net 678)
	)
	(segment
		(start 95.49 87.15)
		(end 94.3 87.15)
		(width 0.125)
		(layer "B.Cu")
		(net 678)
	)
	(segment
		(start 93.0075 88.45)
		(end 93.75 88.45)
		(width 0.125)
		(layer "B.Cu")
		(net 678)
	)
	(segment
		(start 94.1 87.35)
		(end 94.1 88.1)
		(width 0.125)
		(layer "B.Cu")
		(net 678)
	)
	(segment
		(start 93.75 88.45)
		(end 94.1 88.1)
		(width 0.125)
		(layer "B.Cu")
		(net 678)
	)
	(segment
		(start 89.7 87.188)
		(end 89.7 87.965)
		(width 0.125)
		(layer "F.Cu")
		(net 679)
	)
	(segment
		(start 89.7 87.965)
		(end 89.95 88.215)
		(width 0.125)
		(layer "F.Cu")
		(net 679)
	)
	(via
		(at 89.7 87.188)
		(size 0.45)
		(drill 0.1)
		(layers "F.Cu" "B.Cu")
		(net 679)
	)
	(segment
		(start 89.7 87.188)
		(end 90.038 86.85)
		(width 0.125)
		(layer "B.Cu")
		(net 679)
	)
	(segment
		(start 91.07 87.02)
		(end 91.07 87.5125)
		(width 0.125)
		(layer "B.Cu")
		(net 679)
	)
	(segment
		(start 90.9 86.85)
		(end 91.07 87.02)
		(width 0.125)
		(layer "B.Cu")
		(net 679)
	)
	(segment
		(start 90.038 86.85)
		(end 90.9 86.85)
		(width 0.125)
		(layer "B.Cu")
		(net 679)
	)
	(segment
		(start 89.1 87.35)
		(end 89.1 88.065)
		(width 0.125)
		(layer "F.Cu")
		(net 680)
	)
	(segment
		(start 89.1 88.065)
		(end 88.95 88.215)
		(width 0.125)
		(layer "F.Cu")
		(net 680)
	)
	(via
		(at 89.1 87.35)
		(size 0.45)
		(drill 0.1)
		(layers "F.Cu" "B.Cu")
		(net 680)
	)
	(segment
		(start 90.4825 87.6)
		(end 90.57 87.5125)
		(width 0.125)
		(layer "B.Cu")
		(net 680)
	)
	(segment
		(start 89.1 87.35)
		(end 89.35 87.6)
		(width 0.125)
		(layer "B.Cu")
		(net 680)
	)
	(segment
		(start 89.35 87.6)
		(end 90.4825 87.6)
		(width 0.125)
		(layer "B.Cu")
		(net 680)
	)
	(segment
		(start 67.5 118.515)
		(end 67.5 118.1)
		(width 0.15)
		(layer "F.Cu")
		(net 682)
	)
	(segment
		(start 67.5 118.1)
		(end 67.9 117.7)
		(width 0.15)
		(layer "F.Cu")
		(net 682)
	)
	(segment
		(start 67.9 117.7)
		(end 67.9 116.8)
		(width 0.15)
		(layer "F.Cu")
		(net 682)
	)
	(segment
		(start 41.9 69.8)
		(end 41.5 69.8)
		(width 0.15)
		(layer "B.Cu")
		(net 683)
	)
	(segment
		(start 40.5 69.8)
		(end 41.5 69.8)
		(width 0.15)
		(layer "B.Cu")
		(net 683)
	)
	(segment
		(start 41.9 69.8)
		(end 42.875 69.8)
		(width 0.15)
		(layer "B.Cu")
		(net 683)
	)
	(segment
		(start 41.5 69.8)
		(end 41.6 69.8)
		(width 0.15)
		(layer "B.Cu")
		(net 683)
	)
	(segment
		(start 41.7 71.51)
		(end 41.7 69.9)
		(width 0.15)
		(layer "B.Cu")
		(net 683)
	)
	(segment
		(start 41.8 69.8)
		(end 41.9 69.8)
		(width 0.15)
		(layer "B.Cu")
		(net 683)
	)
	(segment
		(start 41.6 69.8)
		(end 41.7 69.9)
		(width 0.15)
		(layer "B.Cu")
		(net 683)
	)
	(segment
		(start 41.7 69.9)
		(end 41.8 69.8)
		(width 0.15)
		(layer "B.Cu")
		(net 683)
	)
	(segment
		(start 76.395 84.835)
		(end 75.9 84.34)
		(width 0.15)
		(layer "F.Cu")
		(net 684)
	)
	(segment
		(start 77.725 86.895)
		(end 77.275 86.445)
		(width 0.15)
		(layer "F.Cu")
		(net 684)
	)
	(segment
		(start 76.395 85.355)
		(end 76.395 84.835)
		(width 0.15)
		(layer "F.Cu")
		(net 684)
	)
	(segment
		(start 77.275 86.235)
		(end 76.395 85.355)
		(width 0.15)
		(layer "F.Cu")
		(net 684)
	)
	(segment
		(start 77.725 87.475)
		(end 77.725 86.895)
		(width 0.15)
		(layer "F.Cu")
		(net 684)
	)
	(segment
		(start 77.275 86.445)
		(end 77.275 86.235)
		(width 0.15)
		(layer "F.Cu")
		(net 684)
	)
	(segment
		(start 138.32 124.82)
		(end 137.95 124.45)
		(width 0.15)
		(layer "B.Cu")
		(net 685)
	)
	(segment
		(start 137.95 123.365)
		(end 138.315 123)
		(width 0.15)
		(layer "B.Cu")
		(net 685)
	)
	(segment
		(start 138.48 124.82)
		(end 138.32 124.82)
		(width 0.15)
		(layer "B.Cu")
		(net 685)
	)
	(segment
		(start 137.95 124.45)
		(end 137.95 123.365)
		(width 0.15)
		(layer "B.Cu")
		(net 685)
	)
	(segment
		(start 93.875 95.9)
		(end 93.875 95.625)
		(width 0.15)
		(layer "B.Cu")
		(net 686)
	)
	(segment
		(start 92.9 98.015)
		(end 92.9 96.875)
		(width 0.15)
		(layer "B.Cu")
		(net 686)
	)
	(segment
		(start 93.875 95.625)
		(end 93.7 95.45)
		(width 0.15)
		(layer "B.Cu")
		(net 686)
	)
	(segment
		(start 93.7 95.45)
		(end 93.0075 95.45)
		(width 0.15)
		(layer "B.Cu")
		(net 686)
	)
	(segment
		(start 92.9 96.875)
		(end 93.875 95.9)
		(width 0.15)
		(layer "B.Cu")
		(net 686)
	)
	(segment
		(start 77.275 86.915)
		(end 76.85 86.49)
		(width 0.15)
		(layer "F.Cu")
		(net 687)
	)
	(segment
		(start 76.4 85.84)
		(end 75.9 85.34)
		(width 0.15)
		(layer "F.Cu")
		(net 687)
	)
	(segment
		(start 76.85 86.49)
		(end 76.4 86.04)
		(width 0.15)
		(layer "F.Cu")
		(net 687)
	)
	(segment
		(start 76.4 86.04)
		(end 76.4 85.84)
		(width 0.15)
		(layer "F.Cu")
		(net 687)
	)
	(segment
		(start 81.086541 88.016541)
		(end 81.23 88.16)
		(width 0.15)
		(layer "F.Cu")
		(net 687)
	)
	(segment
		(start 81.086541 87.623459)
		(end 81.086541 88.016541)
		(width 0.15)
		(layer "F.Cu")
		(net 687)
	)
	(segment
		(start 77.275 87.475)
		(end 77.275 86.915)
		(width 0.15)
		(layer "F.Cu")
		(net 687)
	)
	(segment
		(start 81.23 88.16)
		(end 81.23 88.65)
		(width 0.15)
		(layer "F.Cu")
		(net 687)
	)
	(via
		(at 76.85 86.49)
		(size 0.45)
		(drill 0.1)
		(layers "F.Cu" "B.Cu")
		(net 687)
	)
	(via
		(at 81.086541 87.623459)
		(size 0.45)
		(drill 0.1)
		(layers "F.Cu" "B.Cu")
		(net 687)
	)
	(segment
		(start 79.953082 86.49)
		(end 76.85 86.49)
		(width 0.15)
		(layer "In1.Cu")
		(net 687)
	)
	(segment
		(start 81.086541 87.623459)
		(end 79.953082 86.49)
		(width 0.15)
		(layer "In1.Cu")
		(net 687)
	)
	(segment
		(start 62.4 77.26)
		(end 62.694 77.554)
		(width 0.15)
		(layer "B.Cu")
		(net 688)
	)
	(segment
		(start 68.8 72.3)
		(end 64.6 72.3)
		(width 0.15)
		(layer "B.Cu")
		(net 688)
	)
	(segment
		(start 62.696 77.554)
		(end 62.53 77.72)
		(width 0.15)
		(layer "B.Cu")
		(net 688)
	)
	(segment
		(start 64.05 74.7)
		(end 63.7 75.05)
		(width 0.15)
		(layer "B.Cu")
		(net 688)
	)
	(segment
		(start 69.4 74.21)
		(end 69.4 72.9)
		(width 0.15)
		(layer "B.Cu")
		(net 688)
	)
	(segment
		(start 64.6 72.3)
		(end 64.05 72.85)
		(width 0.15)
		(layer "B.Cu")
		(net 688)
	)
	(segment
		(start 69.45 74.26)
		(end 69.4 74.21)
		(width 0.15)
		(layer "B.Cu")
		(net 688)
	)
	(segment
		(start 62.285 78.535)
		(end 62.285 78.95)
		(width 0.15)
		(layer "B.Cu")
		(net 688)
	)
	(segment
		(start 62.4 75.2)
		(end 62.4 77.26)
		(width 0.15)
		(layer "B.Cu")
		(net 688)
	)
	(segment
		(start 63.7 75.05)
		(end 62.55 75.05)
		(width 0.15)
		(layer "B.Cu")
		(net 688)
	)
	(segment
		(start 69.4 72.9)
		(end 68.8 72.3)
		(width 0.15)
		(layer "B.Cu")
		(net 688)
	)
	(segment
		(start 64.05 72.85)
		(end 64.05 74.7)
		(width 0.15)
		(layer "B.Cu")
		(net 688)
	)
	(segment
		(start 63.264 77.554)
		(end 62.696 77.554)
		(width 0.15)
		(layer "B.Cu")
		(net 688)
	)
	(segment
		(start 62.53 77.72)
		(end 62.53 78.29)
		(width 0.15)
		(layer "B.Cu")
		(net 688)
	)
	(segment
		(start 62.53 78.29)
		(end 62.285 78.535)
		(width 0.15)
		(layer "B.Cu")
		(net 688)
	)
	(segment
		(start 62.694 77.554)
		(end 62.696 77.554)
		(width 0.15)
		(layer "B.Cu")
		(net 688)
	)
	(segment
		(start 62.55 75.05)
		(end 62.4 75.2)
		(width 0.15)
		(layer "B.Cu")
		(net 688)
	)
	(segment
		(start 65.785 77.415)
		(end 67 76.2)
		(width 0.15)
		(layer "B.Cu")
		(net 689)
	)
	(segment
		(start 65.785 77.5)
		(end 65.785 77.415)
		(width 0.15)
		(layer "B.Cu")
		(net 689)
	)
	(segment
		(start 67 76.2)
		(end 67.15 76.2)
		(width 0.15)
		(layer "B.Cu")
		(net 689)
	)
	(segment
		(start 58.65 85.83)
		(end 58.651 85.829)
		(width 0.15)
		(layer "B.Cu")
		(net 690)
	)
	(segment
		(start 58.651 85.829)
		(end 58.651 85.201)
		(width 0.15)
		(layer "B.Cu")
		(net 690)
	)
	(segment
		(start 58.65 86.29)
		(end 58.65 85.83)
		(width 0.15)
		(layer "B.Cu")
		(net 690)
	)
	(segment
		(start 62.76 98.03)
		(end 63.79 97)
		(width 0.125)
		(layer "B.Cu")
		(net 691)
	)
	(segment
		(start 62.9525 99.2125)
		(end 62.76 99.02)
		(width 0.125)
		(layer "B.Cu")
		(net 691)
	)
	(segment
		(start 62.76 99.02)
		(end 62.76 98.03)
		(width 0.125)
		(layer "B.Cu")
		(net 691)
	)
	(segment
		(start 64.0025 99.2125)
		(end 62.9525 99.2125)
		(width 0.125)
		(layer "B.Cu")
		(net 691)
	)
	(segment
		(start 64.1 99.75)
		(end 64.1 99.31)
		(width 0.125)
		(layer "B.Cu")
		(net 691)
	)
	(segment
		(start 64.1 99.31)
		(end 64.0025 99.2125)
		(width 0.125)
		(layer "B.Cu")
		(net 691)
	)
	(segment
		(start 64.885 117.505)
		(end 64.885 115.145)
		(width 0.15)
		(layer "F.Cu")
		(net 692)
	)
	(segment
		(start 72.232531 108.767469)
		(end 72.07 108.93)
		(width 0.15)
		(layer "F.Cu")
		(net 692)
	)
	(segment
		(start 72.07 108.93)
		(end 72.07 109.86)
		(width 0.15)
		(layer "F.Cu")
		(net 692)
	)
	(segment
		(start 65.14 117.76)
		(end 64.885 117.505)
		(width 0.15)
		(layer "F.Cu")
		(net 692)
	)
	(segment
		(start 64.885 114.78)
		(end 65.015 114.65)
		(width 0.15)
		(layer "F.Cu")
		(net 692)
	)
	(segment
		(start 65.48 122.485)
		(end 65.48 118.1)
		(width 0.15)
		(layer "F.Cu")
		(net 692)
	)
	(segment
		(start 65.48 118.1)
		(end 65.14 117.76)
		(width 0.15)
		(layer "F.Cu")
		(net 692)
	)
	(segment
		(start 64.885 115.145)
		(end 64.885 114.78)
		(width 0.15)
		(layer "F.Cu")
		(net 692)
	)
	(segment
		(start 72.232531 108.767469)
		(end 72.55 108.767469)
		(width 0.15)
		(layer "F.Cu")
		(net 692)
	)
	(via
		(at 65.015 114.65)
		(size 0.45)
		(drill 0.1)
		(layers "F.Cu" "B.Cu")
		(net 692)
	)
	(via
		(at 72.07 109.86)
		(size 0.45)
		(drill 0.1)
		(layers "F.Cu" "B.Cu")
		(net 692)
	)
	(segment
		(start 68.715 109.86)
		(end 65.015 113.56)
		(width 0.15)
		(layer "In5.Cu")
		(net 692)
	)
	(segment
		(start 72.07 109.86)
		(end 68.715 109.86)
		(width 0.15)
		(layer "In5.Cu")
		(net 692)
	)
	(segment
		(start 65.015 113.56)
		(end 65.015 114.65)
		(width 0.15)
		(layer "In5.Cu")
		(net 692)
	)
	(segment
		(start 95.065 94.9)
		(end 94.715 94.55)
		(width 0.125)
		(layer "B.Cu")
		(net 699)
	)
	(segment
		(start 93.798222 93.825)
		(end 93.1325 93.825)
		(width 0.125)
		(layer "B.Cu")
		(net 699)
	)
	(segment
		(start 94.523222 94.55)
		(end 93.798222 93.825)
		(width 0.125)
		(layer "B.Cu")
		(net 699)
	)
	(segment
		(start 93.1325 93.825)
		(end 93.0075 93.95)
		(width 0.125)
		(layer "B.Cu")
		(net 699)
	)
	(segment
		(start 94.715 94.55)
		(end 94.523222 94.55)
		(width 0.125)
		(layer "B.Cu")
		(net 699)
	)
	(segment
		(start 93.901778 93.575)
		(end 93.1325 93.575)
		(width 0.125)
		(layer "B.Cu")
		(net 700)
	)
	(segment
		(start 93.1325 93.575)
		(end 93.0075 93.45)
		(width 0.125)
		(layer "B.Cu")
		(net 700)
	)
	(segment
		(start 94.626778 94.3)
		(end 93.901778 93.575)
		(width 0.125)
		(layer "B.Cu")
		(net 700)
	)
	(segment
		(start 95.065 93.95)
		(end 94.715 94.3)
		(width 0.125)
		(layer "B.Cu")
		(net 700)
	)
	(segment
		(start 94.715 94.3)
		(end 94.626778 94.3)
		(width 0.125)
		(layer "B.Cu")
		(net 700)
	)
	(segment
		(start 85.55 92.85)
		(end 85.55 97.45)
		(width 0.125)
		(layer "F.Cu")
		(net 701)
	)
	(segment
		(start 87.9 104.4996)
		(end 87.9 101.83)
		(width 0.15)
		(layer "F.Cu")
		(net 701)
	)
	(segment
		(start 85.55 97.45)
		(end 87.4 99.3)
		(width 0.125)
		(layer "F.Cu")
		(net 701)
	)
	(segment
		(start 90.305 116.25)
		(end 90.305 115.105)
		(width 0.15)
		(layer "F.Cu")
		(net 701)
	)
	(segment
		(start 88.325 90.075)
		(end 85.55 92.85)
		(width 0.125)
		(layer "F.Cu")
		(net 701)
	)
	(segment
		(start 87.4 101.33)
		(end 87.4 99.3)
		(width 0.15)
		(layer "F.Cu")
		(net 701)
	)
	(segment
		(start 90.305 115.105)
		(end 90.25 115.05)
		(width 0.15)
		(layer "F.Cu")
		(net 701)
	)
	(segment
		(start 88.95 89.185)
		(end 88.95 89.8)
		(width 0.125)
		(layer "F.Cu")
		(net 701)
	)
	(segment
		(start 87.9 101.83)
		(end 87.4 101.33)
		(width 0.15)
		(layer "F.Cu")
		(net 701)
	)
	(segment
		(start 87.9 105.1)
		(end 89.05 106.25)
		(width 0.155)
		(layer "F.Cu")
		(net 701)
	)
	(segment
		(start 89.05 106.25)
		(end 89.05 112.65)
		(width 0.155)
		(layer "F.Cu")
		(net 701)
	)
	(segment
		(start 88.95 89.8)
		(end 88.675 90.075)
		(width 0.125)
		(layer "F.Cu")
		(net 701)
	)
	(segment
		(start 87.9 104.4996)
		(end 87.9 105.1)
		(width 0.155)
		(layer "F.Cu")
		(net 701)
	)
	(segment
		(start 90.25 114.85)
		(end 90.25 115.05)
		(width 0.155)
		(layer "F.Cu")
		(net 701)
	)
	(segment
		(start 88.675 90.075)
		(end 88.325 90.075)
		(width 0.125)
		(layer "F.Cu")
		(net 701)
	)
	(segment
		(start 90.4 114.7)
		(end 90.25 114.85)
		(width 0.155)
		(layer "F.Cu")
		(net 701)
	)
	(segment
		(start 89.05 112.65)
		(end 90.4 114)
		(width 0.155)
		(layer "F.Cu")
		(net 701)
	)
	(segment
		(start 90.4 114)
		(end 90.4 114.7)
		(width 0.155)
		(layer "F.Cu")
		(net 701)
	)
	(via
		(at 90.25 115.05)
		(size 0.45)
		(drill 0.1)
		(layers "F.Cu" "B.Cu")
		(net 701)
	)
	(segment
		(start 90.25 115.05)
		(end 90.25 114.9008)
		(width 0.15)
		(layer "B.Cu")
		(net 701)
	)
	(segment
		(start 90.25 114.9008)
		(end 89.7492 114.4)
		(width 0.15)
		(layer "B.Cu")
		(net 701)
	)
	(segment
		(start 90.25 115.05)
		(end 89.9 115.4)
		(width 0.155)
		(layer "B.Cu")
		(net 701)
	)
	(segment
		(start 89.9 115.4)
		(end 89.9 115.615)
		(width 0.155)
		(layer "B.Cu")
		(net 701)
	)
	(segment
		(start 84.75 108.85)
		(end 87.2 106.4)
		(width 0.15)
		(layer "F.Cu")
		(net 703)
	)
	(segment
		(start 84.75 114.635)
		(end 84.915 114.8)
		(width 0.15)
		(layer "F.Cu")
		(net 703)
	)
	(segment
		(start 87.2 106.4)
		(end 87.2 103.965)
		(width 0.15)
		(layer "F.Cu")
		(net 703)
	)
	(segment
		(start 86.6 103.365)
		(end 87.035 103.8)
		(width 0.15)
		(layer "F.Cu")
		(net 703)
	)
	(segment
		(start 87.2 103.965)
		(end 87.035 103.8)
		(width 0.15)
		(layer "F.Cu")
		(net 703)
	)
	(segment
		(start 86.6 102.12)
		(end 86.6 103.365)
		(width 0.15)
		(layer "F.Cu")
		(net 703)
	)
	(segment
		(start 84.75 113.2)
		(end 84.75 114.635)
		(width 0.15)
		(layer "F.Cu")
		(net 703)
	)
	(segment
		(start 84.75 113.2)
		(end 84.75 108.85)
		(width 0.15)
		(layer "F.Cu")
		(net 703)
	)
	(via
		(at 90 97.64)
		(size 0.45)
		(drill 0.1)
		(layers "F.Cu" "B.Cu")
		(net 703)
	)
	(via
		(at 86.6 102.12)
		(size 0.45)
		(drill 0.1)
		(layers "F.Cu" "B.Cu")
		(net 703)
	)
	(segment
		(start 89.925 97.715)
		(end 90 97.64)
		(width 0.15)
		(layer "In5.Cu")
		(net 703)
	)
	(segment
		(start 87.93 102.12)
		(end 89.925 100.125)
		(width 0.15)
		(layer "In5.Cu")
		(net 703)
	)
	(segment
		(start 86.6 102.12)
		(end 87.93 102.12)
		(width 0.15)
		(layer "In5.Cu")
		(net 703)
	)
	(segment
		(start 89.925 100.125)
		(end 89.925 97.715)
		(width 0.15)
		(layer "In5.Cu")
		(net 703)
	)
	(segment
		(start 90.325 97.965)
		(end 90 97.64)
		(width 0.15)
		(layer "B.Cu")
		(net 703)
	)
	(segment
		(start 91.05 99.675)
		(end 90.55 99.675)
		(width 0.15)
		(layer "B.Cu")
		(net 703)
	)
	(segment
		(start 90.01 97.64)
		(end 90.57 97.08)
		(width 0.15)
		(layer "B.Cu")
		(net 703)
	)
	(segment
		(start 91.3 99.425)
		(end 91.05 99.675)
		(width 0.15)
		(layer "B.Cu")
		(net 703)
	)
	(segment
		(start 90.2 98.8)
		(end 90.325 98.675)
		(width 0.15)
		(layer "B.Cu")
		(net 703)
	)
	(segment
		(start 91.3 98.935)
		(end 91.3 99.425)
		(width 0.15)
		(layer "B.Cu")
		(net 703)
	)
	(segment
		(start 90.57 97.08)
		(end 90.57 96.3875)
		(width 0.15)
		(layer "B.Cu")
		(net 703)
	)
	(segment
		(start 90.2 99.325)
		(end 90.2 98.8)
		(width 0.15)
		(layer "B.Cu")
		(net 703)
	)
	(segment
		(start 90 97.64)
		(end 90.01 97.64)
		(width 0.15)
		(layer "B.Cu")
		(net 703)
	)
	(segment
		(start 90.325 98.675)
		(end 90.325 97.965)
		(width 0.15)
		(layer "B.Cu")
		(net 703)
	)
	(segment
		(start 90.55 99.675)
		(end 90.2 99.325)
		(width 0.15)
		(layer "B.Cu")
		(net 703)
	)
	(segment
		(start 59.86 102.41)
		(end 59.69 102.41)
		(width 0.125)
		(layer "B.Cu")
		(net 708)
	)
	(segment
		(start 62.95 102.5)
		(end 62.1 102.5)
		(width 0.125)
		(layer "B.Cu")
		(net 708)
	)
	(segment
		(start 62.1 102.5)
		(end 61.51 103.09)
		(width 0.125)
		(layer "B.Cu")
		(net 708)
	)
	(segment
		(start 60.54 103.09)
		(end 59.86 102.41)
		(width 0.125)
		(layer "B.Cu")
		(net 708)
	)
	(segment
		(start 61.51 103.09)
		(end 60.54 103.09)
		(width 0.125)
		(layer "B.Cu")
		(net 708)
	)
	(segment
		(start 79.61 86.74)
		(end 79.23 86.36)
		(width 0.15)
		(layer "F.Cu")
		(net 711)
	)
	(segment
		(start 80.23 86.74)
		(end 79.61 86.74)
		(width 0.15)
		(layer "F.Cu")
		(net 711)
	)
	(segment
		(start 79.09 88.14)
		(end 79.54 88.14)
		(width 0.15)
		(layer "F.Cu")
		(net 711)
	)
	(segment
		(start 79.54 88.14)
		(end 79.61 88.07)
		(width 0.15)
		(layer "F.Cu")
		(net 711)
	)
	(segment
		(start 79.61 88.07)
		(end 79.61 86.74)
		(width 0.15)
		(layer "F.Cu")
		(net 711)
	)
	(segment
		(start 67.8 97.16)
		(end 68.06 97.42)
		(width 0.125)
		(layer "F.Cu")
		(net 712)
	)
	(segment
		(start 68.67 98.94)
		(end 68.67 97.98)
		(width 0.125)
		(layer "F.Cu")
		(net 712)
	)
	(segment
		(start 64.61 98.46)
		(end 65.22 98.46)
		(width 0.125)
		(layer "F.Cu")
		(net 712)
	)
	(segment
		(start 65.22 98.46)
		(end 65.33 98.35)
		(width 0.125)
		(layer "F.Cu")
		(net 712)
	)
	(segment
		(start 65.55 98.35)
		(end 66.74 97.16)
		(width 0.125)
		(layer "F.Cu")
		(net 712)
	)
	(segment
		(start 68.06 97.42)
		(end 68.06 97.82)
		(width 0.125)
		(layer "F.Cu")
		(net 712)
	)
	(segment
		(start 68.06 97.82)
		(end 68.22 97.98)
		(width 0.125)
		(layer "F.Cu")
		(net 712)
	)
	(segment
		(start 67.67 98.94)
		(end 68.67 98.94)
		(width 0.125)
		(layer "F.Cu")
		(net 712)
	)
	(segment
		(start 68.22 97.98)
		(end 68.67 97.98)
		(width 0.125)
		(layer "F.Cu")
		(net 712)
	)
	(segment
		(start 65.33 98.35)
		(end 65.55 98.35)
		(width 0.125)
		(layer "F.Cu")
		(net 712)
	)
	(segment
		(start 66.74 97.16)
		(end 67.8 97.16)
		(width 0.125)
		(layer "F.Cu")
		(net 712)
	)
	(segment
		(start 63.44 99.49)
		(end 62.61 99.49)
		(width 0.125)
		(layer "B.Cu")
		(net 713)
	)
	(segment
		(start 63.7 99.75)
		(end 63.44 99.49)
		(width 0.125)
		(layer "B.Cu")
		(net 713)
	)
	(segment
		(start 62.61 99.49)
		(end 62.15 99.03)
		(width 0.125)
		(layer "B.Cu")
		(net 713)
	)
	(segment
		(start 62.15 99.03)
		(end 62.15 98.635)
		(width 0.125)
		(layer "B.Cu")
		(net 713)
	)
	(segment
		(start 121.2 115.6)
		(end 119.9 115.6)
		(width 0.125)
		(layer "F.Cu")
		(net 714)
	)
	(segment
		(start 121.55 114.6)
		(end 121.55 115.25)
		(width 0.125)
		(layer "F.Cu")
		(net 714)
	)
	(segment
		(start 114.65 105.65)
		(end 113.5 105.65)
		(width 0.125)
		(layer "F.Cu")
		(net 714)
	)
	(segment
		(start 70.6995 81.75)
		(end 70.6995 81.714105)
		(width 0.15)
		(layer "F.Cu")
		(net 714)
	)
	(segment
		(start 119.9 115.6)
		(end 118.65 114.35)
		(width 0.125)
		(layer "F.Cu")
		(net 714)
	)
	(segment
		(start 118.65 109.65)
		(end 114.65 105.65)
		(width 0.125)
		(layer "F.Cu")
		(net 714)
	)
	(segment
		(start 118.65 114.35)
		(end 118.65 109.65)
		(width 0.125)
		(layer "F.Cu")
		(net 714)
	)
	(segment
		(start 71.347323 81.066282)
		(end 71.347323 80.205136)
		(width 0.15)
		(layer "F.Cu")
		(net 714)
	)
	(segment
		(start 121.55 115.25)
		(end 121.2 115.6)
		(width 0.125)
		(layer "F.Cu")
		(net 714)
	)
	(segment
		(start 70.6995 81.714105)
		(end 71.347323 81.066282)
		(width 0.15)
		(layer "F.Cu")
		(net 714)
	)
	(via
		(at 121.55 114.6)
		(size 0.45)
		(drill 0.1)
		(layers "F.Cu" "B.Cu")
		(net 714)
	)
	(via
		(at 70.6995 81.75)
		(size 0.45)
		(drill 0.1)
		(layers "F.Cu" "B.Cu")
		(net 714)
	)
	(via
		(at 113.5 105.65)
		(size 0.45)
		(drill 0.1)
		(layers "F.Cu" "B.Cu")
		(net 714)
	)
	(via
		(at 67.53 94.5)
		(size 0.45)
		(drill 0.1)
		(layers "F.Cu" "B.Cu")
		(net 714)
	)
	(segment
		(start 64.85 84.9)
		(end 65.41 84.34)
		(width 0.125)
		(layer "In5.Cu")
		(net 714)
	)
	(segment
		(start 67.53 94.5)
		(end 67.25 94.5)
		(width 0.125)
		(layer "In5.Cu")
		(net 714)
	)
	(segment
		(start 68.9 84.8)
		(end 70.682636 84.8)
		(width 0.125)
		(layer "In5.Cu")
		(net 714)
	)
	(segment
		(start 73.25 82.85)
		(end 72.15 81.75)
		(width 0.125)
		(layer "In5.Cu")
		(net 714)
	)
	(segment
		(start 70.992636 84.49)
		(end 72.11 84.49)
		(width 0.125)
		(layer "In5.Cu")
		(net 714)
	)
	(segment
		(start 72.4 105.8)
		(end 82.5 105.8)
		(width 0.125)
		(layer "In5.Cu")
		(net 714)
	)
	(segment
		(start 65.41 84.34)
		(end 68.44 84.34)
		(width 0.125)
		(layer "In5.Cu")
		(net 714)
	)
	(segment
		(start 91.8 105.1)
		(end 99.2 112.5)
		(width 0.125)
		(layer "In5.Cu")
		(net 714)
	)
	(segment
		(start 72.25 84.35)
		(end 72.95 84.35)
		(width 0.125)
		(layer "In5.Cu")
		(net 714)
	)
	(segment
		(start 64.85 86.4)
		(end 64.85 84.9)
		(width 0.125)
		(layer "In5.Cu")
		(net 714)
	)
	(segment
		(start 68.44 84.34)
		(end 68.9 84.8)
		(width 0.125)
		(layer "In5.Cu")
		(net 714)
	)
	(segment
		(start 99.2 112.5)
		(end 119.45 112.5)
		(width 0.125)
		(layer "In5.Cu")
		(net 714)
	)
	(segment
		(start 119.45 112.5)
		(end 121.55 114.6)
		(width 0.125)
		(layer "In5.Cu")
		(net 714)
	)
	(segment
		(start 65.3 91.65)
		(end 65.3 86.85)
		(width 0.125)
		(layer "In5.Cu")
		(net 714)
	)
	(segment
		(start 72.95 84.35)
		(end 73.25 84.05)
		(width 0.125)
		(layer "In5.Cu")
		(net 714)
	)
	(segment
		(start 67.53 94.5)
		(end 69.95 94.5)
		(width 0.125)
		(layer "In5.Cu")
		(net 714)
	)
	(segment
		(start 82.5 105.8)
		(end 83.2 105.1)
		(width 0.125)
		(layer "In5.Cu")
		(net 714)
	)
	(segment
		(start 67 93.35)
		(end 65.3 91.65)
		(width 0.125)
		(layer "In5.Cu")
		(net 714)
	)
	(segment
		(start 67.25 94.5)
		(end 67 94.25)
		(width 0.125)
		(layer "In5.Cu")
		(net 714)
	)
	(segment
		(start 70.682636 84.8)
		(end 70.992636 84.49)
		(width 0.125)
		(layer "In5.Cu")
		(net 714)
	)
	(segment
		(start 69.95 94.5)
		(end 71.05 95.6)
		(width 0.125)
		(layer "In5.Cu")
		(net 714)
	)
	(segment
		(start 72.11 84.49)
		(end 72.25 84.35)
		(width 0.125)
		(layer "In5.Cu")
		(net 714)
	)
	(segment
		(start 65.3 86.85)
		(end 64.85 86.4)
		(width 0.125)
		(layer "In5.Cu")
		(net 714)
	)
	(segment
		(start 73.25 84.05)
		(end 73.25 82.85)
		(width 0.125)
		(layer "In5.Cu")
		(net 714)
	)
	(segment
		(start 72.15 81.75)
		(end 70.6995 81.75)
		(width 0.125)
		(layer "In5.Cu")
		(net 714)
	)
	(segment
		(start 67 94.25)
		(end 67 93.35)
		(width 0.125)
		(layer "In5.Cu")
		(net 714)
	)
	(segment
		(start 71.05 95.6)
		(end 71.05 104.45)
		(width 0.125)
		(layer "In5.Cu")
		(net 714)
	)
	(segment
		(start 71.05 104.45)
		(end 72.4 105.8)
		(width 0.125)
		(layer "In5.Cu")
		(net 714)
	)
	(segment
		(start 83.2 105.1)
		(end 91.8 105.1)
		(width 0.125)
		(layer "In5.Cu")
		(net 714)
	)
	(segment
		(start 63.11 96.47)
		(end 63.11 96.96)
		(width 0.125)
		(layer "B.Cu")
		(net 714)
	)
	(segment
		(start 67.15 95.33)
		(end 66.72 95.76)
		(width 0.125)
		(layer "B.Cu")
		(net 714)
	)
	(segment
		(start 113.35 105.1)
		(end 113.5 105.25)
		(width 0.125)
		(layer "B.Cu")
		(net 714)
	)
	(segment
		(start 112.885 105.1)
		(end 113.35 105.1)
		(width 0.125)
		(layer "B.Cu")
		(net 714)
	)
	(segment
		(start 62.405 97.665)
		(end 62.15 97.665)
		(width 0.125)
		(layer "B.Cu")
		(net 714)
	)
	(segment
		(start 69.1495 83.3)
		(end 68.585 83.3)
		(width 0.125)
		(layer "B.Cu")
		(net 714)
	)
	(segment
		(start 65.18 95.76)
		(end 64.74 96.2)
		(width 0.125)
		(layer "B.Cu")
		(net 714)
	)
	(segment
		(start 70.6995 81.75)
		(end 69.1495 83.3)
		(width 0.125)
		(layer "B.Cu")
		(net 714)
	)
	(segment
		(start 67.15 94.88)
		(end 67.15 95.33)
		(width 0.125)
		(layer "B.Cu")
		(net 714)
	)
	(segment
		(start 66.72 95.76)
		(end 65.18 95.76)
		(width 0.125)
		(layer "B.Cu")
		(net 714)
	)
	(segment
		(start 64.74 96.2)
		(end 63.38 96.2)
		(width 0.125)
		(layer "B.Cu")
		(net 714)
	)
	(segment
		(start 113.5 105.25)
		(end 113.5 105.65)
		(width 0.125)
		(layer "B.Cu")
		(net 714)
	)
	(segment
		(start 63.11 96.96)
		(end 62.405 97.665)
		(width 0.125)
		(layer "B.Cu")
		(net 714)
	)
	(segment
		(start 67.53 94.5)
		(end 67.15 94.88)
		(width 0.125)
		(layer "B.Cu")
		(net 714)
	)
	(segment
		(start 63.38 96.2)
		(end 63.11 96.47)
		(width 0.125)
		(layer "B.Cu")
		(net 714)
	)
	(segment
		(start 43.821 115.45)
		(end 46.016398 115.45)
		(width 0.3)
		(layer "B.Cu")
		(net 715)
	)
	(segment
		(start 41.9 117.371)
		(end 43.821 115.45)
		(width 0.3)
		(layer "B.Cu")
		(net 715)
	)
	(segment
		(start 46.016398 115.45)
		(end 47 114.466398)
		(width 0.3)
		(layer "B.Cu")
		(net 715)
	)
	(segment
		(start 33.982387 115.2)
		(end 36.153387 117.371)
		(width 0.3)
		(layer "B.Cu")
		(net 715)
	)
	(segment
		(start 31.866398 114.466398)
		(end 32.6 115.2)
		(width 0.3)
		(layer "B.Cu")
		(net 715)
	)
	(segment
		(start 39.608 117.371)
		(end 41.9 117.371)
		(width 0.3)
		(layer "B.Cu")
		(net 715)
	)
	(segment
		(start 36.153387 117.371)
		(end 39.608 117.371)
		(width 0.3)
		(layer "B.Cu")
		(net 715)
	)
	(segment
		(start 32.6 115.2)
		(end 33.982387 115.2)
		(width 0.3)
		(layer "B.Cu")
		(net 715)
	)
	(segment
		(start 58.2 109.6)
		(end 57.85 109.95)
		(width 0.15)
		(layer "F.Cu")
		(net 717)
	)
	(segment
		(start 56.635 109.2)
		(end 56.1 109.735)
		(width 0.15)
		(layer "F.Cu")
		(net 717)
	)
	(segment
		(start 59.05 109.2)
		(end 58.9 109.2)
		(width 0.15)
		(layer "F.Cu")
		(net 717)
	)
	(segment
		(start 58.5 109.6)
		(end 58.2 109.6)
		(width 0.15)
		(layer "F.Cu")
		(net 717)
	)
	(segment
		(start 57.85 109.95)
		(end 57.15 109.95)
		(width 0.15)
		(layer "F.Cu")
		(net 717)
	)
	(segment
		(start 57.15 109.2)
		(end 57.15 109.95)
		(width 0.15)
		(layer "F.Cu")
		(net 717)
	)
	(segment
		(start 58.9 109.2)
		(end 58.5 109.6)
		(width 0.15)
		(layer "F.Cu")
		(net 717)
	)
	(segment
		(start 57.15 109.2)
		(end 56.635 109.2)
		(width 0.15)
		(layer "F.Cu")
		(net 717)
	)
	(segment
		(start 42.79 74.675)
		(end 44.69 74.675)
		(width 0.15)
		(layer "B.Cu")
		(net 718)
	)
	(segment
		(start 42.79 73.925)
		(end 42.79 74.675)
		(width 0.15)
		(layer "B.Cu")
		(net 718)
	)
	(segment
		(start 45.34 74.475)
		(end 45.34 73.675)
		(width 0.15)
		(layer "B.Cu")
		(net 718)
	)
	(segment
		(start 45.54 73.475)
		(end 46.055 73.475)
		(width 0.15)
		(layer "B.Cu")
		(net 718)
	)
	(segment
		(start 45.34 73.675)
		(end 45.54 73.475)
		(width 0.15)
		(layer "B.Cu")
		(net 718)
	)
	(segment
		(start 45.14 74.675)
		(end 45.34 74.475)
		(width 0.15)
		(layer "B.Cu")
		(net 718)
	)
	(segment
		(start 44.69 74.675)
		(end 45.14 74.675)
		(width 0.15)
		(layer "B.Cu")
		(net 718)
	)
	(segment
		(start 55.991 98.801)
		(end 55.389 98.801)
		(width 0.15)
		(layer "B.Cu")
		(net 730)
	)
	(segment
		(start 55.389 98.801)
		(end 54.93 99.26)
		(width 0.15)
		(layer "B.Cu")
		(net 730)
	)
	(segment
		(start 54.93 99.26)
		(end 54.4 99.26)
		(width 0.15)
		(layer "B.Cu")
		(net 730)
	)
	(segment
		(start 56.065 106.525)
		(end 56.065 107.26)
		(width 0.15)
		(layer "B.Cu")
		(net 731)
	)
	(segment
		(start 55.99 105.051)
		(end 55.99 106.45)
		(width 0.15)
		(layer "B.Cu")
		(net 731)
	)
	(segment
		(start 55.99 106.45)
		(end 56.065 106.525)
		(width 0.15)
		(layer "B.Cu")
		(net 731)
	)
	(segment
		(start 55.991 105.05)
		(end 55.99 105.051)
		(width 0.15)
		(layer "B.Cu")
		(net 731)
	)
	(segment
		(start 132.170706 70.985706)
		(end 132.085 70.9)
		(width 0.15)
		(layer "B.Cu")
		(net 732)
	)
	(segment
		(start 132.170706 72.05)
		(end 132.170706 70.985706)
		(width 0.15)
		(layer "B.Cu")
		(net 732)
	)
	(segment
		(start 102.847323 80.205136)
		(end 102.847323 81.697323)
		(width 0.15)
		(layer "F.Cu")
		(net 742)
	)
	(segment
		(start 102.847323 81.697323)
		(end 103.3492 82.1992)
		(width 0.15)
		(layer "F.Cu")
		(net 742)
	)
	(segment
		(start 103.3492 82.1992)
		(end 104.1 82.1992)
		(width 0.15)
		(layer "F.Cu")
		(net 742)
	)
	(segment
		(start 96.7 86.95)
		(end 96.7 84.3)
		(width 0.125)
		(layer "F.Cu")
		(net 743)
	)
	(segment
		(start 95.7755 87.8745)
		(end 96.7 86.95)
		(width 0.125)
		(layer "F.Cu")
		(net 743)
	)
	(segment
		(start 96.7 84.3)
		(end 97.847323 83.152677)
		(width 0.125)
		(layer "F.Cu")
		(net 743)
	)
	(segment
		(start 97.847323 83.152677)
		(end 97.847323 80.205136)
		(width 0.125)
		(layer "F.Cu")
		(net 743)
	)
	(segment
		(start 95.7755 88.095694)
		(end 95.7755 87.8745)
		(width 0.125)
		(layer "F.Cu")
		(net 743)
	)
	(via
		(at 95.7755 88.095694)
		(size 0.45)
		(drill 0.1)
		(layers "F.Cu" "B.Cu")
		(net 743)
	)
	(via
		(at 134.407917 101.617583)
		(size 0.45)
		(drill 0.1)
		(layers "F.Cu" "B.Cu")
		(net 743)
	)
	(segment
		(start 117.25 107.6)
		(end 124.05 107.6)
		(width 0.125)
		(layer "In5.Cu")
		(net 743)
	)
	(segment
		(start 95.6 98.3)
		(end 95.8 98.5)
		(width 0.125)
		(layer "In5.Cu")
		(net 743)
	)
	(segment
		(start 95.8 99.45)
		(end 96.15 99.8)
		(width 0.125)
		(layer "In5.Cu")
		(net 743)
	)
	(segment
		(start 96.9 99.8)
		(end 99.9 102.8)
		(width 0.125)
		(layer "In5.Cu")
		(net 743)
	)
	(segment
		(start 99.9 102.8)
		(end 99.9 106.45)
		(width 0.125)
		(layer "In5.Cu")
		(net 743)
	)
	(segment
		(start 124.05 107.6)
		(end 126.9 104.75)
		(width 0.125)
		(layer "In5.Cu")
		(net 743)
	)
	(segment
		(start 95.6 94.05)
		(end 95.6 98.3)
		(width 0.125)
		(layer "In5.Cu")
		(net 743)
	)
	(segment
		(start 95.8 98.5)
		(end 95.8 99.45)
		(width 0.125)
		(layer "In5.Cu")
		(net 743)
	)
	(segment
		(start 95.9 93.75)
		(end 95.6 94.05)
		(width 0.125)
		(layer "In5.Cu")
		(net 743)
	)
	(segment
		(start 96.15 99.8)
		(end 96.9 99.8)
		(width 0.125)
		(layer "In5.Cu")
		(net 743)
	)
	(segment
		(start 132.7 104.75)
		(end 134.407917 103.042083)
		(width 0.125)
		(layer "In5.Cu")
		(net 743)
	)
	(segment
		(start 99.9 106.45)
		(end 100.3 106.85)
		(width 0.125)
		(layer "In5.Cu")
		(net 743)
	)
	(segment
		(start 95.7755 88.095694)
		(end 95.9 88.220194)
		(width 0.125)
		(layer "In5.Cu")
		(net 743)
	)
	(segment
		(start 126.9 104.75)
		(end 132.7 104.75)
		(width 0.125)
		(layer "In5.Cu")
		(net 743)
	)
	(segment
		(start 134.407917 103.042083)
		(end 134.407917 101.617583)
		(width 0.125)
		(layer "In5.Cu")
		(net 743)
	)
	(segment
		(start 95.9 88.220194)
		(end 95.9 93.75)
		(width 0.125)
		(layer "In5.Cu")
		(net 743)
	)
	(segment
		(start 116.5 106.85)
		(end 117.25 107.6)
		(width 0.125)
		(layer "In5.Cu")
		(net 743)
	)
	(segment
		(start 100.3 106.85)
		(end 116.5 106.85)
		(width 0.125)
		(layer "In5.Cu")
		(net 743)
	)
	(segment
		(start 134.65 101.3755)
		(end 134.65 98.41)
		(width 0.15)
		(layer "B.Cu")
		(net 743)
	)
	(segment
		(start 134.66 98.4)
		(end 135.315 98.4)
		(width 0.15)
		(layer "B.Cu")
		(net 743)
	)
	(segment
		(start 134.407917 101.617583)
		(end 134.65 101.3755)
		(width 0.15)
		(layer "B.Cu")
		(net 743)
	)
	(segment
		(start 134.65 98.41)
		(end 134.66 98.4)
		(width 0.15)
		(layer "B.Cu")
		(net 743)
	)
	(segment
		(start 97.347323 82.753477)
		(end 97.347323 80.205136)
		(width 0.15)
		(layer "F.Cu")
		(net 744)
	)
	(segment
		(start 96.95 83.1508)
		(end 97.347323 82.753477)
		(width 0.15)
		(layer "F.Cu")
		(net 744)
	)
	(segment
		(start 96.347323 82.352677)
		(end 96.347323 80.205136)
		(width 0.125)
		(layer "F.Cu")
		(net 745)
	)
	(segment
		(start 96.05 82.65)
		(end 96.347323 82.352677)
		(width 0.125)
		(layer "F.Cu")
		(net 745)
	)
	(segment
		(start 94.748949 88.100592)
		(end 94.748949 87.701051)
		(width 0.125)
		(layer "F.Cu")
		(net 745)
	)
	(segment
		(start 94.748949 87.701051)
		(end 96.05 86.4)
		(width 0.125)
		(layer "F.Cu")
		(net 745)
	)
	(segment
		(start 96.05 86.4)
		(end 96.05 82.65)
		(width 0.125)
		(layer "F.Cu")
		(net 745)
	)
	(via
		(at 94.748949 88.100592)
		(size 0.45)
		(drill 0.1)
		(layers "F.Cu" "B.Cu")
		(free yes)
		(net 745)
	)
	(via
		(at 135.12 101.01)
		(size 0.45)
		(drill 0.1)
		(layers "F.Cu" "B.Cu")
		(net 745)
	)
	(segment
		(start 94.85 97.071446)
		(end 94.4 97.521446)
		(width 0.125)
		(layer "In5.Cu")
		(net 745)
	)
	(segment
		(start 94.85 88.201643)
		(end 94.85 97.071446)
		(width 0.125)
		(layer "In5.Cu")
		(net 745)
	)
	(segment
		(start 122.25 108.65)
		(end 122.7 108.2)
		(width 0.125)
		(layer "In5.Cu")
		(net 745)
	)
	(segment
		(start 94.748949 88.100592)
		(end 94.85 88.201643)
		(width 0.125)
		(layer "In5.Cu")
		(net 745)
	)
	(segment
		(start 127.1 105.35)
		(end 133.29 105.35)
		(width 0.125)
		(layer "In5.Cu")
		(net 745)
	)
	(segment
		(start 99.85 108.65)
		(end 122.25 108.65)
		(width 0.125)
		(layer "In5.Cu")
		(net 745)
	)
	(segment
		(start 94.4 97.521446)
		(end 94.4 102.4)
		(width 0.125)
		(layer "In5.Cu")
		(net 745)
	)
	(segment
		(start 135.12 103.52)
		(end 135.12 101.01)
		(width 0.125)
		(layer "In5.Cu")
		(net 745)
	)
	(segment
		(start 97.5 105.5)
		(end 97.5 106.3)
		(width 0.125)
		(layer "In5.Cu")
		(net 745)
	)
	(segment
		(start 133.29 105.35)
		(end 135.12 103.52)
		(width 0.125)
		(layer "In5.Cu")
		(net 745)
	)
	(segment
		(start 94.4 102.4)
		(end 97.5 105.5)
		(width 0.125)
		(layer "In5.Cu")
		(net 745)
	)
	(segment
		(start 122.7 108.2)
		(end 124.25 108.2)
		(width 0.125)
		(layer "In5.Cu")
		(net 745)
	)
	(segment
		(start 97.5 106.3)
		(end 99.85 108.65)
		(width 0.125)
		(layer "In5.Cu")
		(net 745)
	)
	(segment
		(start 124.25 108.2)
		(end 127.1 105.35)
		(width 0.125)
		(layer "In5.Cu")
		(net 745)
	)
	(segment
		(start 135.315 100.815)
		(end 135.315 99.4)
		(width 0.15)
		(layer "B.Cu")
		(net 745)
	)
	(segment
		(start 135.12 101.01)
		(end 135.315 100.815)
		(width 0.15)
		(layer "B.Cu")
		(net 745)
	)
	(segment
		(start 95.847323 81.953477)
		(end 95.55 82.2508)
		(width 0.3)
		(layer "F.Cu")
		(net 746)
	)
	(segment
		(start 95.847323 80.205136)
		(end 95.847323 81.953477)
		(width 0.3)
		(layer "F.Cu")
		(net 746)
	)
	(segment
		(start 95.15 97.69)
		(end 94.375 98.465)
		(width 0.125)
		(layer "F.Cu")
		(net 747)
	)
	(segment
		(start 95.55 103.45)
		(end 95.55 111.85)
		(width 0.125)
		(layer "F.Cu")
		(net 747)
	)
	(segment
		(start 94.375 98.465)
		(end 94.375 102.275)
		(width 0.125)
		(layer "F.Cu")
		(net 747)
	)
	(segment
		(start 95.347323 80.205136)
		(end 95.347323 81.552677)
		(width 0.125)
		(layer "F.Cu")
		(net 747)
	)
	(segment
		(start 95.15 89.96)
		(end 95.15 97.69)
		(width 0.125)
		(layer "F.Cu")
		(net 747)
	)
	(segment
		(start 94.01 84.09)
		(end 94.01 88.82)
		(width 0.125)
		(layer "F.Cu")
		(net 747)
	)
	(segment
		(start 95.347323 81.552677)
		(end 94.825 82.075)
		(width 0.125)
		(layer "F.Cu")
		(net 747)
	)
	(segment
		(start 94.01 88.82)
		(end 95.15 89.96)
		(width 0.125)
		(layer "F.Cu")
		(net 747)
	)
	(segment
		(start 94.825 82.075)
		(end 94.825 83.275)
		(width 0.125)
		(layer "F.Cu")
		(net 747)
	)
	(segment
		(start 94.825 83.275)
		(end 94.01 84.09)
		(width 0.125)
		(layer "F.Cu")
		(net 747)
	)
	(segment
		(start 94.375 102.275)
		(end 95.55 103.45)
		(width 0.125)
		(layer "F.Cu")
		(net 747)
	)
	(segment
		(start 95.55 111.85)
		(end 95.7 112)
		(width 0.125)
		(layer "F.Cu")
		(net 747)
	)
	(via
		(at 89.410307 113.668914)
		(size 0.45)
		(drill 0.1)
		(layers "F.Cu" "B.Cu")
		(net 747)
	)
	(via
		(at 95.7 112)
		(size 0.45)
		(drill 0.1)
		(layers "F.Cu" "B.Cu")
		(net 747)
	)
	(segment
		(start 89.410307 113.668914)
		(end 89.410307 112.539693)
		(width 0.15)
		(layer "In3.Cu")
		(net 747)
	)
	(segment
		(start 89.95 112)
		(end 95.7 112)
		(width 0.15)
		(layer "In3.Cu")
		(net 747)
	)
	(segment
		(start 89.410307 112.539693)
		(end 89.95 112)
		(width 0.15)
		(layer "In3.Cu")
		(net 747)
	)
	(segment
		(start 89.881086 113.668914)
		(end 90 113.55)
		(width 0.125)
		(layer "B.Cu")
		(net 747)
	)
	(segment
		(start 89.410307 113.668914)
		(end 89.881086 113.668914)
		(width 0.125)
		(layer "B.Cu")
		(net 747)
	)
	(segment
		(start 90 113.55)
		(end 90 113.085)
		(width 0.125)
		(layer "B.Cu")
		(net 747)
	)
	(segment
		(start 74.716454 76.141515)
		(end 74.716454 76.763546)
		(width 0.125)
		(layer "F.Cu")
		(net 750)
	)
	(segment
		(start 74.716454 76.763546)
		(end 73.295 78.185)
		(width 0.125)
		(layer "F.Cu")
		(net 750)
	)
	(segment
		(start 72.2 78.185)
		(end 71.826 78.559)
		(width 0.125)
		(layer "F.Cu")
		(net 750)
	)
	(segment
		(start 71.826 78.559)
		(end 71.826 80.1965)
		(width 0.125)
		(layer "F.Cu")
		(net 750)
	)
	(segment
		(start 73.295 78.185)
		(end 72.2 78.185)
		(width 0.125)
		(layer "F.Cu")
		(net 750)
	)
	(via
		(at 74.716454 76.141515)
		(size 0.45)
		(drill 0.1)
		(layers "F.Cu" "B.Cu")
		(net 750)
	)
	(segment
		(start 74.716454 75.958546)
		(end 75.28 75.395)
		(width 0.125)
		(layer "B.Cu")
		(net 750)
	)
	(segment
		(start 74.716454 76.141515)
		(end 74.716454 75.958546)
		(width 0.125)
		(layer "B.Cu")
		(net 750)
	)
	(segment
		(start 55.015 89.35)
		(end 54.81 89.145)
		(width 0.125)
		(layer "F.Cu")
		(net 751)
	)
	(segment
		(start 55.83 89.35)
		(end 55.015 89.35)
		(width 0.125)
		(layer "F.Cu")
		(net 751)
	)
	(segment
		(start 68.74 81.83)
		(end 69.69 81.83)
		(width 0.125)
		(layer "F.Cu")
		(net 752)
	)
	(segment
		(start 69.847323 81.672677)
		(end 69.69 81.83)
		(width 0.125)
		(layer "F.Cu")
		(net 752)
	)
	(segment
		(start 69.847323 80.205136)
		(end 69.847323 81.672677)
		(width 0.125)
		(layer "F.Cu")
		(net 752)
	)
	(segment
		(start 67.347323 80.205136)
		(end 67.347323 81.597323)
		(width 0.125)
		(layer "F.Cu")
		(net 753)
	)
	(segment
		(start 68.21 84.96)
		(end 68.75 85.5)
		(width 0.125)
		(layer "F.Cu")
		(net 753)
	)
	(segment
		(start 67.347323 81.597323)
		(end 68.21 82.46)
		(width 0.125)
		(layer "F.Cu")
		(net 753)
	)
	(segment
		(start 68.21 82.46)
		(end 68.21 84.96)
		(width 0.125)
		(layer "F.Cu")
		(net 753)
	)
	(segment
		(start 68.75 86.47)
		(end 68.75 85.5)
		(width 0.125)
		(layer "F.Cu")
		(net 753)
	)
	(segment
		(start 75.08 86.89)
		(end 74.94 86.75)
		(width 0.125)
		(layer "F.Cu")
		(net 758)
	)
	(segment
		(start 75.53 86.89)
		(end 75.08 86.89)
		(width 0.125)
		(layer "F.Cu")
		(net 758)
	)
	(segment
		(start 75.675 87.475)
		(end 75.675 87.035)
		(width 0.125)
		(layer "F.Cu")
		(net 758)
	)
	(segment
		(start 74.94 86.75)
		(end 74.94 86.34)
		(width 0.125)
		(layer "F.Cu")
		(net 758)
	)
	(segment
		(start 75.675 87.035)
		(end 75.53 86.89)
		(width 0.125)
		(layer "F.Cu")
		(net 758)
	)
	(segment
		(start 62.83 101.5)
		(end 62.85 101.5)
		(width 0.15)
		(layer "F.Cu")
		(net 759)
	)
	(segment
		(start 62.83 100.08)
		(end 63.045 99.865)
		(width 0.15)
		(layer "F.Cu")
		(net 759)
	)
	(segment
		(start 62.83 100.52)
		(end 62.83 101.5)
		(width 0.15)
		(layer "F.Cu")
		(net 759)
	)
	(segment
		(start 62.83 100.52)
		(end 62.83 100.08)
		(width 0.15)
		(layer "F.Cu")
		(net 759)
	)
	(segment
		(start 63.045 99.865)
		(end 63.045 99.375)
		(width 0.15)
		(layer "F.Cu")
		(net 759)
	)
	(segment
		(start 64.61 96.41)
		(end 65.64 96.41)
		(width 0.15)
		(layer "F.Cu")
		(net 760)
	)
	(segment
		(start 65.64 96.41)
		(end 65.75 96.3)
		(width 0.15)
		(layer "F.Cu")
		(net 760)
	)
	(segment
		(start 64.63 98.93)
		(end 64.61 98.91)
		(width 0.15)
		(layer "F.Cu")
		(net 761)
	)
	(segment
		(start 66.81 98.24)
		(end 66.42 98.24)
		(width 0.15)
		(layer "F.Cu")
		(net 761)
	)
	(segment
		(start 66.42 98.24)
		(end 65.73 98.93)
		(width 0.15)
		(layer "F.Cu")
		(net 761)
	)
	(segment
		(start 65.73 98.93)
		(end 64.63 98.93)
		(width 0.15)
		(layer "F.Cu")
		(net 761)
	)
	(via
		(at 66.81 98.24)
		(size 0.45)
		(drill 0.1)
		(layers "F.Cu" "B.Cu")
		(net 761)
	)
	(via
		(at 59.51 94.43)
		(size 0.45)
		(drill 0.1)
		(layers "F.Cu" "B.Cu")
		(net 761)
	)
	(segment
		(start 64.1 98.24)
		(end 66.81 98.24)
		(width 0.15)
		(layer "In1.Cu")
		(net 761)
	)
	(segment
		(start 63.11 94.43)
		(end 63.33 94.65)
		(width 0.15)
		(layer "In1.Cu")
		(net 761)
	)
	(segment
		(start 63.33 97.47)
		(end 64.1 98.24)
		(width 0.15)
		(layer "In1.Cu")
		(net 761)
	)
	(segment
		(start 59.51 94.43)
		(end 63.11 94.43)
		(width 0.15)
		(layer "In1.Cu")
		(net 761)
	)
	(segment
		(start 63.33 94.65)
		(end 63.33 97.47)
		(width 0.15)
		(layer "In1.Cu")
		(net 761)
	)
	(segment
		(start 60.91 100.07)
		(end 61.0425 99.9375)
		(width 0.15)
		(layer "F.Cu")
		(net 762)
	)
	(segment
		(start 61.5825 99.9375)
		(end 61.695 99.825)
		(width 0.15)
		(layer "F.Cu")
		(net 762)
	)
	(segment
		(start 61.695 99.825)
		(end 61.695 99.375)
		(width 0.15)
		(layer "F.Cu")
		(net 762)
	)
	(segment
		(start 60.91 100.52)
		(end 60.91 100.07)
		(width 0.15)
		(layer "F.Cu")
		(net 762)
	)
	(segment
		(start 61.0425 99.9375)
		(end 61.5825 99.9375)
		(width 0.15)
		(layer "F.Cu")
		(net 762)
	)
	(segment
		(start 66.34 96.525528)
		(end 66.39 96.475528)
		(width 0.125)
		(layer "F.Cu")
		(net 764)
	)
	(segment
		(start 61.245431 101.5)
		(end 61.89 101.5)
		(width 0.15)
		(layer "F.Cu")
		(net 764)
	)
	(segment
		(start 66.39 94.9)
		(end 66.39 94.35)
		(width 0.125)
		(layer "F.Cu")
		(net 764)
	)
	(segment
		(start 65.305528 97.56)
		(end 64.61 97.56)
		(width 0.125)
		(layer "F.Cu")
		(net 764)
	)
	(segment
		(start 66.34 96.525528)
		(end 65.305528 97.56)
		(width 0.125)
		(layer "F.Cu")
		(net 764)
	)
	(segment
		(start 66.39 96.475528)
		(end 66.39 94.9)
		(width 0.125)
		(layer "F.Cu")
		(net 764)
	)
	(segment
		(start 60.848714 101.896717)
		(end 61.245431 101.5)
		(width 0.15)
		(layer "F.Cu")
		(net 764)
	)
	(via
		(at 60.848714 101.896717)
		(size 0.45)
		(drill 0.1)
		(layers "F.Cu" "B.Cu")
		(net 764)
	)
	(via
		(at 66.39 94.9)
		(size 0.45)
		(drill 0.1)
		(layers "F.Cu" "B.Cu")
		(net 764)
	)
	(segment
		(start 68.025 98.285)
		(end 66.91 99.4)
		(width 0.15)
		(layer "In1.Cu")
		(net 764)
	)
	(segment
		(start 63.35 99.4)
		(end 60.853283 101.896717)
		(width 0.15)
		(layer "In1.Cu")
		(net 764)
	)
	(segment
		(start 68.025 96.535)
		(end 68.025 98.285)
		(width 0.15)
		(layer "In1.Cu")
		(net 764)
	)
	(segment
		(start 60.853283 101.896717)
		(end 60.848714 101.896717)
		(width 0.15)
		(layer "In1.Cu")
		(net 764)
	)
	(segment
		(start 66.39 94.9)
		(end 68.025 96.535)
		(width 0.15)
		(layer "In1.Cu")
		(net 764)
	)
	(segment
		(start 66.91 99.4)
		(end 63.35 99.4)
		(width 0.15)
		(layer "In1.Cu")
		(net 764)
	)
	(segment
		(start 65.13 95.96)
		(end 64.61 95.96)
		(width 0.15)
		(layer "F.Cu")
		(net 765)
	)
	(segment
		(start 65.75 95.34)
		(end 65.13 95.96)
		(width 0.15)
		(layer "F.Cu")
		(net 765)
	)
	(segment
		(start 63.945 99.835)
		(end 64.01 99.9)
		(width 0.125)
		(layer "F.Cu")
		(net 766)
	)
	(segment
		(start 66.69 99.99)
		(end 66.69 98.93)
		(width 0.125)
		(layer "F.Cu")
		(net 766)
	)
	(segment
		(start 63.945 99.375)
		(end 63.945 99.835)
		(width 0.125)
		(layer "F.Cu")
		(net 766)
	)
	(segment
		(start 66.15 99.47)
		(end 66.69 98.93)
		(width 0.125)
		(layer "F.Cu")
		(net 766)
	)
	(segment
		(start 64.84 99.47)
		(end 66.15 99.47)
		(width 0.125)
		(layer "F.Cu")
		(net 766)
	)
	(segment
		(start 64.01 99.9)
		(end 64.41 99.9)
		(width 0.125)
		(layer "F.Cu")
		(net 766)
	)
	(segment
		(start 64.41 99.9)
		(end 64.84 99.47)
		(width 0.125)
		(layer "F.Cu")
		(net 766)
	)
	(segment
		(start 66.69 96.66)
		(end 66.8725 96.4775)
		(width 0.125)
		(layer "F.Cu")
		(net 767)
	)
	(segment
		(start 66.8725 96.4775)
		(end 66.8725 93.8325)
		(width 0.125)
		(layer "F.Cu")
		(net 767)
	)
	(segment
		(start 65.34 98.01)
		(end 64.61 98.01)
		(width 0.125)
		(layer "F.Cu")
		(net 767)
	)
	(segment
		(start 66.8725 93.8325)
		(end 66.39 93.35)
		(width 0.125)
		(layer "F.Cu")
		(net 767)
	)
	(segment
		(start 66.69 96.66)
		(end 65.34 98.01)
		(width 0.125)
		(layer "F.Cu")
		(net 767)
	)
	(segment
		(start 59.36 89.552)
		(end 59.321217 89.590783)
		(width 0.125)
		(layer "B.Cu")
		(net 768)
	)
	(segment
		(start 59.321217 89.590783)
		(end 59.321217 89.695419)
		(width 0.125)
		(layer "B.Cu")
		(net 768)
	)
	(segment
		(start 57.934627 91.690373)
		(end 57.32 92.305)
		(width 0.125)
		(layer "B.Cu")
		(net 768)
	)
	(segment
		(start 57.32 92.305)
		(end 57.32 93.565)
		(width 0.125)
		(layer "B.Cu")
		(net 768)
	)
	(segment
		(start 57.934627 90.95)
		(end 57.934627 90.745373)
		(width 0.125)
		(layer "B.Cu")
		(net 768)
	)
	(segment
		(start 57.934627 90.745373)
		(end 58.101682 90.578318)
		(width 0.125)
		(layer "B.Cu")
		(net 768)
	)
	(segment
		(start 57.32 93.565)
		(end 57.905 94.15)
		(width 0.125)
		(layer "B.Cu")
		(net 768)
	)
	(segment
		(start 57.934627 90.95)
		(end 57.934627 91.690373)
		(width 0.125)
		(layer "B.Cu")
		(net 768)
	)
	(segment
		(start 58.101682 90.578318)
		(end 58.306309 90.578318)
		(width 0.125)
		(layer "B.Cu")
		(net 768)
	)
	(segment
		(start 58.438318 90.578318)
		(end 58.306309 90.578318)
		(width 0.125)
		(layer "B.Cu")
		(net 768)
	)
	(segment
		(start 59.321217 89.695419)
		(end 58.438318 90.578318)
		(width 0.125)
		(layer "B.Cu")
		(net 768)
	)
	(segment
		(start 61.64 98.46)
		(end 61.68 98.42)
		(width 0.15)
		(layer "F.Cu")
		(net 769)
	)
	(segment
		(start 78.175 87.475)
		(end 78.175 86.365)
		(width 0.15)
		(layer "F.Cu")
		(net 771)
	)
	(segment
		(start 78.175 86.365)
		(end 78.17 86.36)
		(width 0.15)
		(layer "F.Cu")
		(net 771)
	)
	(segment
		(start 83.81 123.09)
		(end 83.81 122.408)
		(width 0.125)
		(layer "B.Cu")
		(net 772)
	)
	(segment
		(start 85.179 125.8885)
		(end 84.54 125.2495)
		(width 0.125)
		(layer "B.Cu")
		(net 772)
	)
	(segment
		(start 84.54 123.82)
		(end 83.81 123.09)
		(width 0.125)
		(layer "B.Cu")
		(net 772)
	)
	(segment
		(start 84.54 125.2495)
		(end 84.54 123.82)
		(width 0.125)
		(layer "B.Cu")
		(net 772)
	)
	(segment
		(start 85.627049 122.968531)
		(end 84.18558 124.41)
		(width 0.15)
		(layer "F.Cu")
		(net 773)
	)
	(segment
		(start 82.559502 124.41)
		(end 82.069502 123.92)
		(width 0.15)
		(layer "F.Cu")
		(net 773)
	)
	(segment
		(start 84.18558 124.41)
		(end 82.559502 124.41)
		(width 0.15)
		(layer "F.Cu")
		(net 773)
	)
	(via
		(at 85.627049 122.968531)
		(size 0.45)
		(drill 0.1)
		(layers "F.Cu" "B.Cu")
		(net 773)
	)
	(via
		(at 82.069502 123.92)
		(size 0.45)
		(drill 0.1)
		(layers "F.Cu" "B.Cu")
		(net 773)
	)
	(segment
		(start 85.627049 122.968531)
		(end 85.412 122.753482)
		(width 0.125)
		(layer "B.Cu")
		(net 773)
	)
	(segment
		(start 81.37 124.6195)
		(end 82.069502 123.92)
		(width 0.125)
		(layer "B.Cu")
		(net 773)
	)
	(segment
		(start 82.069502 123.92)
		(end 82.612 123.377502)
		(width 0.125)
		(layer "B.Cu")
		(net 773)
	)
	(segment
		(start 85.412 122.753482)
		(end 85.412 122.378)
		(width 0.125)
		(layer "B.Cu")
		(net 773)
	)
	(segment
		(start 82.612 123.377502)
		(end 82.612 122.408)
		(width 0.125)
		(layer "B.Cu")
		(net 773)
	)
	(segment
		(start 84.265 123.715)
		(end 85.01 122.97)
		(width 0.125)
		(layer "F.Cu")
		(net 774)
	)
	(segment
		(start 83.695 123.715)
		(end 84.265 123.715)
		(width 0.125)
		(layer "F.Cu")
		(net 774)
	)
	(via
		(at 85.01 122.97)
		(size 0.45)
		(drill 0.1)
		(layers "F.Cu" "B.Cu")
		(net 774)
	)
	(via
		(at 83.695 123.715)
		(size 0.45)
		(drill 0.1)
		(layers "F.Cu" "B.Cu")
		(net 774)
	)
	(segment
		(start 83.909 123.929)
		(end 83.909 124.6195)
		(width 0.125)
		(layer "B.Cu")
		(net 774)
	)
	(segment
		(start 83.902 124.6125)
		(end 83.909 124.6195)
		(width 0.15)
		(layer "B.Cu")
		(net 774)
	)
	(segment
		(start 83.412 123.432)
		(end 83.412 122.408)
		(width 0.125)
		(layer "B.Cu")
		(net 774)
	)
	(segment
		(start 85.01 122.97)
		(end 85.01 122.378)
		(width 0.125)
		(layer "B.Cu")
		(net 774)
	)
	(segment
		(start 83.695 123.715)
		(end 83.909 123.929)
		(width 0.125)
		(layer "B.Cu")
		(net 774)
	)
	(segment
		(start 83.695 123.715)
		(end 83.412 123.432)
		(width 0.125)
		(layer "B.Cu")
		(net 774)
	)
	(segment
		(start 85.68 122.4)
		(end 86.25 122.97)
		(width 0.15)
		(layer "F.Cu")
		(net 779)
	)
	(segment
		(start 84.409 122.4)
		(end 85.68 122.4)
		(width 0.15)
		(layer "F.Cu")
		(net 779)
	)
	(via
		(at 86.25 122.97)
		(size 0.45)
		(drill 0.1)
		(layers "F.Cu" "B.Cu")
		(net 779)
	)
	(segment
		(start 86.25 122.97)
		(end 85.81 122.53)
		(width 0.125)
		(layer "B.Cu")
		(net 779)
	)
	(segment
		(start 85.81 122.53)
		(end 85.81 122.378)
		(width 0.125)
		(layer "B.Cu")
		(net 779)
	)
	(via
		(at 51.031046 117.521569)
		(size 0.45)
		(drill 0.1)
		(layers "F.Cu" "B.Cu")
		(net 780)
	)
	(via
		(at 51.037587 111.944372)
		(size 0.45)
		(drill 0.1)
		(layers "F.Cu" "B.Cu")
		(net 780)
	)
	(segment
		(start 51.031046 117.521569)
		(end 51.025 117.515523)
		(width 0.15)
		(layer "In5.Cu")
		(net 780)
	)
	(segment
		(start 51.025 115.775)
		(end 51.3 115.5)
		(width 0.15)
		(layer "In5.Cu")
		(net 780)
	)
	(segment
		(start 51.025 117.515523)
		(end 51.025 115.775)
		(width 0.15)
		(layer "In5.Cu")
		(net 780)
	)
	(segment
		(start 51.3 115.5)
		(end 51.3 112.206785)
		(width 0.15)
		(layer "In5.Cu")
		(net 780)
	)
	(segment
		(start 51.3 112.206785)
		(end 51.037587 111.944372)
		(width 0.15)
		(layer "In5.Cu")
		(net 780)
	)
	(segment
		(start 50.53 111.7745)
		(end 50.867715 111.7745)
		(width 0.15)
		(layer "B.Cu")
		(net 780)
	)
	(segment
		(start 51.368215 112.275)
		(end 51.037587 111.944372)
		(width 0.15)
		(layer "B.Cu")
		(net 780)
	)
	(segment
		(start 51.031046 117.521046)
		(end 50.46 116.95)
		(width 0.15)
		(layer "B.Cu")
		(net 780)
	)
	(segment
		(start 50.867715 111.7745)
		(end 51.037587 111.944372)
		(width 0.15)
		(layer "B.Cu")
		(net 780)
	)
	(segment
		(start 51.5 112.275)
		(end 51.368215 112.275)
		(width 0.15)
		(layer "B.Cu")
		(net 780)
	)
	(segment
		(start 51.031046 117.521569)
		(end 51.031046 117.521046)
		(width 0.15)
		(layer "B.Cu")
		(net 780)
	)
	(segment
		(start 51.8 93.525)
		(end 51.8 102.9)
		(width 0.125)
		(layer "F.Cu")
		(net 787)
	)
	(segment
		(start 52.675 79.65)
		(end 49.84 79.65)
		(width 0.125)
		(layer "F.Cu")
		(net 787)
	)
	(segment
		(start 52.5 88.28)
		(end 53.68 88.28)
		(width 0.125)
		(layer "F.Cu")
		(net 787)
	)
	(segment
		(start 49.34 80.15)
		(end 49.34 85.12)
		(width 0.125)
		(layer "F.Cu")
		(net 787)
	)
	(segment
		(start 53.68 88.28)
		(end 54.2975 88.8975)
		(width 0.125)
		(layer "F.Cu")
		(net 787)
	)
	(segment
		(start 54.2975 88.8975)
		(end 54.2975 91.2475)
		(width 0.125)
		(layer "F.Cu")
		(net 787)
	)
	(segment
		(start 50.7 104)
		(end 49.12 104)
		(width 0.125)
		(layer "F.Cu")
		(net 787)
	)
	(segment
		(start 51.8 102.9)
		(end 50.7 104)
		(width 0.125)
		(layer "F.Cu")
		(net 787)
	)
	(segment
		(start 54.2975 91.2475)
		(end 54.0775 91.2475)
		(width 0.125)
		(layer "F.Cu")
		(net 787)
	)
	(segment
		(start 53.2175 78.13)
		(end 53.2175 79.1075)
		(width 0.125)
		(layer "F.Cu")
		(net 787)
	)
	(segment
		(start 56.04 91.84)
		(end 56.04 92.59)
		(width 0.125)
		(layer "F.Cu")
		(net 787)
	)
	(segment
		(start 54.675 91.625)
		(end 55.825 91.625)
		(width 0.125)
		(layer "F.Cu")
		(net 787)
	)
	(segment
		(start 54.2975 91.2475)
		(end 54.675 91.625)
		(width 0.125)
		(layer "F.Cu")
		(net 787)
	)
	(segment
		(start 49.84 79.65)
		(end 49.34 80.15)
		(width 0.125)
		(layer "F.Cu")
		(net 787)
	)
	(segment
		(start 54.0775 91.2475)
		(end 51.8 93.525)
		(width 0.125)
		(layer "F.Cu")
		(net 787)
	)
	(segment
		(start 49.12 104)
		(end 48.3 104.82)
		(width 0.125)
		(layer "F.Cu")
		(net 787)
	)
	(segment
		(start 55.825 91.625)
		(end 56.04 91.84)
		(width 0.125)
		(layer "F.Cu")
		(net 787)
	)
	(segment
		(start 49.34 85.12)
		(end 52.5 88.28)
		(width 0.125)
		(layer "F.Cu")
		(net 787)
	)
	(segment
		(start 53.2175 79.1075)
		(end 52.675 79.65)
		(width 0.125)
		(layer "F.Cu")
		(net 787)
	)
	(via
		(at 60.45 90.825)
		(size 0.45)
		(drill 0.1)
		(layers "F.Cu" "B.Cu")
		(free yes)
		(net 787)
	)
	(via
		(at 57.35 91.625)
		(size 0.45)
		(drill 0.1)
		(layers "F.Cu" "B.Cu")
		(free yes)
		(net 787)
	)
	(via
		(at 58.8 91.150001)
		(size 0.45)
		(drill 0.1)
		(layers "F.Cu" "B.Cu")
		(free yes)
		(net 787)
	)
	(via
		(at 58.025 88.95)
		(size 0.45)
		(drill 0.1)
		(layers "F.Cu" "B.Cu")
		(free yes)
		(net 787)
	)
	(via
		(at 59.07 90.65)
		(size 0.45)
		(drill 0.1)
		(layers "F.Cu" "B.Cu")
		(free yes)
		(net 787)
	)
	(via
		(at 53.2175 78.13)
		(size 0.45)
		(drill 0.1)
		(layers "F.Cu" "B.Cu")
		(net 787)
	)
	(via
		(at 60.45 90.325)
		(size 0.45)
		(drill 0.1)
		(layers "F.Cu" "B.Cu")
		(free yes)
		(net 787)
	)
	(via
		(at 59.3 91.15)
		(size 0.45)
		(drill 0.1)
		(layers "F.Cu" "B.Cu")
		(free yes)
		(net 787)
	)
	(via
		(at 56.775 91.8)
		(size 0.45)
		(drill 0.1)
		(layers "F.Cu" "B.Cu")
		(free yes)
		(net 787)
	)
	(via
		(at 59.43 90.29)
		(size 0.45)
		(drill 0.1)
		(layers "F.Cu" "B.Cu")
		(free yes)
		(net 787)
	)
	(via
		(at 60.45 91.375)
		(size 0.45)
		(drill 0.1)
		(layers "F.Cu" "B.Cu")
		(free yes)
		(net 787)
	)
	(segment
		(start 53.3275 78.24)
		(end 54.2 78.24)
		(width 0.125)
		(layer "B.Cu")
		(net 787)
	)
	(segment
		(start 53.2175 78.13)
		(end 53.3275 78.24)
		(width 0.125)
		(layer "B.Cu")
		(net 787)
	)
	(segment
		(start 56.83 94.035)
		(end 56.945 94.15)
		(width 0.125)
		(layer "B.Cu")
		(net 787)
	)
	(segment
		(start 56.83 91.855)
		(end 56.83 94.035)
		(width 0.125)
		(layer "B.Cu")
		(net 787)
	)
	(segment
		(start 56.775 91.8)
		(end 56.83 91.855)
		(width 0.125)
		(layer "B.Cu")
		(net 787)
	)
	(via
		(at 50.07 81.28)
		(size 0.45)
		(drill 0.1)
		(layers "F.Cu" "B.Cu")
		(free yes)
		(net 788)
	)
	(via
		(at 50.73 82.25)
		(size 0.45)
		(drill 0.1)
		(layers "F.Cu" "B.Cu")
		(free yes)
		(net 788)
	)
	(via
		(at 56.962771 87.825)
		(size 0.45)
		(drill 0.1)
		(layers "F.Cu" "B.Cu")
		(free yes)
		(net 788)
	)
	(via
		(at 50.16 82.24)
		(size 0.45)
		(drill 0.1)
		(layers "F.Cu" "B.Cu")
		(free yes)
		(net 788)
	)
	(via
		(at 56.962771 86.7)
		(size 0.45)
		(drill 0.1)
		(layers "F.Cu" "B.Cu")
		(free yes)
		(net 788)
	)
	(via
		(at 50.36 81.74)
		(size 0.45)
		(drill 0.1)
		(layers "F.Cu" "B.Cu")
		(free yes)
		(net 788)
	)
	(via
		(at 56.962771 88.375)
		(size 0.45)
		(drill 0.1)
		(layers "F.Cu" "B.Cu")
		(free yes)
		(net 788)
	)
	(via
		(at 50.95 81.73)
		(size 0.45)
		(drill 0.1)
		(layers "F.Cu" "B.Cu")
		(free yes)
		(net 788)
	)
	(via
		(at 56.962771 87.275)
		(size 0.45)
		(drill 0.1)
		(layers "F.Cu" "B.Cu")
		(free yes)
		(net 788)
	)
	(via
		(at 57.375 86.25)
		(size 0.45)
		(drill 0.1)
		(layers "F.Cu" "B.Cu")
		(free yes)
		(net 788)
	)
	(via
		(at 50.41 82.75)
		(size 0.45)
		(drill 0.1)
		(layers "F.Cu" "B.Cu")
		(free yes)
		(net 788)
	)
	(via
		(at 50.661689 81.289817)
		(size 0.45)
		(drill 0.1)
		(layers "F.Cu" "B.Cu")
		(free yes)
		(net 788)
	)
	(via
		(at 51.240541 81.297835)
		(size 0.45)
		(drill 0.1)
		(layers "F.Cu" "B.Cu")
		(free yes)
		(net 788)
	)
	(segment
		(start 70.117427 71.955073)
		(end 70.076 71.9965)
		(width 0.125)
		(layer "F.Cu")
		(net 789)
	)
	(segment
		(start 70.117427 70.642571)
		(end 70.117427 71.955073)
		(width 0.125)
		(layer "F.Cu")
		(net 789)
	)
	(segment
		(start 70.349998 70.41)
		(end 70.117427 70.642571)
		(width 0.125)
		(layer "F.Cu")
		(net 789)
	)
	(via
		(at 70.349998 70.41)
		(size 0.45)
		(drill 0.1)
		(layers "F.Cu" "B.Cu")
		(net 789)
	)
	(segment
		(start 63.7 72)
		(end 62.72 72)
		(width 0.125)
		(layer "B.Cu")
		(net 789)
	)
	(segment
		(start 54.85 77.68)
		(end 54.85 78.55)
		(width 0.125)
		(layer "B.Cu")
		(net 789)
	)
	(segment
		(start 55.09 74.66)
		(end 54.37 75.38)
		(width 0.125)
		(layer "B.Cu")
		(net 789)
	)
	(segment
		(start 70.139998 70.62)
		(end 65.08 70.62)
		(width 0.125)
		(layer "B.Cu")
		(net 789)
	)
	(segment
		(start 62.72 72)
		(end 61.07 70.35)
		(width 0.125)
		(layer "B.Cu")
		(net 789)
	)
	(segment
		(start 65.08 70.62)
		(end 63.7 72)
		(width 0.125)
		(layer "B.Cu")
		(net 789)
	)
	(segment
		(start 52.77 77.63)
		(end 53.94 77.63)
		(width 0.125)
		(layer "B.Cu")
		(net 789)
	)
	(segment
		(start 61.07 70.35)
		(end 57.07 70.35)
		(width 0.125)
		(layer "B.Cu")
		(net 789)
	)
	(segment
		(start 70.349998 70.41)
		(end 70.139998 70.62)
		(width 0.125)
		(layer "B.Cu")
		(net 789)
	)
	(segment
		(start 57.07 70.35)
		(end 55.09 72.33)
		(width 0.125)
		(layer "B.Cu")
		(net 789)
	)
	(segment
		(start 53.94 77.63)
		(end 54.26 77.31)
		(width 0.125)
		(layer "B.Cu")
		(net 789)
	)
	(segment
		(start 54.37 77.2)
		(end 54.485 77.315)
		(width 0.125)
		(layer "B.Cu")
		(net 789)
	)
	(segment
		(start 54.26 77.31)
		(end 54.48 77.31)
		(width 0.125)
		(layer "B.Cu")
		(net 789)
	)
	(segment
		(start 52.175 80.175)
		(end 52.175 79.715)
		(width 0.125)
		(layer "B.Cu")
		(net 789)
	)
	(segment
		(start 54.85 78.55)
		(end 53.575 79.825)
		(width 0.125)
		(layer "B.Cu")
		(net 789)
	)
	(segment
		(start 54.26 77.31)
		(end 54.37 77.2)
		(width 0.125)
		(layer "B.Cu")
		(net 789)
	)
	(segment
		(start 54.37 75.38)
		(end 54.37 77.2)
		(width 0.125)
		(layer "B.Cu")
		(net 789)
	)
	(segment
		(start 55.09 72.33)
		(end 55.09 74.66)
		(width 0.125)
		(layer "B.Cu")
		(net 789)
	)
	(segment
		(start 52.175 79.715)
		(end 51.99 79.53)
		(width 0.125)
		(layer "B.Cu")
		(net 789)
	)
	(segment
		(start 51.99 79.53)
		(end 51.99 78.41)
		(width 0.125)
		(layer "B.Cu")
		(net 789)
	)
	(segment
		(start 54.485 77.315)
		(end 54.85 77.68)
		(width 0.125)
		(layer "B.Cu")
		(net 789)
	)
	(segment
		(start 54.48 77.31)
		(end 54.485 77.315)
		(width 0.125)
		(layer "B.Cu")
		(net 789)
	)
	(segment
		(start 53.575 79.825)
		(end 53.575 80.175)
		(width 0.125)
		(layer "B.Cu")
		(net 789)
	)
	(segment
		(start 51.99 78.41)
		(end 52.77 77.63)
		(width 0.125)
		(layer "B.Cu")
		(net 789)
	)
	(segment
		(start 54.9 90.85)
		(end 55.475 90.275)
		(width 0.15)
		(layer "F.Cu")
		(net 790)
	)
	(segment
		(start 55.475 90.275)
		(end 55.83 90.275)
		(width 0.15)
		(layer "F.Cu")
		(net 790)
	)
	(via
		(at 56.750964 85.659445)
		(size 0.45)
		(drill 0.1)
		(layers "F.Cu" "B.Cu")
		(net 790)
	)
	(via
		(at 54.9 90.85)
		(size 0.45)
		(drill 0.1)
		(layers "F.Cu" "B.Cu")
		(net 790)
	)
	(segment
		(start 55.8 86.610409)
		(end 56.750964 85.659445)
		(width 0.15)
		(layer "In5.Cu")
		(net 790)
	)
	(segment
		(start 54.9 90.85)
		(end 55.8 89.95)
		(width 0.15)
		(layer "In5.Cu")
		(net 790)
	)
	(segment
		(start 55.8 89.95)
		(end 55.8 86.610409)
		(width 0.15)
		(layer "In5.Cu")
		(net 790)
	)
	(segment
		(start 56.305096 85.425)
		(end 56.516519 85.425)
		(width 0.15)
		(layer "B.Cu")
		(net 790)
	)
	(segment
		(start 55.555 84.674904)
		(end 56.305096 85.425)
		(width 0.15)
		(layer "B.Cu")
		(net 790)
	)
	(segment
		(start 56.516519 85.425)
		(end 56.750964 85.659445)
		(width 0.15)
		(layer "B.Cu")
		(net 790)
	)
	(segment
		(start 55.555 84.25)
		(end 55.555 84.674904)
		(width 0.15)
		(layer "B.Cu")
		(net 790)
	)
	(segment
		(start 53.79 83.74)
		(end 54.26 83.27)
		(width 0.15)
		(layer "B.Cu")
		(net 791)
	)
	(segment
		(start 52.65 82.35)
		(end 52.45 82.55)
		(width 0.15)
		(layer "B.Cu")
		(net 791)
	)
	(segment
		(start 52.45 83.5)
		(end 52.69 83.74)
		(width 0.15)
		(layer "B.Cu")
		(net 791)
	)
	(segment
		(start 52.45 82.55)
		(end 52.45 83.5)
		(width 0.15)
		(layer "B.Cu")
		(net 791)
	)
	(segment
		(start 54.26 83.27)
		(end 54.26 83.2)
		(width 0.15)
		(layer "B.Cu")
		(net 791)
	)
	(segment
		(start 52.65 81.975)
		(end 52.65 82.35)
		(width 0.15)
		(layer "B.Cu")
		(net 791)
	)
	(segment
		(start 52.69 83.74)
		(end 53.79 83.74)
		(width 0.15)
		(layer "B.Cu")
		(net 791)
	)
	(segment
		(start 57.875 89.825)
		(end 58.2175 89.4825)
		(width 0.125)
		(layer "F.Cu")
		(net 792)
	)
	(segment
		(start 57.63 89.825)
		(end 57.875 89.825)
		(width 0.125)
		(layer "F.Cu")
		(net 792)
	)
	(segment
		(start 58.2175 89.4825)
		(end 58.301669 89.4825)
		(width 0.125)
		(layer "F.Cu")
		(net 792)
	)
	(segment
		(start 57.99 92.77)
		(end 57.99 92.22)
		(width 0.125)
		(layer "F.Cu")
		(net 792)
	)
	(via
		(at 57.99 92.22)
		(size 0.45)
		(drill 0.1)
		(layers "F.Cu" "B.Cu")
		(net 792)
	)
	(via
		(at 58.301669 89.4825)
		(size 0.45)
		(drill 0.1)
		(layers "F.Cu" "B.Cu")
		(net 792)
	)
	(segment
		(start 58.71 90.41)
		(end 58.71 89.890831)
		(width 0.125)
		(layer "In3.Cu")
		(net 792)
	)
	(segment
		(start 57.99 91.13)
		(end 58.71 90.41)
		(width 0.125)
		(layer "In3.Cu")
		(net 792)
	)
	(segment
		(start 57.99 92.22)
		(end 57.99 91.13)
		(width 0.125)
		(layer "In3.Cu")
		(net 792)
	)
	(segment
		(start 58.71 89.890831)
		(end 58.301669 89.4825)
		(width 0.125)
		(layer "In3.Cu")
		(net 792)
	)
	(segment
		(start 47 104.325)
		(end 46.375 104.325)
		(width 0.15)
		(layer "F.Cu")
		(net 793)
	)
	(segment
		(start 46.15 104.55)
		(end 46.15 105.175)
		(width 0.15)
		(layer "F.Cu")
		(net 793)
	)
	(segment
		(start 46.375 104.325)
		(end 46.15 104.55)
		(width 0.15)
		(layer "F.Cu")
		(net 793)
	)
	(via
		(at 46.15 105.175)
		(size 0.45)
		(drill 0.1)
		(layers "F.Cu" "B.Cu")
		(net 793)
	)
	(via
		(at 47.95 72.775)
		(size 0.45)
		(drill 0.1)
		(layers "F.Cu" "B.Cu")
		(net 793)
	)
	(segment
		(start 46.65 101.875)
		(end 46.65 104.675)
		(width 0.15)
		(layer "In3.Cu")
		(net 793)
	)
	(segment
		(start 46.65 97.85)
		(end 46.65 101.875)
		(width 0.15)
		(layer "In3.Cu")
		(net 793)
	)
	(segment
		(start 49 95.5)
		(end 46.925 97.575)
		(width 0.15)
		(layer "In3.Cu")
		(net 793)
	)
	(segment
		(start 47.95 72.775)
		(end 47.95 73.875)
		(width 0.15)
		(layer "In3.Cu")
		(net 793)
	)
	(segment
		(start 46.925 97.575)
		(end 46.65 97.85)
		(width 0.15)
		(layer "In3.Cu")
		(net 793)
	)
	(segment
		(start 49 74.925)
		(end 49 95.5)
		(width 0.15)
		(layer "In3.Cu")
		(net 793)
	)
	(segment
		(start 47.95 73.875)
		(end 49 74.925)
		(width 0.15)
		(layer "In3.Cu")
		(net 793)
	)
	(segment
		(start 46.65 104.675)
		(end 46.15 105.175)
		(width 0.15)
		(layer "In3.Cu")
		(net 793)
	)
	(segment
		(start 48.6 73.025)
		(end 48.35 72.775)
		(width 0.15)
		(layer "B.Cu")
		(net 793)
	)
	(segment
		(start 48.35 72.775)
		(end 47.95 72.775)
		(width 0.15)
		(layer "B.Cu")
		(net 793)
	)
	(segment
		(start 48.7 73.125)
		(end 48.6 73.025)
		(width 0.15)
		(layer "B.Cu")
		(net 793)
	)
	(segment
		(start 48.7 73.647999)
		(end 48.7 73.125)
		(width 0.15)
		(layer "B.Cu")
		(net 793)
	)
	(segment
		(start 48.245 105.725)
		(end 48.3 105.78)
		(width 0.15)
		(layer "F.Cu")
		(net 798)
	)
	(segment
		(start 47 105.725)
		(end 48.245 105.725)
		(width 0.15)
		(layer "F.Cu")
		(net 798)
	)
	(segment
		(start 51.6 74.425)
		(end 52.125 74.95)
		(width 0.15)
		(layer "F.Cu")
		(net 799)
	)
	(segment
		(start 50.975 74.425)
		(end 51.6 74.425)
		(width 0.15)
		(layer "F.Cu")
		(net 799)
	)
	(segment
		(start 52.125 76.325)
		(end 52.6 76.8)
		(width 0.15)
		(layer "F.Cu")
		(net 799)
	)
	(segment
		(start 52.6 76.8)
		(end 52.6 78.5)
		(width 0.15)
		(layer "F.Cu")
		(net 799)
	)
	(segment
		(start 52.125 74.95)
		(end 52.125 76.325)
		(width 0.15)
		(layer "F.Cu")
		(net 799)
	)
	(via
		(at 50.975 74.425)
		(size 0.45)
		(drill 0.1)
		(layers "F.Cu" "B.Cu")
		(net 799)
	)
	(via
		(at 52.6 78.5)
		(size 0.45)
		(drill 0.1)
		(layers "F.Cu" "B.Cu")
		(net 799)
	)
	(segment
		(start 49.2 74.95)
		(end 49.65 74.95)
		(width 0.15)
		(layer "B.Cu")
		(net 799)
	)
	(segment
		(start 50.4 74.775)
		(end 50.75 74.425)
		(width 0.15)
		(layer "B.Cu")
		(net 799)
	)
	(segment
		(start 49.65 74.95)
		(end 49.82 74.78)
		(width 0.15)
		(layer "B.Cu")
		(net 799)
	)
	(segment
		(start 53.2 79.64)
		(end 53.1 79.74)
		(width 0.125)
		(layer "B.Cu")
		(net 799)
	)
	(segment
		(start 49.82 74.78)
		(end 50.4 74.78)
		(width 0.15)
		(layer "B.Cu")
		(net 799)
	)
	(segment
		(start 50.75 74.425)
		(end 50.975 74.425)
		(width 0.15)
		(layer "B.Cu")
		(net 799)
	)
	(segment
		(start 50.4 74.78)
		(end 50.4 74.775)
		(width 0.15)
		(layer "B.Cu")
		(net 799)
	)
	(segment
		(start 53.19 79.09)
		(end 52.6 78.5)
		(width 0.15)
		(layer "B.Cu")
		(net 799)
	)
	(segment
		(start 53.2 79.2)
		(end 53.2 79.64)
		(width 0.125)
		(layer "B.Cu")
		(net 799)
	)
	(segment
		(start 53.1 79.74)
		(end 53.1 80.175)
		(width 0.125)
		(layer "B.Cu")
		(net 799)
	)
	(segment
		(start 53.23 79.09)
		(end 53.19 79.09)
		(width 0.15)
		(layer "B.Cu")
		(net 799)
	)
	(zone
		(net 482)
		(net_name "/Peripherals/3V3_CONN")
		(layer "F.Cu")
		(hatch edge 0.508)
		(connect_pads yes
			(clearance 0.2)
		)
		(min_thickness 0.254)
		(filled_areas_thickness no)
		(fill yes
			(thermal_gap 0.508)
			(thermal_bridge_width 5)
		)
		(polygon
			(pts
				(xy 142.2 110.7) (xy 140.8 110.7) (xy 138.5 111.2) (xy 137.3 111.2) (xy 137.3 108.9) (xy 138.3 108.9)
				(xy 138.3 110) (xy 140.8 109.1) (xy 142.2 109.1)
			)
		)
	)
	(zone
		(net 99)
		(net_name "+5V")
		(layer "F.Cu")
		(hatch edge 0.508)
		(priority 2)
		(connect_pads yes
			(clearance 0.2)
		)
		(min_thickness 0.254)
		(filled_areas_thickness no)
		(fill yes
			(thermal_gap 0.508)
			(thermal_bridge_width 5)
		)
		(polygon
			(pts
				(xy 70.3 119.1) (xy 68 119.1) (xy 68 118) (xy 68.4 117.6) (xy 68.4 116.1) (xy 70.3 116.1)
			)
		)
	)
	(zone
		(net 485)
		(net_name "/Peripherals/VCC_CONN")
		(layer "F.Cu")
		(hatch edge 0.508)
		(connect_pads yes
			(clearance 0.2)
		)
		(min_thickness 0.254)
		(filled_areas_thickness no)
		(fill yes
			(thermal_gap 0.508)
			(thermal_bridge_width 0.508)
		)
		(polygon
			(pts
				(xy 147.3 119.9) (xy 143.8 119.9) (xy 143.8 113.2) (xy 147.3 113.2)
			)
		)
	)
	(zone
		(net 769)
		(net_name "unconnected-(U1-GL-Pad10)")
		(layer "F.Cu")
		(hatch edge 0.5)
		(priority 15)
		(connect_pads yes
			(clearance 0)
		)
		(min_thickness 0.25)
		(filled_areas_thickness no)
		(fill yes
			(thermal_gap 0.5)
			(thermal_bridge_width 0.5)
		)
		(polygon
			(pts
				(xy 61.395 99.666) (xy 61.396 98.981) (xy 61.79 98.71) (xy 61.86 98.61) (xy 61.79 98.13) (xy 61.34 98.13)
				(xy 61.14 98.31) (xy 60.44 98.31) (xy 60.373 98.538) (xy 61.107 99.703) (xy 61.245 99.7375)
			)
		)
	)
	(zone
		(net 99)
		(net_name "+5V")
		(layer "F.Cu")
		(hatch edge 0.508)
		(connect_pads yes
			(clearance 0.2)
		)
		(min_thickness 0.254)
		(filled_areas_thickness no)
		(fill yes
			(thermal_gap 0.508)
			(thermal_bridge_width 5)
		)
		(polygon
			(pts
				(xy 137 115) (xy 135.75 115) (xy 135.75 116.75) (xy 137.25 116.75) (xy 137.25 118.75) (xy 134.5 118.75)
				(xy 134.5 113.75) (xy 137 113.75)
			)
		)
	)
	(zone
		(net 1)
		(net_name "GND")
		(layer "F.Cu")
		(hatch edge 0.508)
		(connect_pads yes
			(clearance 0.2)
		)
		(min_thickness 0.254)
		(filled_areas_thickness no)
		(fill yes
			(thermal_gap 0.508)
			(thermal_bridge_width 5)
		)
		(polygon
			(pts
				(xy 69.65 102.35) (xy 68.39 103.6) (xy 62.6 103.59) (xy 62.6 102.2) (xy 63.08 102.2) (xy 64.95 100.46)
				(xy 66.885231 100.46) (xy 67.17 100.199995) (xy 67.17 99.61) (xy 69.65 99.61)
			)
		)
	)
	(zone
		(net 87)
		(net_name "+3V3")
		(layer "F.Cu")
		(hatch edge 0.508)
		(connect_pads yes
			(clearance 0.2)
		)
		(min_thickness 0.254)
		(filled_areas_thickness no)
		(fill yes
			(thermal_gap 0.508)
			(thermal_bridge_width 5)
		)
		(polygon
			(pts
				(xy 134.8 109.9) (xy 137 109.9) (xy 137 111.2) (xy 133.5 111.2) (xy 133.5 108.8) (xy 134.8 108.8)
			)
		)
	)
	(zone
		(net 261)
		(net_name "/USB Debug, DP/USBC0_VBUS")
		(layer "F.Cu")
		(hatch edge 0.508)
		(priority 101)
		(connect_pads yes
			(clearance 0.2)
		)
		(min_thickness 0.254)
		(filled_areas_thickness no)
		(fill yes
			(thermal_gap 0.508)
			(thermal_bridge_width 5)
		)
		(polygon
			(pts
				(xy 69.7 116.1) (xy 67.7 116.1) (xy 67.7 114.9) (xy 68.4 114.9) (xy 68.4 113.5) (xy 69.7 113.5)
			)
		)
	)
	(zone
		(net 1)
		(net_name "GND")
		(layer "F.Cu")
		(hatch edge 0.5)
		(priority 18)
		(connect_pads yes
			(clearance 0)
		)
		(min_thickness 0.25)
		(filled_areas_thickness no)
		(fill yes
			(thermal_gap 0.5)
			(thermal_bridge_width 0.5)
		)
		(polygon
			(pts
				(xy 76.5525 89.49) (xy 76.8525 89.19) (xy 76.8525 88.14) (xy 78.5 88.14) (xy 78.8 88.44) (xy 79.55 88.44)
				(xy 79.55 87.405) (xy 80.55 87.405) (xy 80.55 90.69) (xy 75.04 90.69) (xy 74.23 91.5) (xy 69.33 91.5)
				(xy 69.245 91.415) (xy 69.245 86.515) (xy 69.77 85.99) (xy 71.29 85.99) (xy 71.8 86.5) (xy 71.8 89.31)
				(xy 71.98 89.49)
			)
		)
	)
	(zone
		(net 657)
		(net_name "Net-(U9-EN)")
		(layer "F.Cu")
		(hatch edge 0.508)
		(priority 1)
		(connect_pads yes
			(clearance 0.2)
		)
		(min_thickness 0.254)
		(filled_areas_thickness no)
		(fill yes
			(thermal_gap 0.508)
			(thermal_bridge_width 5)
		)
		(polygon
			(pts
				(xy 65.05 109.35) (xy 63.55 109.35) (xy 63.55 107.1) (xy 65.05 107.1)
			)
		)
	)
	(zone
		(net 328)
		(net_name "/Supply/VCC_IN")
		(layer "F.Cu")
		(hatch edge 0.508)
		(priority 7)
		(connect_pads yes
			(clearance 0.2)
		)
		(min_thickness 0.254)
		(filled_areas_thickness no)
		(fill yes
			(thermal_gap 0.508)
			(thermal_bridge_width 5)
		)
		(polygon
			(pts
				(xy 57.7 112.25) (xy 54.6 112.25) (xy 54.6 109.5) (xy 55.5 109.5) (xy 55.5 110.15) (xy 57.7 110.15)
			)
		)
	)
	(zone
		(net 756)
		(net_name "unconnected-(U40-GL-Pad10)")
		(layer "F.Cu")
		(hatch edge 0.5)
		(priority 15)
		(connect_pads yes
			(clearance 0)
		)
		(min_thickness 0.25)
		(filled_areas_thickness no)
		(fill yes
			(thermal_gap 0.5)
			(thermal_bridge_width 0.5)
		)
		(polygon
			(pts
				(xy 79.09 90.69) (xy 78.64 90.69) (xy 78.39 90.215) (xy 78.135 90.215) (xy 77.845 90.405) (xy 77.845 90.78)
				(xy 78.025 90.95) (xy 78.025 91.35) (xy 78.32 91.07) (xy 78.37 90.99) (xy 79.4525 90.99) (xy 79.4525 90.84)
			)
		)
	)
	(zone
		(net 1)
		(net_name "GND")
		(layer "F.Cu")
		(hatch edge 0.5)
		(priority 2)
		(connect_pads yes
			(clearance 0)
		)
		(min_thickness 0.25)
		(filled_areas_thickness no)
		(fill yes
			(thermal_gap 0.5)
			(thermal_bridge_width 0.5)
			(smoothing fillet)
			(radius 0.2)
		)
		(polygon
			(pts
				(xy 64.49742 73.001249) (xy 64.29742 73.001249) (xy 64.29742 81.001249) (xy 68.034663 81.001249)
				(xy 68.037225 89.383963) (xy 66.344796 91.025) (xy 62.625 91.025) (xy 62.625 97.13) (xy 63.95 97.13)
				(xy 63.95 99.75) (xy 64.2 100.05) (xy 64.2 100.9) (xy 61.46 100.9) (xy 61.46 100.13) (xy 61.92 99.82)
				(xy 61.92 98.96) (xy 61.32 97.92) (xy 61.32 95.6) (xy 60.04 95.6) (xy 57.54 96.7) (xy 55.51 96.7)
				(xy 54.75 96.02) (xy 54.75 94.79) (xy 59.76 94.79) (xy 60.54 93.77) (xy 60.55 89.75) (xy 62.1 88.25)
				(xy 62.1 81.6) (xy 61.596624 81.209997) (xy 61.6 77.29) (xy 61.8 77.11) (xy 61.8 71.001249) (xy 64.49742 71.001249)
			)
		)
	)
	(zone
		(net 196)
		(net_name "/USB Debug, DP/USBC3_VBUS")
		(layer "F.Cu")
		(hatch edge 0.508)
		(connect_pads yes
			(clearance 0.2)
		)
		(min_thickness 0.254)
		(filled_areas_thickness no)
		(fill yes
			(thermal_gap 0.508)
			(thermal_bridge_width 5)
		)
		(polygon
			(pts
				(xy 62.6 112.1) (xy 61 112.1) (xy 61 113.65) (xy 59.4 113.65) (xy 59.4 111.8) (xy 60.6 110.6) (xy 62.6 110.6)
			)
		)
	)
	(zone
		(net 625)
		(net_name "Net-(Q4-D)")
		(layer "F.Cu")
		(hatch edge 0.508)
		(connect_pads yes
			(clearance 0.2)
		)
		(min_thickness 0.254)
		(filled_areas_thickness no)
		(fill yes
			(thermal_gap 0.508)
			(thermal_bridge_width 5)
		)
		(polygon
			(pts
				(xy 103.6 117) (xy 104.4 117) (xy 104.4 119) (xy 102.8 119) (xy 102.8 116) (xy 103.6 116)
			)
		)
	)
	(zone
		(net 270)
		(net_name "/USB3/USBC1_VBUS")
		(layer "F.Cu")
		(hatch edge 0.508)
		(connect_pads yes
			(clearance 0.2)
		)
		(min_thickness 0.254)
		(filled_areas_thickness no)
		(fill yes
			(thermal_gap 0.508)
			(thermal_bridge_width 5)
		)
		(polygon
			(pts
				(xy 104.1 121.3) (xy 104.1 123.45) (xy 103.15 123.45) (xy 103.15 122.3) (xy 100.8 122.3) (xy 100.8 119.9)
				(xy 101.8 119.9) (xy 101.8 121.3)
			)
		)
	)
	(zone
		(net 438)
		(net_name "/SoM/SoM_VIN")
		(layer "F.Cu")
		(hatch edge 0.508)
		(priority 17)
		(connect_pads yes
			(clearance 0.125)
		)
		(min_thickness 0.2)
		(filled_areas_thickness no)
		(fill yes
			(thermal_gap 0.508)
			(thermal_bridge_width 0.508)
			(smoothing fillet)
			(radius 0.2)
		)
		(polygon
			(pts
				(xy 61.8 78.23) (xy 61.6 78.23) (xy 61.596624 81.209997) (xy 61.9 81.45) (xy 61.912212 89.73) (xy 58.81 89.73)
				(xy 58.81 88.49) (xy 57.4 88.49) (xy 57.4 86.27658) (xy 58.309612 85.355) (xy 58.724422 85.355)
				(xy 58.81 85.27) (xy 58.81 71) (xy 61.81 71)
			)
		)
	)
	(zone
		(net 761)
		(net_name "/Supply/5V_OUT")
		(layer "F.Cu")
		(hatch edge 0.5)
		(priority 12)
		(connect_pads yes
			(clearance 0)
		)
		(min_thickness 0.25)
		(filled_areas_thickness no)
		(fill yes
			(thermal_gap 0.5)
			(thermal_bridge_width 0.5)
			(smoothing fillet)
			(radius 0.5)
		)
		(polygon
			(pts
				(xy 55.649658 102.39) (xy 55.659474 97.069634) (xy 54.66 96.16) (xy 54.66 94.66) (xy 59.57 94.66)
				(xy 59.97 94.21) (xy 59.97 93.3) (xy 56.6 93.3) (xy 55.411649 91.905) (xy 54.197501 91.905) (xy 53.704281 92.084353)
				(xy 52.27 94.19) (xy 52.27 100.64) (xy 53.69 102.39)
			)
		)
	)
	(zone
		(net 99)
		(net_name "+5V")
		(layer "F.Cu")
		(hatch edge 0.508)
		(connect_pads yes
			(clearance 0.2)
		)
		(min_thickness 0.254)
		(filled_areas_thickness no)
		(fill yes
			(thermal_gap 0.508)
			(thermal_bridge_width 5)
		)
		(polygon
			(pts
				(xy 62.55 109.4) (xy 59.15 109.4) (xy 59.15 107.4) (xy 62.55 107.4)
			)
		)
	)
	(zone
		(net 0)
		(net_name "")
		(layer "F.Cu")
		(name "CLR")
		(hatch edge 0.508)
		(connect_pads yes
			(clearance 0)
		)
		(min_thickness 0.254)
		(filled_areas_thickness no)
		(keepout
			(tracks allowed)
			(vias allowed)
			(pads allowed)
			(copperpour allowed)
			(footprints allowed)
		)
		(fill
			(thermal_gap 0.508)
			(thermal_bridge_width 0.508)
		)
		(polygon
			(pts
				(xy 79.82 110.57) (xy 69.87 110.57) (xy 69.87 102.07) (xy 79.82 102.07)
			)
		)
	)
	(zone
		(net 87)
		(net_name "+3V3")
		(layer "F.Cu")
		(hatch edge 0.508)
		(connect_pads yes
			(clearance 0.2)
		)
		(min_thickness 0.2)
		(filled_areas_thickness no)
		(fill yes
			(thermal_gap 0.508)
			(thermal_bridge_width 5)
		)
		(polygon
			(pts
				(xy 107.95 107.8) (xy 107 107.8) (xy 106.4 108.3) (xy 106.4 108.5) (xy 105.2 108.5) (xy 105.2 107.5)
				(xy 106.1 107.5) (xy 106.1 107.3) (xy 107.95 107.3)
			)
		)
	)
	(zone
		(net 1)
		(net_name "GND")
		(layer "F.Cu")
		(hatch edge 0.508)
		(connect_pads yes
			(clearance 0.125)
		)
		(min_thickness 0.254)
		(filled_areas_thickness no)
		(fill yes
			(thermal_gap 0.508)
			(thermal_bridge_width 0.508)
			(island_removal_mode 1)
			(island_area_min 0)
		)
		(polygon
			(pts
				(xy 115.35 102.958542) (xy 114.07 102.95) (xy 114.07 103.9) (xy 113.52 103.9) (xy 113.52 101.6)
				(xy 115.35 101.6)
			)
		)
	)
	(zone
		(net 1)
		(net_name "GND")
		(layer "F.Cu")
		(hatch edge 0.508)
		(priority 2)
		(connect_pads yes
			(clearance 0.125)
		)
		(min_thickness 0.2)
		(filled_areas_thickness no)
		(fill yes
			(thermal_gap 0.508)
			(thermal_bridge_width 0.508)
		)
		(polygon
			(pts
				(xy 58.8 85.27) (xy 56.2 85.27) (xy 56.2 82.2) (xy 58.8 82.2)
			)
		)
	)
	(zone
		(net 641)
		(net_name "/Supply/3V3_OUT")
		(layer "F.Cu")
		(hatch edge 0.5)
		(priority 19)
		(connect_pads yes
			(clearance 0)
		)
		(min_thickness 0.25)
		(filled_areas_thickness no)
		(fill yes
			(thermal_gap 0.5)
			(thermal_bridge_width 0.5)
		)
		(polygon
			(pts
				(xy 74.52 92.76) (xy 74.38 92.9) (xy 73.98 92.9) (xy 72.9 93.98) (xy 72.9 97.74) (xy 72.25 98.39)
				(xy 71.05 98.39) (xy 69.41 96.75) (xy 69.41 93.66) (xy 68.86 93.11) (xy 68.17 93.11) (xy 67.81 92.75)
				(xy 67.81 92) (xy 67.97 91.84) (xy 74.38 91.84) (xy 74.52 91.98)
			)
		)
	)
	(zone
		(net 115)
		(net_name "VCC")
		(layer "F.Cu")
		(hatch edge 0.5)
		(priority 8)
		(connect_pads yes
			(clearance 0)
		)
		(min_thickness 0.25)
		(filled_areas_thickness no)
		(fill yes
			(thermal_gap 0.5)
			(thermal_bridge_width 0.5)
			(smoothing fillet)
			(radius 0.2)
		)
		(polygon
			(pts
				(xy 64.92 97.036) (xy 64.99 96.976) (xy 64.99 96.756) (xy 64.92 96.686) (xy 64.31 96.686) (xy 64.12 96.516)
				(xy 64.12 94.5) (xy 64.8812 93.963367) (xy 64.8812 91.25933) (xy 62.8 91.259734) (xy 62.8 96.95)
				(xy 64.05 96.95) (xy 64.15 97.036)
			)
		)
	)
	(zone
		(net 115)
		(net_name "VCC")
		(layer "F.Cu")
		(hatch edge 0.5)
		(priority 8)
		(connect_pads yes
			(clearance 0)
		)
		(min_thickness 0.25)
		(filled_areas_thickness no)
		(fill yes
			(thermal_gap 0.5)
			(thermal_bridge_width 0.5)
			(smoothing fillet)
			(radius 0.2)
		)
		(polygon
			(pts
				(xy 76.75 87.15) (xy 76.69 87.08) (xy 76.47 87.08) (xy 76.4 87.15) (xy 76.4 87.76) (xy 76.23 87.95)
				(xy 74.73 87.95) (xy 74.07 85.22) (xy 71.944 85.22) (xy 71.944 89.34) (xy 76.49 89.34) (xy 76.73 89.1)
				(xy 76.73 88.1) (xy 76.75 87.76)
			)
		)
	)
	(zone
		(net 99)
		(net_name "+5V")
		(layer "F.Cu")
		(hatch edge 0.5)
		(priority 16)
		(connect_pads yes
			(clearance 0.125)
		)
		(min_thickness 0.25)
		(filled_areas_thickness no)
		(fill yes
			(thermal_gap 0.2)
			(thermal_bridge_width 0.5)
		)
		(polygon
			(pts
				(xy 58.425 93) (xy 60.15 93) (xy 60.15 91.375) (xy 58.425 91.375)
			)
		)
	)
	(zone
		(net 404)
		(net_name "/USB Debug, DP/DRAIN1")
		(layer "F.Cu")
		(hatch edge 0.508)
		(priority 1)
		(connect_pads yes
			(clearance 0.2)
		)
		(min_thickness 0.254)
		(filled_areas_thickness no)
		(fill yes
			(thermal_gap 0.508)
			(thermal_bridge_width 5)
		)
		(polygon
			(pts
				(xy 69 105.8) (xy 67.9 105.8) (xy 67.9 106.8) (xy 66.2 106.8) (xy 66.2 104.1) (xy 69 104.1)
			)
		)
	)
	(zone
		(net 270)
		(net_name "/USB3/USBC1_VBUS")
		(layer "F.Cu")
		(hatch edge 0.508)
		(connect_pads yes
			(clearance 0.2)
		)
		(min_thickness 0.254)
		(filled_areas_thickness no)
		(fill yes
			(thermal_gap 0.508)
			(thermal_bridge_width 5)
		)
		(polygon
			(pts
				(xy 114.9 118.9) (xy 115 118.9) (xy 115 119.9) (xy 111.8 119.9) (xy 111.8 118.9) (xy 111.9 118.9)
				(xy 111.9 117.5) (xy 114.9 117.5)
			)
		)
	)
	(zone
		(net 787)
		(net_name "+5V_SoM")
		(layer "F.Cu")
		(hatch edge 0.5)
		(priority 13)
		(connect_pads yes
			(clearance 0.125)
		)
		(min_thickness 0.25)
		(filled_areas_thickness no)
		(fill yes
			(thermal_gap 0.5)
			(thermal_bridge_width 0.5)
		)
		(polygon
			(pts
				(xy 58.31 93.19) (xy 58.3 91.425) (xy 58.45 91.275) (xy 60.175 91.275) (xy 60.175 91.775) (xy 60.725 91.775)
				(xy 60.725 88.5) (xy 56.8 88.5) (xy 56.8 91.4) (xy 55.45 91.4) (xy 55.45 92.875) (xy 55.685 93.19)
			)
		)
	)
	(zone
		(net 99)
		(net_name "+5V")
		(layer "F.Cu")
		(hatch edge 0.508)
		(connect_pads yes
			(clearance 0.2)
		)
		(min_thickness 0.254)
		(filled_areas_thickness no)
		(fill yes
			(thermal_gap 0.508)
			(thermal_bridge_width 5)
		)
		(polygon
			(pts
				(xy 101.6 119.1) (xy 99.3 119.1) (xy 99.3 117.1) (xy 100.8 117.1) (xy 100.8 116.1) (xy 101.6 116.1)
			)
		)
	)
	(zone
		(net 479)
		(net_name "/Peripherals/5V_CONN")
		(layer "F.Cu")
		(hatch edge 0.508)
		(connect_pads yes
			(clearance 0.2)
		)
		(min_thickness 0.254)
		(filled_areas_thickness no)
		(fill yes
			(thermal_gap 0.508)
			(thermal_bridge_width 5)
		)
		(polygon
			(pts
				(xy 142.2 115) (xy 137.4 115) (xy 137.4 113.8) (xy 140.8 113.8) (xy 140.8 113.2) (xy 142.2 113.2)
			)
		)
	)
	(zone
		(net 189)
		(net_name "Net-(D28-C)")
		(layer "F.Cu")
		(hatch edge 0.508)
		(connect_pads yes
			(clearance 0.2)
		)
		(min_thickness 0.254)
		(filled_areas_thickness no)
		(fill yes
			(thermal_gap 0.508)
			(thermal_bridge_width 5)
		)
		(polygon
			(pts
				(xy 58.8 114.7) (xy 56.3 117.7) (xy 56.3 120.6) (xy 53.9 120.6) (xy 53.9 112.7) (xy 58.8 112.7)
			)
		)
	)
	(zone
		(net 105)
		(net_name "/Ethernet/VDD")
		(layer "F.Cu")
		(hatch edge 0.508)
		(priority 1)
		(connect_pads yes
			(clearance 0.2)
		)
		(min_thickness 0.254)
		(filled_areas_thickness no)
		(fill yes
			(thermal_gap 0.508)
			(thermal_bridge_width 5)
		)
		(polygon
			(pts
				(xy 52.62 90.84) (xy 52.34 90.89) (xy 38.478676 97.626717) (xy 38.05 97.94) (xy 37.68 98.38) (xy 37.47 98.83)
				(xy 37.3 99.54) (xy 37.3 105.1) (xy 31.9 105.11) (xy 31.9 98.2) (xy 33.628508 96.498642) (xy 36.420004 96.499677)
				(xy 37.2 96.41) (xy 37.857244 96.22433) (xy 52.27 89.22) (xy 52.64 89.12) (xy 53.76 89.12) (xy 53.76 90.84)
			)
		)
	)
	(zone
		(net 403)
		(net_name "/USB Debug, DP/DRAIN2")
		(layer "F.Cu")
		(hatch edge 0.508)
		(connect_pads yes
			(clearance 0.2)
		)
		(min_thickness 0.254)
		(filled_areas_thickness no)
		(fill yes
			(thermal_gap 0.508)
			(thermal_bridge_width 5)
		)
		(polygon
			(pts
				(xy 66.1 106.8) (xy 63.9 106.8) (xy 62.7 105.8) (xy 62.7 104.4) (xy 63.6 104.4) (xy 63.9 104.1)
				(xy 66.1 104.1)
			)
		)
	)
	(zone
		(net 643)
		(net_name "/Supply/3V3_SW")
		(layer "F.Cu")
		(hatch edge 0.5)
		(priority 10)
		(connect_pads yes
			(clearance 0)
		)
		(min_thickness 0.25)
		(filled_areas_thickness no)
		(fill yes
			(thermal_gap 0.5)
			(thermal_bridge_width 0.5)
			(smoothing fillet)
			(radius 0.5)
		)
		(polygon
			(pts
				(xy 77.92 92.491728) (xy 77.92 90.93) (xy 74.74 90.93) (xy 74.74 92.86) (xy 74.501676 93.086882)
				(xy 74.04676 93.08676) (xy 73.46 93.67) (xy 73.46 97.71) (xy 74.25 98.39) (xy 75.5 98.39) (xy 75.75 98.156665)
				(xy 75.75 95.151202)
			)
		)
	)
	(zone
		(net 1)
		(net_name "GND")
		(layer "F.Cu")
		(hatch edge 0.508)
		(connect_pads yes
			(clearance 0.125)
		)
		(min_thickness 0.254)
		(filled_areas_thickness no)
		(fill yes
			(thermal_gap 0.508)
			(thermal_bridge_width 0.508)
		)
		(polygon
			(pts
				(xy 53.5 120.6) (xy 48.9 120.6) (xy 48.9 115.8) (xy 53.49 115.8)
			)
		)
	)
	(zone
		(net 87)
		(net_name "+3V3")
		(layer "F.Cu")
		(hatch edge 0.508)
		(priority 101)
		(connect_pads yes
			(clearance 0.2)
		)
		(min_thickness 0.254)
		(filled_areas_thickness no)
		(fill yes
			(thermal_gap 0.508)
			(thermal_bridge_width 5)
		)
		(polygon
			(pts
				(xy 119.05 88.05) (xy 117.8 88.05) (xy 117.8 87) (xy 116 87) (xy 116 87.4) (xy 114.2 87.4) (xy 114.2 85.8)
				(xy 119.05 85.8)
			)
		)
	)
	(zone
		(net 115)
		(net_name "VCC")
		(layer "F.Cu")
		(hatch edge 0.508)
		(connect_pads yes
			(clearance 0.2)
		)
		(min_thickness 0.254)
		(filled_areas_thickness no)
		(fill yes
			(thermal_gap 0.508)
			(thermal_bridge_width 5)
		)
		(polygon
			(pts
				(xy 143.55 119.9) (xy 140.05 119.9) (xy 140.05 117.65) (xy 143.55 117.65)
			)
		)
	)
	(zone
		(net 1)
		(net_name "GND")
		(layer "F.Cu")
		(hatch edge 0.508)
		(connect_pads yes
			(clearance 0.125)
		)
		(min_thickness 0.254)
		(filled_areas_thickness no)
		(fill yes
			(thermal_gap 0.508)
			(thermal_bridge_width 0.508)
			(island_removal_mode 1)
			(island_area_min 0)
		)
		(polygon
			(pts
				(xy 113.72 87.39) (xy 112.22 87.39) (xy 112.22 85.89) (xy 113.72 85.89)
			)
		)
	)
	(zone
		(net 87)
		(net_name "+3V3")
		(layer "F.Cu")
		(hatch edge 0.508)
		(priority 101)
		(connect_pads yes
			(clearance 0.2)
		)
		(min_thickness 0.254)
		(filled_areas_thickness no)
		(fill yes
			(thermal_gap 0.508)
			(thermal_bridge_width 5)
		)
		(polygon
			(pts
				(xy 116.008519 103.01) (xy 116.015 103.15) (xy 120.15 103.15) (xy 120.15 104.4) (xy 114.2 104.4)
				(xy 114.2 103.01)
			)
		)
	)
	(zone
		(net 763)
		(net_name "/Supply/5V_SW")
		(layer "F.Cu")
		(hatch edge 0.5)
		(priority 11)
		(connect_pads yes
			(clearance 0)
		)
		(min_thickness 0.25)
		(filled_areas_thickness no)
		(fill yes
			(thermal_gap 0.5)
			(thermal_bridge_width 0.5)
			(smoothing fillet)
			(radius 0.3)
		)
		(polygon
			(pts
				(xy 61.04 95.73) (xy 60.14 95.73) (xy 57.71 96.79) (xy 57.72 102.12) (xy 57.97 102.39) (xy 59.485 102.39)
				(xy 60.01 101.9) (xy 60.01 98.56) (xy 60.3675 98.16) (xy 61.12 98.16) (xy 61.16 98.12) (xy 61.16 95.86)
			)
		)
	)
	(zone
		(net 788)
		(net_name "VDD_SoM")
		(layer "F.Cu")
		(hatch edge 0.5)
		(priority 24)
		(connect_pads yes
			(clearance 0.125)
		)
		(min_thickness 0.25)
		(filled_areas_thickness no)
		(fill yes
			(thermal_gap 0.5)
			(thermal_bridge_width 0.5)
		)
		(polygon
			(pts
				(xy 56.725 91.4) (xy 56.725 89.102627) (xy 57.7 88.230258) (xy 57.7 86.1) (xy 53.960279 86.1) (xy 53.518996 85.659944)
				(xy 53.509196 82.340032) (xy 52.05 80.890668) (xy 49.615 80.881624) (xy 49.615 85.02) (xy 52.554745 87.955712)
				(xy 53.777152 87.952152) (xy 54.675 88.85) (xy 56.102058 88.85) (xy 56.245 88.997273) (xy 56.245 91.4)
			)
		)
	)
	(zone
		(net 87)
		(net_name "+3V3")
		(layer "F.Cu")
		(hatch edge 0.5)
		(priority 20)
		(connect_pads yes
			(clearance 0.125)
		)
		(min_thickness 0.25)
		(filled_areas_thickness no)
		(fill yes
			(thermal_gap 0.5)
			(thermal_bridge_width 0.5)
		)
		(polygon
			(pts
				(xy 69.1 91.5) (xy 69.1 88.15) (xy 67.4 88.15) (xy 67.4 91.5)
			)
		)
	)
	(zone
		(net 0)
		(net_name "")
		(layers "F.Cu" "In1.Cu" "In2.Cu" "In3.Cu" "In4.Cu" "In5.Cu" "In6.Cu")
		(hatch edge 0.508)
		(connect_pads
			(clearance 0)
		)
		(min_thickness 0.254)
		(filled_areas_thickness no)
		(keepout
			(tracks allowed)
			(vias allowed)
			(pads allowed)
			(copperpour not_allowed)
			(footprints allowed)
		)
		(fill
			(thermal_gap 0.508)
			(thermal_bridge_width 0.508)
		)
		(polygon
			(pts
				(xy 51.354743 99.45) (xy 51.335917 99.173854) (xy 51.279788 98.902817) (xy 51.187395 98.641906)
				(xy 51.060446 98.395948) (xy 50.901292 98.169495) (xy 50.712877 97.966736) (xy 50.498688 97.791424)
				(xy 50.262688 97.646803) (xy 50.009245 97.535549) (xy 49.743047 97.459721) (xy 49.469021 97.420721)
				(xy 49.192237 97.419272) (xy 48.917818 97.4554) (xy 48.650841 97.528437) (xy 48.396246 97.637031)
				(xy 48.158745 97.779172) (xy 47.942731 97.952232) (xy 47.752204 98.153006) (xy 47.590687 98.37778)
				(xy 47.46117 98.622395) (xy 47.366049 98.882325) (xy 47.307085 99.152759) (xy 47.285369 99.428693)
				(xy 47.301302 99.705021) (xy 47.354589 99.97663) (xy 47.444245 100.238495) (xy 47.568611 100.485768)
				(xy 47.725385 100.713876) (xy 47.911667 100.918597) (xy 48.124008 101.096142) (xy 48.358481 101.243226)
				(xy 48.610745 101.357128) (xy 48.876135 101.43574) (xy 49.149737 101.477607) (xy 49.42649 101.481954)
				(xy 49.701273 101.448702) (xy 49.969 101.378465) (xy 50.224718 101.272543) (xy 50.463695 101.132896)
				(xy 50.681509 100.962109) (xy 50.874129 100.763341) (xy 51.03799 100.54027) (xy 51.170062 100.297024)
				(xy 51.267899 100.038105) (xy 51.329692 99.768304) (xy 51.354297 99.492612)
			)
		)
	)
	(zone
		(net 0)
		(net_name "")
		(layers "F.Cu" "In1.Cu" "In2.Cu" "In3.Cu" "In4.Cu" "In5.Cu" "In6.Cu" "B.Cu")
		(hatch edge 0.508)
		(connect_pads
			(clearance 0)
		)
		(min_thickness 0.254)
		(filled_areas_thickness no)
		(keepout
			(tracks allowed)
			(vias allowed)
			(pads allowed)
			(copperpour not_allowed)
			(footprints allowed)
		)
		(fill
			(thermal_gap 0.508)
			(thermal_bridge_width 0.508)
		)
		(polygon
			(pts
				(xy 34.664679 113.696397) (xy 34.645997 113.482865) (xy 34.59052 113.275822) (xy 34.499933 113.081558)
				(xy 34.376989 112.905975) (xy 34.225422 112.754408) (xy 34.04984 112.631464) (xy 33.855575 112.540877)
				(xy 33.648532 112.4854) (xy 33.435 112.466718) (xy 33.221468 112.4854) (xy 33.014425 112.540877)
				(xy 32.820161 112.631464) (xy 32.644578 112.754408) (xy 32.493011 112.905975) (xy 32.370067 113.081558)
				(xy 32.27948 113.275822) (xy 32.224003 113.482865) (xy 32.205321 113.696397) (xy 32.224003 113.909929)
				(xy 32.27948 114.116972) (xy 32.370067 114.311236) (xy 32.493011 114.486819) (xy 32.644578 114.638386)
				(xy 32.82016 114.76133) (xy 33.014425 114.851917) (xy 33.221468 114.907394) (xy 33.435 114.926076)
				(xy 33.648532 114.907394) (xy 33.855575 114.851917) (xy 34.04984 114.76133) (xy 34.225422 114.638386)
				(xy 34.376989 114.486819) (xy 34.499933 114.311236) (xy 34.59052 114.116972) (xy 34.645997 113.909929)
			)
		)
	)
	(zone
		(net 0)
		(net_name "")
		(layers "F.Cu" "In1.Cu" "In2.Cu" "In3.Cu" "In4.Cu" "In5.Cu" "In6.Cu" "B.Cu")
		(hatch edge 0.508)
		(connect_pads
			(clearance 0)
		)
		(min_thickness 0.254)
		(filled_areas_thickness no)
		(keepout
			(tracks allowed)
			(vias allowed)
			(pads allowed)
			(copperpour not_allowed)
			(footprints allowed)
		)
		(fill
			(thermal_gap 0.508)
			(thermal_bridge_width 0.508)
		)
		(polygon
			(pts
				(xy 43.734743 99.45) (xy 43.715917 99.173854) (xy 43.659788 98.902817) (xy 43.567395 98.641906)
				(xy 43.440446 98.395948) (xy 43.281292 98.169495) (xy 43.092877 97.966736) (xy 42.878688 97.791424)
				(xy 42.642688 97.646803) (xy 42.389245 97.535549) (xy 42.123047 97.459721) (xy 41.849021 97.420721)
				(xy 41.572237 97.419272) (xy 41.297818 97.4554) (xy 41.030841 97.528437) (xy 40.776246 97.637031)
				(xy 40.538745 97.779172) (xy 40.322731 97.952232) (xy 40.132204 98.153006) (xy 39.970687 98.37778)
				(xy 39.84117 98.622395) (xy 39.746049 98.882325) (xy 39.687085 99.152759) (xy 39.665369 99.428693)
				(xy 39.681302 99.705021) (xy 39.734589 99.97663) (xy 39.824245 100.238495) (xy 39.948611 100.485768)
				(xy 40.105385 100.713876) (xy 40.291667 100.918597) (xy 40.504008 101.096142) (xy 40.738481 101.243226)
				(xy 40.990745 101.357128) (xy 41.256135 101.43574) (xy 41.529737 101.477607) (xy 41.80649 101.481954)
				(xy 42.081273 101.448702) (xy 42.349 101.378465) (xy 42.604718 101.272543) (xy 42.843695 101.132896)
				(xy 43.061509 100.962109) (xy 43.254129 100.763341) (xy 43.41799 100.54027) (xy 43.550062 100.297024)
				(xy 43.647899 100.038105) (xy 43.709692 99.768304) (xy 43.734297 99.492612)
			)
		)
	)
	(zone
		(net 0)
		(net_name "")
		(layers "F.Cu" "In1.Cu" "In2.Cu" "In3.Cu" "In4.Cu" "In5.Cu" "In6.Cu" "B.Cu")
		(hatch edge 0.508)
		(connect_pads
			(clearance 0)
		)
		(min_thickness 0.254)
		(filled_areas_thickness no)
		(keepout
			(tracks allowed)
			(vias allowed)
			(pads allowed)
			(copperpour not_allowed)
			(footprints allowed)
		)
		(fill
			(thermal_gap 0.508)
			(thermal_bridge_width 0.508)
		)
		(polygon
			(pts
				(xy 37.204679 114.956397) (xy 37.185997 114.742865) (xy 37.13052 114.535822) (xy 37.039933 114.341558)
				(xy 36.916989 114.165975) (xy 36.765422 114.014408) (xy 36.58984 113.891464) (xy 36.395575 113.800877)
				(xy 36.188532 113.7454) (xy 35.975 113.726718) (xy 35.761468 113.7454) (xy 35.554425 113.800877)
				(xy 35.360161 113.891464) (xy 35.184578 114.014408) (xy 35.033011 114.165975) (xy 34.910067 114.341558)
				(xy 34.81948 114.535822) (xy 34.764003 114.742865) (xy 34.745321 114.956397) (xy 34.764003 115.169929)
				(xy 34.81948 115.376972) (xy 34.910067 115.571236) (xy 35.033011 115.746819) (xy 35.184578 115.898386)
				(xy 35.36016 116.02133) (xy 35.554425 116.111917) (xy 35.761468 116.167394) (xy 35.975 116.186076)
				(xy 36.188532 116.167394) (xy 36.395575 116.111917) (xy 36.58984 116.02133) (xy 36.765422 115.898386)
				(xy 36.916989 115.746819) (xy 37.039933 115.571236) (xy 37.13052 115.376972) (xy 37.185997 115.169929)
			)
		)
	)
	(zone
		(net 0)
		(net_name "")
		(layers "F.Cu" "In1.Cu" "In2.Cu" "In3.Cu" "In4.Cu" "In5.Cu" "In6.Cu" "B.Cu")
		(hatch edge 0.508)
		(connect_pads
			(clearance 0)
		)
		(min_thickness 0.254)
		(filled_areas_thickness no)
		(keepout
			(tracks allowed)
			(vias allowed)
			(pads allowed)
			(copperpour not_allowed)
			(footprints allowed)
		)
		(fill
			(thermal_gap 0.508)
			(thermal_bridge_width 0.508)
		)
		(polygon
			(pts
				(xy 46.143282 113.686397) (xy 46.1246 113.472865) (xy 46.069123 113.265822) (xy 45.978536 113.071558)
				(xy 45.855592 112.895975) (xy 45.704025 112.744408) (xy 45.528443 112.621464) (xy 45.334178 112.530877)
				(xy 45.127135 112.4754) (xy 44.913603 112.456718) (xy 44.700071 112.4754) (xy 44.493028 112.530877)
				(xy 44.298764 112.621464) (xy 44.123181 112.744408) (xy 43.971614 112.895975) (xy 43.84867 113.071558)
				(xy 43.758083 113.265822) (xy 43.702606 113.472865) (xy 43.683924 113.686397) (xy 43.702606 113.899929)
				(xy 43.758083 114.106972) (xy 43.84867 114.301236) (xy 43.971614 114.476819) (xy 44.123181 114.628386)
				(xy 44.298763 114.75133) (xy 44.493028 114.841917) (xy 44.700071 114.897394) (xy 44.913603 114.916076)
				(xy 45.127135 114.897394) (xy 45.334178 114.841917) (xy 45.528443 114.75133) (xy 45.704025 114.628386)
				(xy 45.855592 114.476819) (xy 45.978536 114.301236) (xy 46.069123 114.106972) (xy 46.1246 113.899929)
			)
		)
	)
	(zone
		(net 0)
		(net_name "")
		(layers "F.Cu" "In1.Cu" "In2.Cu" "In3.Cu" "In4.Cu" "In5.Cu" "In6.Cu" "B.Cu")
		(hatch edge 0.508)
		(connect_pads
			(clearance 0)
		)
		(min_thickness 0.254)
		(filled_areas_thickness no)
		(keepout
			(tracks allowed)
			(vias allowed)
			(pads allowed)
			(copperpour not_allowed)
			(footprints allowed)
		)
		(fill
			(thermal_gap 0.508)
			(thermal_bridge_width 0.508)
		)
		(polygon
			(pts
				(xy 43.295421 99.46) (xy 43.275779 99.210421) (xy 43.217336 98.966988) (xy 43.121531 98.735694)
				(xy 42.990723 98.522235) (xy 42.828133 98.331867) (xy 42.637765 98.169277) (xy 42.424306 98.038469)
				(xy 42.193012 97.942664) (xy 41.949579 97.884221) (xy 41.7 97.864579) (xy 41.450421 97.884221) (xy 41.206988 97.942664)
				(xy 40.975694 98.038469) (xy 40.762235 98.169277) (xy 40.571867 98.331867) (xy 40.409277 98.522235)
				(xy 40.278469 98.735694) (xy 40.182664 98.966988) (xy 40.124221 99.210421) (xy 40.104579 99.46)
				(xy 40.124221 99.709579) (xy 40.182664 99.953012) (xy 40.278469 100.184306) (xy 40.409277 100.397765)
				(xy 40.571867 100.588133) (xy 40.762235 100.750723) (xy 40.975694 100.881531) (xy 41.206988 100.977336)
				(xy 41.450421 101.035779) (xy 41.7 101.055421) (xy 41.949579 101.035779) (xy 42.193012 100.977336)
				(xy 42.424306 100.881531) (xy 42.637765 100.750723) (xy 42.828133 100.588133) (xy 42.990723 100.397765)
				(xy 43.121531 100.184306) (xy 43.217336 99.953012) (xy 43.275779 99.709579)
			)
		)
	)
	(zone
		(net 0)
		(net_name "")
		(layers "F.Cu" "In1.Cu" "In2.Cu" "In3.Cu" "In4.Cu" "In5.Cu" "In6.Cu" "B.Cu")
		(hatch edge 0.508)
		(connect_pads
			(clearance 0)
		)
		(min_thickness 0.254)
		(filled_areas_thickness no)
		(keepout
			(tracks allowed)
			(vias allowed)
			(pads allowed)
			(copperpour not_allowed)
			(footprints allowed)
		)
		(fill
			(thermal_gap 0.508)
			(thermal_bridge_width 0.508)
		)
		(polygon
			(pts
				(xy 43.554679 114.956397) (xy 43.535997 114.742865) (xy 43.48052 114.535822) (xy 43.389933 114.341558)
				(xy 43.266989 114.165975) (xy 43.115422 114.014408) (xy 42.93984 113.891464) (xy 42.745575 113.800877)
				(xy 42.538532 113.7454) (xy 42.325 113.726718) (xy 42.111468 113.7454) (xy 41.904425 113.800877)
				(xy 41.710161 113.891464) (xy 41.534578 114.014408) (xy 41.383011 114.165975) (xy 41.260067 114.341558)
				(xy 41.16948 114.535822) (xy 41.114003 114.742865) (xy 41.095321 114.956397) (xy 41.114003 115.169929)
				(xy 41.16948 115.376972) (xy 41.260067 115.571236) (xy 41.383011 115.746819) (xy 41.534578 115.898386)
				(xy 41.71016 116.02133) (xy 41.904425 116.111917) (xy 42.111468 116.167394) (xy 42.325 116.186076)
				(xy 42.538532 116.167394) (xy 42.745575 116.111917) (xy 42.93984 116.02133) (xy 43.115422 115.898386)
				(xy 43.266989 115.746819) (xy 43.389933 115.571236) (xy 43.48052 115.376972) (xy 43.535997 115.169929)
			)
		)
	)
	(zone
		(net 0)
		(net_name "")
		(layers "F.Cu" "In1.Cu" "In2.Cu" "In3.Cu" "In4.Cu" "In5.Cu" "In6.Cu" "B.Cu")
		(hatch edge 0.508)
		(connect_pads yes
			(clearance 0)
		)
		(min_thickness 0.254)
		(filled_areas_thickness no)
		(keepout
			(tracks allowed)
			(vias allowed)
			(pads allowed)
			(copperpour not_allowed)
			(footprints allowed)
		)
		(fill
			(thermal_gap 0.508)
			(thermal_bridge_width 5)
		)
		(polygon
			(pts
				(xy 44.10516 86.75) (xy 44.085536 86.387645) (xy 44.026892 86.029529) (xy 43.929915 85.67984) (xy 43.795739 85.342671)
				(xy 43.625933 85.021965) (xy 43.422485 84.721473) (xy 43.187774 84.444711) (xy 42.924546 84.194917)
				(xy 42.63588 83.975012) (xy 42.325152 83.78757) (xy 41.995999 83.634781) (xy 41.652269 83.518435)
				(xy 41.297985 83.439893) (xy 40.93729 83.400071) (xy 40.574404 83.399438) (xy 40.213573 83.438)
				(xy 39.859017 83.515306) (xy 39.514883 83.630451) (xy 39.185198 83.782089) (xy 38.873818 83.968446)
				(xy 38.584386 84.187342) (xy 38.320288 84.436216) (xy 38.084612 84.712157) (xy 37.880116 85.011936)
				(xy 37.709192 85.332048) (xy 37.57384 85.668747) (xy 37.475643 86.018095) (xy 37.41575 86.376004)
				(xy 37.39486 86.738288) (xy 37.41322 87.10071) (xy 37.470613 87.459029) (xy 37.566369 87.809053)
				(xy 37.699367 88.146689) (xy 37.868052 88.467986) (xy 38.07045 88.769186) (xy 38.304194 89.046765)
				(xy 38.566548 89.297477) (xy 38.854445 89.518388) (xy 39.164517 89.706914) (xy 39.493135 89.86085)
				(xy 39.836456 89.978395) (xy 40.190464 90.058174) (xy 40.551018 90.099254) (xy 40.913899 90.101154)
				(xy 41.274863 90.063852) (xy 41.629687 89.987785) (xy 41.97422 89.873841) (xy 42.304432 89.723355)
				(xy 42.616461 89.538086) (xy 42.906655 89.320202) (xy 43.171621 89.072251) (xy 43.408259 88.797135)
				(xy 43.613799 88.498071) (xy 43.78584 88.178558) (xy 43.922366 87.842333) (xy 44.021782 87.493331)
				(xy 44.082925 87.135633) (xy 44.105078 86.773423)
			)
		)
	)
	(zone
		(net 0)
		(net_name "")
		(layers "F.Cu" "F.SilkS")
		(name "allow_overlap")
		(hatch edge 0.5)
		(connect_pads
			(clearance 0)
		)
		(min_thickness 0.25)
		(filled_areas_thickness no)
		(keepout
			(tracks allowed)
			(vias allowed)
			(pads allowed)
			(copperpour allowed)
			(footprints allowed)
		)
		(fill
			(thermal_gap 0.5)
			(thermal_bridge_width 0.5)
		)
		(polygon
			(pts
				(xy 146.81 83.5) (xy 148.15 83.5) (xy 148.15 91.7) (xy 146.81 91.7)
			)
		)
	)
	(zone
		(net 0)
		(net_name "")
		(layers "F.Cu" "F.SilkS")
		(name "allow_overlap")
		(hatch edge 0.5)
		(connect_pads
			(clearance 0)
		)
		(min_thickness 0.25)
		(filled_areas_thickness no)
		(keepout
			(tracks allowed)
			(vias allowed)
			(pads allowed)
			(copperpour allowed)
			(footprints allowed)
		)
		(fill
			(thermal_gap 0.5)
			(thermal_bridge_width 0.5)
		)
		(polygon
			(pts
				(xy 137.26 82) (xy 138.3 82) (xy 138.3 88.2) (xy 137.26 88.2)
			)
		)
	)
	(zone
		(net 0)
		(net_name "")
		(layers "F.Cu" "F.SilkS")
		(name "allow_overlap")
		(hatch edge 0.5)
		(connect_pads
			(clearance 0)
		)
		(min_thickness 0.25)
		(filled_areas_thickness no)
		(keepout
			(tracks allowed)
			(vias allowed)
			(pads allowed)
			(copperpour allowed)
			(footprints allowed)
		)
		(fill
			(thermal_gap 0.5)
			(thermal_bridge_width 0.5)
		)
		(polygon
			(pts
				(xy 134.61 87.7) (xy 135.6 87.7) (xy 135.6 90.6) (xy 134.61 90.6)
			)
		)
	)
	(zone
		(net 0)
		(net_name "")
		(layers "F.Cu" "F.SilkS")
		(name "allow_overlap")
		(hatch edge 0.5)
		(connect_pads
			(clearance 0)
		)
		(min_thickness 0.25)
		(filled_areas_thickness no)
		(keepout
			(tracks allowed)
			(vias allowed)
			(pads allowed)
			(copperpour allowed)
			(footprints allowed)
		)
		(fill
			(thermal_gap 0.5)
			(thermal_bridge_width 0.5)
		)
		(polygon
			(pts
				(xy 135.75 90.5) (xy 136.74 90.5) (xy 136.74 93.4) (xy 135.75 93.4)
			)
		)
	)
	(zone
		(net 1)
		(net_name "GND")
		(layer "In1.Cu")
		(hatch edge 0.508)
		(priority 5)
		(connect_pads yes
			(clearance 0.125)
		)
		(min_thickness 0.254)
		(filled_areas_thickness no)
		(fill yes
			(thermal_gap 0.508)
			(thermal_bridge_width 0.508)
		)
		(polygon
			(pts
				(xy 134.414506 117.89) (xy 134.396655 117.800258) (xy 134.345821 117.724179) (xy 134.269742 117.673345)
				(xy 134.18 117.655494) (xy 134.090258 117.673345) (xy 134.014179 117.724179) (xy 133.963345 117.800258)
				(xy 133.945494 117.89) (xy 133.963345 117.979742) (xy 134.014179 118.055821) (xy 134.090258 118.106655)
				(xy 134.18 118.124506) (xy 134.269742 118.106655) (xy 134.345821 118.055821) (xy 134.396655 117.979742)
			)
		)
	)
	(zone
		(net 788)
		(net_name "VDD_SoM")
		(layer "In1.Cu")
		(hatch edge 0.5)
		(priority 25)
		(connect_pads yes
			(clearance 0.125)
		)
		(min_thickness 0.25)
		(filled_areas_thickness no)
		(fill yes
			(thermal_gap 0.5)
			(thermal_bridge_width 0.5)
		)
		(polygon
			(pts
				(xy 51.34 84.015) (xy 51.34 86.879056) (xy 53.499827 88.639433) (xy 57.195 88.635) (xy 57.61 88.22)
				(xy 57.61 86.005) (xy 54.71 86.005) (xy 53.835 85.13) (xy 53.835 82.735) (xy 52.125 81.025) (xy 49.95 81.025)
				(xy 49.825 81.15) (xy 49.825 82.5)
			)
		)
	)
	(zone
		(net 0)
		(net_name "")
		(layer "In1.Cu")
		(hatch edge 0.508)
		(connect_pads
			(clearance 0)
		)
		(min_thickness 0.254)
		(filled_areas_thickness no)
		(keepout
			(tracks not_allowed)
			(vias not_allowed)
			(pads not_allowed)
			(copperpour not_allowed)
			(footprints allowed)
		)
		(fill
			(thermal_gap 0.508)
			(thermal_bridge_width 0.508)
		)
		(polygon
			(pts
				(xy 115.85 118.95) (xy 114.9 118.95) (xy 114.9 117.5) (xy 115.85 117.5)
			)
		)
	)
	(zone
		(net 0)
		(net_name "")
		(layer "In1.Cu")
		(hatch edge 0.508)
		(connect_pads
			(clearance 0)
		)
		(min_thickness 0.254)
		(filled_areas_thickness no)
		(keepout
			(tracks not_allowed)
			(vias not_allowed)
			(pads not_allowed)
			(copperpour not_allowed)
			(footprints allowed)
		)
		(fill
			(thermal_gap 0.508)
			(thermal_bridge_width 0.508)
		)
		(polygon
			(pts
				(xy 94.35 118.85) (xy 92.85 118.85) (xy 92.85 117.75) (xy 94.35 117.75)
			)
		)
	)
	(zone
		(net 0)
		(net_name "")
		(layer "In1.Cu")
		(hatch edge 0.508)
		(connect_pads
			(clearance 0)
		)
		(min_thickness 0.254)
		(filled_areas_thickness no)
		(keepout
			(tracks not_allowed)
			(vias not_allowed)
			(pads not_allowed)
			(copperpour not_allowed)
			(footprints allowed)
		)
		(fill
			(thermal_gap 0.508)
			(thermal_bridge_width 0.508)
		)
		(polygon
			(pts
				(xy 82.75 108.35) (xy 81.05 108.35) (xy 81.05 106.65) (xy 82.75 106.65)
			)
		)
	)
	(zone
		(net 0)
		(net_name "")
		(layer "In1.Cu")
		(hatch edge 0.508)
		(connect_pads
			(clearance 0)
		)
		(min_thickness 0.254)
		(filled_areas_thickness no)
		(keepout
			(tracks not_allowed)
			(vias not_allowed)
			(pads not_allowed)
			(copperpour not_allowed)
			(footprints allowed)
		)
		(fill
			(thermal_gap 0.508)
			(thermal_bridge_width 0.508)
		)
		(polygon
			(pts
				(xy 110.25 116.9) (xy 109.3 116.9) (xy 109.3 115.45) (xy 110.25 115.45)
			)
		)
	)
	(zone
		(net 0)
		(net_name "")
		(layer "In1.Cu")
		(hatch edge 0.508)
		(connect_pads
			(clearance 0)
		)
		(min_thickness 0.254)
		(filled_areas_thickness no)
		(keepout
			(tracks not_allowed)
			(vias not_allowed)
			(pads not_allowed)
			(copperpour not_allowed)
			(footprints allowed)
		)
		(fill
			(thermal_gap 0.508)
			(thermal_bridge_width 0.508)
		)
		(polygon
			(pts
				(xy 87.6 81.1) (xy 86.6 81.1) (xy 86.6 79.3) (xy 87.6 79.3)
			)
		)
	)
	(zone
		(net 0)
		(net_name "")
		(layer "In1.Cu")
		(hatch edge 0.508)
		(connect_pads
			(clearance 0)
		)
		(min_thickness 0.254)
		(filled_areas_thickness no)
		(keepout
			(tracks not_allowed)
			(vias not_allowed)
			(pads not_allowed)
			(copperpour not_allowed)
			(footprints allowed)
		)
		(fill
			(thermal_gap 0.508)
			(thermal_bridge_width 0.508)
		)
		(polygon
			(pts
				(xy 112.15 112.6) (xy 110.45 112.6) (xy 110.45 110.9) (xy 112.15 110.9)
			)
		)
	)
	(zone
		(net 0)
		(net_name "")
		(layer "In1.Cu")
		(hatch edge 0.508)
		(connect_pads
			(clearance 0)
		)
		(min_thickness 0.254)
		(filled_areas_thickness no)
		(keepout
			(tracks not_allowed)
			(vias not_allowed)
			(pads not_allowed)
			(copperpour not_allowed)
			(footprints allowed)
		)
		(fill
			(thermal_gap 0.508)
			(thermal_bridge_width 0.508)
		)
		(polygon
			(pts
				(xy 82.75 105.95) (xy 81.05 105.95) (xy 81.05 104.25) (xy 82.75 104.25)
			)
		)
	)
	(zone
		(net 0)
		(net_name "")
		(layer "In1.Cu")
		(hatch edge 0.508)
		(connect_pads
			(clearance 0)
		)
		(min_thickness 0.254)
		(filled_areas_thickness no)
		(keepout
			(tracks not_allowed)
			(vias not_allowed)
			(pads not_allowed)
			(copperpour not_allowed)
			(footprints allowed)
		)
		(fill
			(thermal_gap 0.508)
			(thermal_bridge_width 0.508)
		)
		(polygon
			(pts
				(xy 142.1 92.3) (xy 140.9 92.3) (xy 140.9 90.8) (xy 142.1 90.8)
			)
		)
	)
	(zone
		(net 0)
		(net_name "")
		(layer "In1.Cu")
		(hatch edge 0.508)
		(connect_pads
			(clearance 0)
		)
		(min_thickness 0.254)
		(filled_areas_thickness no)
		(keepout
			(tracks not_allowed)
			(vias not_allowed)
			(pads not_allowed)
			(copperpour not_allowed)
			(footprints allowed)
		)
		(fill
			(thermal_gap 0.508)
			(thermal_bridge_width 0.508)
		)
		(polygon
			(pts
				(xy 147.75 88.05) (xy 147.15 88.05) (xy 147.15 87.05) (xy 147.75 87.05)
			)
		)
	)
	(zone
		(net 1)
		(net_name "GND")
		(layer "In1.Cu")
		(hatch edge 0.508)
		(priority 5)
		(connect_pads yes
			(clearance 0.125)
		)
		(min_thickness 0.254)
		(filled_areas_thickness no)
		(fill yes
			(thermal_gap 0.508)
			(thermal_bridge_width 0.508)
		)
		(polygon
			(pts
				(xy 109.534506 83.25) (xy 109.516655 83.160258) (xy 109.465821 83.084179) (xy 109.389742 83.033345)
				(xy 109.3 83.015494) (xy 109.210258 83.033345) (xy 109.134179 83.084179) (xy 109.083345 83.160258)
				(xy 109.065494 83.25) (xy 109.083345 83.339742) (xy 109.134179 83.415821) (xy 109.210258 83.466655)
				(xy 109.3 83.484506) (xy 109.389742 83.466655) (xy 109.465821 83.415821) (xy 109.516655 83.339742)
			)
		)
	)
	(zone
		(net 0)
		(net_name "")
		(layer "In1.Cu")
		(hatch edge 0.508)
		(connect_pads
			(clearance 0)
		)
		(min_thickness 0.254)
		(filled_areas_thickness no)
		(keepout
			(tracks not_allowed)
			(vias not_allowed)
			(pads not_allowed)
			(copperpour not_allowed)
			(footprints allowed)
		)
		(fill
			(thermal_gap 0.508)
			(thermal_bridge_width 0.508)
		)
		(polygon
			(pts
				(xy 87.35 73.05) (xy 86.35 73.05) (xy 86.35 71.05) (xy 87.35 71.05)
			)
		)
	)
	(zone
		(net 0)
		(net_name "")
		(layer "In1.Cu")
		(hatch edge 0.508)
		(connect_pads
			(clearance 0)
		)
		(min_thickness 0.254)
		(filled_areas_thickness no)
		(keepout
			(tracks not_allowed)
			(vias not_allowed)
			(pads not_allowed)
			(copperpour not_allowed)
			(footprints allowed)
		)
		(fill
			(thermal_gap 0.508)
			(thermal_bridge_width 0.508)
		)
		(polygon
			(pts
				(xy 135.4 89.65) (xy 134.8 89.65) (xy 134.8 88.65) (xy 135.4 88.65)
			)
		)
	)
	(zone
		(net 0)
		(net_name "")
		(layer "In1.Cu")
		(hatch edge 0.508)
		(connect_pads
			(clearance 0)
		)
		(min_thickness 0.254)
		(filled_areas_thickness no)
		(keepout
			(tracks not_allowed)
			(vias not_allowed)
			(pads not_allowed)
			(copperpour not_allowed)
			(footprints allowed)
		)
		(fill
			(thermal_gap 0.508)
			(thermal_bridge_width 0.508)
		)
		(polygon
			(pts
				(xy 121.1 81.01) (xy 120.1 81.01) (xy 120.1 79.29) (xy 121.1 79.29)
			)
		)
	)
	(zone
		(net 0)
		(net_name "")
		(layer "In1.Cu")
		(hatch edge 0.508)
		(connect_pads
			(clearance 0)
		)
		(min_thickness 0.254)
		(filled_areas_thickness no)
		(keepout
			(tracks not_allowed)
			(vias not_allowed)
			(pads not_allowed)
			(copperpour not_allowed)
			(footprints allowed)
		)
		(fill
			(thermal_gap 0.508)
			(thermal_bridge_width 0.508)
		)
		(polygon
			(pts
				(xy 125.6 81.1) (xy 124.6 81.1) (xy 124.6 79.2) (xy 125.6 79.2)
			)
		)
	)
	(zone
		(net 0)
		(net_name "")
		(layer "In1.Cu")
		(hatch edge 0.508)
		(connect_pads
			(clearance 0)
		)
		(min_thickness 0.254)
		(filled_areas_thickness no)
		(keepout
			(tracks not_allowed)
			(vias not_allowed)
			(pads not_allowed)
			(copperpour not_allowed)
			(footprints allowed)
		)
		(fill
			(thermal_gap 0.508)
			(thermal_bridge_width 0.508)
		)
		(polygon
			(pts
				(xy 102.1 81.25) (xy 101.1 81.25) (xy 101.1 79.25) (xy 102.1 79.25)
			)
		)
	)
	(zone
		(net 0)
		(net_name "")
		(layer "In1.Cu")
		(hatch edge 0.508)
		(connect_pads
			(clearance 0)
		)
		(min_thickness 0.254)
		(filled_areas_thickness no)
		(keepout
			(tracks not_allowed)
			(vias not_allowed)
			(pads not_allowed)
			(copperpour not_allowed)
			(footprints allowed)
		)
		(fill
			(thermal_gap 0.508)
			(thermal_bridge_width 0.508)
		)
		(polygon
			(pts
				(xy 142.1 89.9) (xy 140.9 89.9) (xy 140.9 88.4) (xy 142.1 88.4)
			)
		)
	)
	(zone
		(net 0)
		(net_name "")
		(layer "In1.Cu")
		(hatch edge 0.508)
		(connect_pads
			(clearance 0)
		)
		(min_thickness 0.254)
		(filled_areas_thickness no)
		(keepout
			(tracks not_allowed)
			(vias not_allowed)
			(pads not_allowed)
			(copperpour not_allowed)
			(footprints allowed)
		)
		(fill
			(thermal_gap 0.508)
			(thermal_bridge_width 0.508)
		)
		(polygon
			(pts
				(xy 106 110.35) (xy 104.3 110.35) (xy 104.3 108.65) (xy 106 108.65)
			)
		)
	)
	(zone
		(net 0)
		(net_name "")
		(layer "In1.Cu")
		(hatch edge 0.508)
		(connect_pads
			(clearance 0)
		)
		(min_thickness 0.254)
		(filled_areas_thickness no)
		(keepout
			(tracks not_allowed)
			(vias not_allowed)
			(pads not_allowed)
			(copperpour not_allowed)
			(footprints allowed)
		)
		(fill
			(thermal_gap 0.508)
			(thermal_bridge_width 0.508)
		)
		(polygon
			(pts
				(xy 109.35 73) (xy 108.35 73) (xy 108.35 71) (xy 109.35 71)
			)
		)
	)
	(zone
		(net 0)
		(net_name "")
		(layer "In1.Cu")
		(hatch edge 0.508)
		(connect_pads
			(clearance 0)
		)
		(min_thickness 0.254)
		(filled_areas_thickness no)
		(keepout
			(tracks not_allowed)
			(vias not_allowed)
			(pads not_allowed)
			(copperpour not_allowed)
			(footprints allowed)
		)
		(fill
			(thermal_gap 0.508)
			(thermal_bridge_width 0.508)
		)
		(polygon
			(pts
				(xy 124.35 73) (xy 123.35 73) (xy 123.35 71) (xy 124.35 71)
			)
		)
	)
	(zone
		(net 0)
		(net_name "")
		(layer "In1.Cu")
		(hatch edge 0.508)
		(connect_pads
			(clearance 0)
		)
		(min_thickness 0.254)
		(filled_areas_thickness no)
		(keepout
			(tracks not_allowed)
			(vias not_allowed)
			(pads not_allowed)
			(copperpour not_allowed)
			(footprints allowed)
		)
		(fill
			(thermal_gap 0.508)
			(thermal_bridge_width 0.508)
		)
		(polygon
			(pts
				(xy 119.85 73) (xy 118.85 73) (xy 118.85 71) (xy 119.85 71)
			)
		)
	)
	(zone
		(net 0)
		(net_name "")
		(layer "In1.Cu")
		(hatch edge 0.508)
		(connect_pads
			(clearance 0)
		)
		(min_thickness 0.254)
		(filled_areas_thickness no)
		(keepout
			(tracks not_allowed)
			(vias not_allowed)
			(pads not_allowed)
			(copperpour not_allowed)
			(footprints allowed)
		)
		(fill
			(thermal_gap 0.508)
			(thermal_bridge_width 0.508)
		)
		(polygon
			(pts
				(xy 116.85 73.05) (xy 115.85 73.05) (xy 115.85 71.05) (xy 116.85 71.05)
			)
		)
	)
	(zone
		(net 0)
		(net_name "")
		(layer "In1.Cu")
		(hatch edge 0.508)
		(connect_pads
			(clearance 0)
		)
		(min_thickness 0.254)
		(filled_areas_thickness no)
		(keepout
			(tracks not_allowed)
			(vias not_allowed)
			(pads not_allowed)
			(copperpour not_allowed)
			(footprints allowed)
		)
		(fill
			(thermal_gap 0.508)
			(thermal_bridge_width 0.508)
		)
		(polygon
			(pts
				(xy 74.95 111.8) (xy 73.25 111.8) (xy 73.25 110.15) (xy 74.95 110.15)
			)
		)
	)
	(zone
		(net 0)
		(net_name "")
		(layer "In1.Cu")
		(hatch edge 0.508)
		(connect_pads
			(clearance 0)
		)
		(min_thickness 0.254)
		(filled_areas_thickness no)
		(keepout
			(tracks not_allowed)
			(vias not_allowed)
			(pads not_allowed)
			(copperpour not_allowed)
			(footprints allowed)
		)
		(fill
			(thermal_gap 0.508)
			(thermal_bridge_width 0.508)
		)
		(polygon
			(pts
				(xy 77.2 118.85) (xy 76.25 118.85) (xy 76.25 117.4) (xy 77.2 117.4)
			)
		)
	)
	(zone
		(net 0)
		(net_name "")
		(layer "In1.Cu")
		(hatch edge 0.508)
		(connect_pads
			(clearance 0)
		)
		(min_thickness 0.254)
		(filled_areas_thickness no)
		(keepout
			(tracks not_allowed)
			(vias not_allowed)
			(pads not_allowed)
			(copperpour not_allowed)
			(footprints allowed)
		)
		(fill
			(thermal_gap 0.508)
			(thermal_bridge_width 0.508)
		)
		(polygon
			(pts
				(xy 76.95 111.8) (xy 75.25 111.8) (xy 75.25 110.15) (xy 76.95 110.15)
			)
		)
	)
	(zone
		(net 0)
		(net_name "")
		(layer "In1.Cu")
		(hatch edge 0.508)
		(connect_pads
			(clearance 0)
		)
		(min_thickness 0.254)
		(filled_areas_thickness no)
		(keepout
			(tracks not_allowed)
			(vias not_allowed)
			(pads not_allowed)
			(copperpour not_allowed)
			(footprints allowed)
		)
		(fill
			(thermal_gap 0.508)
			(thermal_bridge_width 0.508)
		)
		(polygon
			(pts
				(xy 138.3 84) (xy 137.35 84) (xy 137.35 84.3) (xy 135.5 84.3) (xy 135.5 82.6) (xy 137.4 82.6) (xy 137.4 82.95)
				(xy 138.3 82.95)
			)
		)
	)
	(zone
		(net 0)
		(net_name "")
		(layer "In1.Cu")
		(hatch edge 0.508)
		(connect_pads
			(clearance 0)
		)
		(min_thickness 0.254)
		(filled_areas_thickness no)
		(keepout
			(tracks not_allowed)
			(vias not_allowed)
			(pads not_allowed)
			(copperpour not_allowed)
			(footprints allowed)
		)
		(fill
			(thermal_gap 0.508)
			(thermal_bridge_width 0.508)
		)
		(polygon
			(pts
				(xy 118.15 112.6) (xy 116.45 112.6) (xy 116.45 110.9) (xy 118.15 110.9)
			)
		)
	)
	(zone
		(net 0)
		(net_name "")
		(layer "In1.Cu")
		(hatch edge 0.508)
		(connect_pads
			(clearance 0)
		)
		(min_thickness 0.254)
		(filled_areas_thickness no)
		(keepout
			(tracks not_allowed)
			(vias not_allowed)
			(pads not_allowed)
			(copperpour not_allowed)
			(footprints allowed)
		)
		(fill
			(thermal_gap 0.508)
			(thermal_bridge_width 0.508)
		)
		(polygon
			(pts
				(xy 146.6 85.9) (xy 145.4 85.9) (xy 145.4 84.4) (xy 146.6 84.4)
			)
		)
	)
	(zone
		(net 0)
		(net_name "")
		(layer "In1.Cu")
		(hatch edge 0.508)
		(connect_pads
			(clearance 0)
		)
		(min_thickness 0.254)
		(filled_areas_thickness no)
		(keepout
			(tracks not_allowed)
			(vias not_allowed)
			(pads not_allowed)
			(copperpour not_allowed)
			(footprints allowed)
		)
		(fill
			(thermal_gap 0.508)
			(thermal_bridge_width 0.508)
		)
		(polygon
			(pts
				(xy 73.25 116.25) (xy 72.3 116.25) (xy 72.3 114.8) (xy 73.25 114.8)
			)
		)
	)
	(zone
		(net 0)
		(net_name "")
		(layer "In1.Cu")
		(hatch edge 0.508)
		(connect_pads
			(clearance 0)
		)
		(min_thickness 0.254)
		(filled_areas_thickness no)
		(keepout
			(tracks not_allowed)
			(vias not_allowed)
			(pads not_allowed)
			(copperpour not_allowed)
			(footprints allowed)
		)
		(fill
			(thermal_gap 0.508)
			(thermal_bridge_width 0.508)
		)
		(polygon
			(pts
				(xy 97.45 118.85) (xy 95.95 118.85) (xy 95.95 117.75) (xy 97.45 117.75)
			)
		)
	)
	(zone
		(net 0)
		(net_name "")
		(layer "In1.Cu")
		(hatch edge 0.508)
		(connect_pads
			(clearance 0)
		)
		(min_thickness 0.254)
		(filled_areas_thickness no)
		(keepout
			(tracks not_allowed)
			(vias not_allowed)
			(pads not_allowed)
			(copperpour not_allowed)
			(footprints allowed)
		)
		(fill
			(thermal_gap 0.508)
			(thermal_bridge_width 0.508)
		)
		(polygon
			(pts
				(xy 127.52 95.98) (xy 127.29 97) (xy 125.9 97) (xy 125.9 95.3) (xy 127.51 95.3)
			)
		)
	)
	(zone
		(net 99)
		(net_name "+5V")
		(layer "In1.Cu")
		(hatch edge 0.508)
		(priority 4)
		(connect_pads yes
			(clearance 0.125)
		)
		(min_thickness 0.125)
		(filled_areas_thickness no)
		(fill yes
			(thermal_gap 0.508)
			(thermal_bridge_width 0.508)
		)
		(polygon
			(pts
				(xy 99.5 89) (xy 97.5 89) (xy 97.5 94.5) (xy 98.5 95.5) (xy 98.5 97) (xy 101 99.5) (xy 101 109.7)
				(xy 102.3 111.1) (xy 102.3 119) (xy 100 119) (xy 100 113) (xy 96 113) (xy 96 95.5) (xy 94.5 94)
				(xy 94.5 86.5) (xy 96.5 86.5) (xy 96.5 85) (xy 99.5 85)
			)
		)
	)
	(zone
		(net 0)
		(net_name "")
		(layer "In1.Cu")
		(hatch edge 0.508)
		(connect_pads
			(clearance 0)
		)
		(min_thickness 0.254)
		(filled_areas_thickness no)
		(keepout
			(tracks not_allowed)
			(vias not_allowed)
			(pads not_allowed)
			(copperpour not_allowed)
			(footprints allowed)
		)
		(fill
			(thermal_gap 0.508)
			(thermal_bridge_width 0.508)
		)
		(polygon
			(pts
				(xy 125.85 73) (xy 124.85 73) (xy 124.85 71) (xy 125.85 71)
			)
		)
	)
	(zone
		(net 0)
		(net_name "")
		(layer "In1.Cu")
		(hatch edge 0.508)
		(connect_pads
			(clearance 0)
		)
		(min_thickness 0.254)
		(filled_areas_thickness no)
		(keepout
			(tracks not_allowed)
			(vias not_allowed)
			(pads not_allowed)
			(copperpour not_allowed)
			(footprints allowed)
		)
		(fill
			(thermal_gap 0.508)
			(thermal_bridge_width 0.508)
		)
		(polygon
			(pts
				(xy 79.2 116.2) (xy 78.25 116.2) (xy 78.25 114.75) (xy 79.2 114.75)
			)
		)
	)
	(zone
		(net 0)
		(net_name "")
		(layer "In1.Cu")
		(hatch edge 0.508)
		(connect_pads
			(clearance 0)
		)
		(min_thickness 0.254)
		(filled_areas_thickness no)
		(keepout
			(tracks not_allowed)
			(vias not_allowed)
			(pads not_allowed)
			(copperpour not_allowed)
			(footprints allowed)
		)
		(fill
			(thermal_gap 0.508)
			(thermal_bridge_width 0.508)
		)
		(polygon
			(pts
				(xy 118.35 73.05) (xy 117.35 73.05) (xy 117.35 71.05) (xy 118.35 71.05)
			)
		)
	)
	(zone
		(net 328)
		(net_name "/Supply/VCC_IN")
		(layer "In1.Cu")
		(hatch edge 0.508)
		(priority 1)
		(connect_pads
			(clearance 0.2)
		)
		(min_thickness 0.254)
		(filled_areas_thickness no)
		(fill yes
			(thermal_gap 0.508)
			(thermal_bridge_width 0.508)
		)
		(polygon
			(pts
				(xy 52 81.2) (xy 52 87) (xy 60 87) (xy 60 94.6) (xy 63.2 94.6) (xy 63.18 114.01) (xy 52.6 114) (xy 52.6 98.19)
				(xy 50.554286 96.4) (xy 46 96.4) (xy 46 84.32) (xy 44.88 83.2) (xy 43.6 83.2) (xy 43.6 80.2) (xy 51 80.2)
			)
		)
	)
	(zone
		(net 0)
		(net_name "")
		(layer "In1.Cu")
		(hatch edge 0.508)
		(connect_pads
			(clearance 0)
		)
		(min_thickness 0.254)
		(filled_areas_thickness no)
		(keepout
			(tracks not_allowed)
			(vias not_allowed)
			(pads not_allowed)
			(copperpour not_allowed)
			(footprints allowed)
		)
		(fill
			(thermal_gap 0.508)
			(thermal_bridge_width 0.508)
		)
		(polygon
			(pts
				(xy 136.7 92.4) (xy 135.75 92.4) (xy 135.75 92.7) (xy 133.9 92.7) (xy 133.9 91) (xy 135.8 91) (xy 135.8 91.35)
				(xy 136.7 91.35)
			)
		)
	)
	(zone
		(net 0)
		(net_name "")
		(layer "In1.Cu")
		(hatch edge 0.508)
		(connect_pads
			(clearance 0)
		)
		(min_thickness 0.254)
		(filled_areas_thickness no)
		(keepout
			(tracks not_allowed)
			(vias not_allowed)
			(pads not_allowed)
			(copperpour not_allowed)
			(footprints allowed)
		)
		(fill
			(thermal_gap 0.508)
			(thermal_bridge_width 0.508)
		)
		(polygon
			(pts
				(xy 96.35 73.05) (xy 95.35 73.05) (xy 95.35 71.05) (xy 96.35 71.05)
			)
		)
	)
	(zone
		(net 0)
		(net_name "")
		(layer "In1.Cu")
		(hatch edge 0.508)
		(connect_pads
			(clearance 0)
		)
		(min_thickness 0.254)
		(filled_areas_thickness no)
		(keepout
			(tracks not_allowed)
			(vias not_allowed)
			(pads not_allowed)
			(copperpour not_allowed)
			(footprints allowed)
		)
		(fill
			(thermal_gap 0.508)
			(thermal_bridge_width 0.508)
		)
		(polygon
			(pts
				(xy 112.35 73) (xy 111.35 73) (xy 111.35 71) (xy 112.35 71)
			)
		)
	)
	(zone
		(net 0)
		(net_name "")
		(layer "In1.Cu")
		(hatch edge 0.508)
		(connect_pads
			(clearance 0)
		)
		(min_thickness 0.254)
		(filled_areas_thickness no)
		(keepout
			(tracks not_allowed)
			(vias not_allowed)
			(pads not_allowed)
			(copperpour not_allowed)
			(footprints allowed)
		)
		(fill
			(thermal_gap 0.508)
			(thermal_bridge_width 0.508)
		)
		(polygon
			(pts
				(xy 116.6 81.2) (xy 115.6 81.2) (xy 115.6 79.2) (xy 116.6 79.2)
			)
		)
	)
	(zone
		(net 0)
		(net_name "")
		(layer "In1.Cu")
		(hatch edge 0.508)
		(connect_pads
			(clearance 0)
		)
		(min_thickness 0.254)
		(filled_areas_thickness no)
		(keepout
			(tracks not_allowed)
			(vias not_allowed)
			(pads not_allowed)
			(copperpour not_allowed)
			(footprints allowed)
		)
		(fill
			(thermal_gap 0.508)
			(thermal_bridge_width 0.508)
		)
		(polygon
			(pts
				(xy 112.1 81.2) (xy 111.1 81.2) (xy 111.1 79.31) (xy 112.1 79.31)
			)
		)
	)
	(zone
		(net 0)
		(net_name "")
		(layer "In1.Cu")
		(hatch edge 0.508)
		(connect_pads
			(clearance 0)
		)
		(min_thickness 0.254)
		(filled_areas_thickness no)
		(keepout
			(tracks not_allowed)
			(vias not_allowed)
			(pads not_allowed)
			(copperpour not_allowed)
			(footprints allowed)
		)
		(fill
			(thermal_gap 0.508)
			(thermal_bridge_width 0.508)
		)
		(polygon
			(pts
				(xy 81.6 81.1) (xy 80.6 81.1) (xy 80.6 79.3) (xy 81.6 79.3)
			)
		)
	)
	(zone
		(net 0)
		(net_name "")
		(layer "In1.Cu")
		(hatch edge 0.508)
		(connect_pads
			(clearance 0)
		)
		(min_thickness 0.254)
		(filled_areas_thickness no)
		(keepout
			(tracks not_allowed)
			(vias not_allowed)
			(pads not_allowed)
			(copperpour not_allowed)
			(footprints allowed)
		)
		(fill
			(thermal_gap 0.508)
			(thermal_bridge_width 0.508)
		)
		(polygon
			(pts
				(xy 142.1 87.5) (xy 140.9 87.5) (xy 140.9 86) (xy 142.1 86)
			)
		)
	)
	(zone
		(net 87)
		(net_name "+3V3")
		(layer "In1.Cu")
		(hatch edge 0.508)
		(priority 1)
		(connect_pads yes
			(clearance 0.2)
		)
		(min_thickness 0.254)
		(filled_areas_thickness no)
		(fill yes
			(thermal_gap 0.508)
			(thermal_bridge_width 5)
		)
		(polygon
			(pts
				(xy 119.3 99.9) (xy 120.458202 100) (xy 120.5 104.5) (xy 118.75 104.5) (xy 118.75 106) (xy 119.75 107)
				(xy 121.5 107) (xy 121.5 112.7) (xy 131.7 112.7) (xy 131.7 108.9) (xy 134.65 108.9) (xy 134.65 110.7)
				(xy 133.92 110.7) (xy 133.95 124.5) (xy 98.1 124.35) (xy 98.1 115.5) (xy 96 115.5) (xy 95.999989 113.1)
				(xy 99.899989 113.099382) (xy 99.912415 119.198767) (xy 108.5 119.199945) (xy 108.500032 121.741966)
				(xy 118.75 121.75) (xy 118.75 109.75) (xy 116 107) (xy 116 89) (xy 107.7 89) (xy 103.75 85) (xy 96.6 85)
				(xy 96.600609 86.384054) (xy 94.4 86.4) (xy 94.4 82.6) (xy 108.4 82.7) (xy 112 86.25) (xy 119.2 86.25)
			)
		)
	)
	(zone
		(net 0)
		(net_name "")
		(layer "In1.Cu")
		(hatch edge 0.508)
		(connect_pads
			(clearance 0)
		)
		(min_thickness 0.254)
		(filled_areas_thickness no)
		(keepout
			(tracks not_allowed)
			(vias not_allowed)
			(pads not_allowed)
			(copperpour not_allowed)
			(footprints allowed)
		)
		(fill
			(thermal_gap 0.508)
			(thermal_bridge_width 0.508)
		)
		(polygon
			(pts
				(xy 113.25 116.9) (xy 112.3 116.9) (xy 112.3 115.45) (xy 113.25 115.45)
			)
		)
	)
	(zone
		(net 0)
		(net_name "")
		(layer "In1.Cu")
		(hatch edge 0.508)
		(connect_pads
			(clearance 0)
		)
		(min_thickness 0.254)
		(filled_areas_thickness no)
		(keepout
			(tracks not_allowed)
			(vias not_allowed)
			(pads not_allowed)
			(copperpour not_allowed)
			(footprints allowed)
		)
		(fill
			(thermal_gap 0.508)
			(thermal_bridge_width 0.508)
		)
		(polygon
			(pts
				(xy 147.75 90.65) (xy 147.15 90.65) (xy 147.15 89.65) (xy 147.75 89.65)
			)
		)
	)
	(zone
		(net 0)
		(net_name "")
		(layer "In1.Cu")
		(hatch edge 0.508)
		(connect_pads
			(clearance 0)
		)
		(min_thickness 0.254)
		(filled_areas_thickness no)
		(keepout
			(tracks not_allowed)
			(vias not_allowed)
			(pads not_allowed)
			(copperpour not_allowed)
			(footprints allowed)
		)
		(fill
			(thermal_gap 0.508)
			(thermal_bridge_width 0.508)
		)
		(polygon
			(pts
				(xy 76.25 116.25) (xy 75.3 116.25) (xy 75.3 114.85) (xy 76.25 114.85)
			)
		)
	)
	(zone
		(net 0)
		(net_name "")
		(layer "In1.Cu")
		(hatch edge 0.508)
		(connect_pads
			(clearance 0)
		)
		(min_thickness 0.254)
		(filled_areas_thickness no)
		(keepout
			(tracks not_allowed)
			(vias not_allowed)
			(pads not_allowed)
			(copperpour not_allowed)
			(footprints allowed)
		)
		(fill
			(thermal_gap 0.508)
			(thermal_bridge_width 0.508)
		)
		(polygon
			(pts
				(xy 77.7 116.2) (xy 76.75 116.2) (xy 76.75 114.75) (xy 77.7 114.75)
			)
		)
	)
	(zone
		(net 0)
		(net_name "")
		(layer "In1.Cu")
		(hatch edge 0.508)
		(connect_pads
			(clearance 0)
		)
		(min_thickness 0.254)
		(filled_areas_thickness no)
		(keepout
			(tracks not_allowed)
			(vias not_allowed)
			(pads not_allowed)
			(copperpour not_allowed)
			(footprints allowed)
		)
		(fill
			(thermal_gap 0.508)
			(thermal_bridge_width 0.508)
		)
		(polygon
			(pts
				(xy 122.6 81.15) (xy 121.6 81.15) (xy 121.6 79.15) (xy 122.6 79.15)
			)
		)
	)
	(zone
		(net 0)
		(net_name "")
		(layer "In1.Cu")
		(hatch edge 0.508)
		(connect_pads
			(clearance 0)
		)
		(min_thickness 0.254)
		(filled_areas_thickness no)
		(keepout
			(tracks not_allowed)
			(vias not_allowed)
			(pads not_allowed)
			(copperpour not_allowed)
			(footprints allowed)
		)
		(fill
			(thermal_gap 0.508)
			(thermal_bridge_width 0.508)
		)
		(polygon
			(pts
				(xy 142.1 85.1) (xy 140.9 85.1) (xy 140.9 83.6) (xy 142.1 83.6)
			)
		)
	)
	(zone
		(net 1)
		(net_name "GND")
		(layer "In1.Cu")
		(hatch edge 0.508)
		(connect_pads yes
			(clearance 0.2)
		)
		(min_thickness 0.254)
		(filled_areas_thickness no)
		(fill yes
			(thermal_gap 0.508)
			(thermal_bridge_width 5)
		)
		(polygon
			(pts
				(xy 153.099036 67.069899) (xy 152.75 130.25) (xy 26.95 130.55) (xy 26.95 66.45) (xy 44.06 66.45)
			)
		)
	)
	(zone
		(net 1)
		(net_name "GND")
		(layer "In1.Cu")
		(hatch edge 0.508)
		(priority 105)
		(connect_pads yes
			(clearance 0.2)
		)
		(min_thickness 0.254)
		(filled_areas_thickness no)
		(fill yes
			(thermal_gap 0.508)
			(thermal_bridge_width 5)
		)
		(polygon
			(pts
				(xy 121.45 89) (xy 120.84 89) (xy 120.84 88.44) (xy 121.45 88.44)
			)
		)
	)
	(zone
		(net 0)
		(net_name "")
		(layer "In1.Cu")
		(hatch edge 0.508)
		(connect_pads
			(clearance 0)
		)
		(min_thickness 0.254)
		(filled_areas_thickness no)
		(keepout
			(tracks not_allowed)
			(vias not_allowed)
			(pads not_allowed)
			(copperpour not_allowed)
			(footprints allowed)
		)
		(fill
			(thermal_gap 0.508)
			(thermal_bridge_width 0.508)
		)
		(polygon
			(pts
				(xy 67.85 73) (xy 66.85 73) (xy 66.85 71) (xy 67.85 71)
			)
		)
	)
	(zone
		(net 0)
		(net_name "")
		(layer "In1.Cu")
		(hatch edge 0.508)
		(connect_pads
			(clearance 0)
		)
		(min_thickness 0.254)
		(filled_areas_thickness no)
		(keepout
			(tracks not_allowed)
			(vias not_allowed)
			(pads not_allowed)
			(copperpour not_allowed)
			(footprints allowed)
		)
		(fill
			(thermal_gap 0.508)
			(thermal_bridge_width 0.508)
		)
		(polygon
			(pts
				(xy 119.6 81.2) (xy 118.6 81.2) (xy 118.6 79.2) (xy 119.6 79.2)
			)
		)
	)
	(zone
		(net 0)
		(net_name "")
		(layer "In1.Cu")
		(hatch edge 0.508)
		(connect_pads
			(clearance 0)
		)
		(min_thickness 0.254)
		(filled_areas_thickness no)
		(keepout
			(tracks not_allowed)
			(vias not_allowed)
			(pads not_allowed)
			(copperpour not_allowed)
			(footprints allowed)
		)
		(fill
			(thermal_gap 0.508)
			(thermal_bridge_width 0.508)
		)
		(polygon
			(pts
				(xy 82.85 73.05) (xy 81.85 73.05) (xy 81.85 71.05) (xy 82.85 71.05)
			)
		)
	)
	(zone
		(net 0)
		(net_name "")
		(layer "In1.Cu")
		(hatch edge 0.508)
		(connect_pads
			(clearance 0)
		)
		(min_thickness 0.254)
		(filled_areas_thickness no)
		(keepout
			(tracks not_allowed)
			(vias not_allowed)
			(pads not_allowed)
			(copperpour not_allowed)
			(footprints allowed)
		)
		(fill
			(thermal_gap 0.508)
			(thermal_bridge_width 0.508)
		)
		(polygon
			(pts
				(xy 121.35 73) (xy 120.35 73) (xy 120.35 71) (xy 121.35 71)
			)
		)
	)
	(zone
		(net 0)
		(net_name "")
		(layer "In1.Cu")
		(hatch edge 0.508)
		(connect_pads
			(clearance 0)
		)
		(min_thickness 0.254)
		(filled_areas_thickness no)
		(keepout
			(tracks not_allowed)
			(vias not_allowed)
			(pads not_allowed)
			(copperpour not_allowed)
			(footprints allowed)
		)
		(fill
			(thermal_gap 0.508)
			(thermal_bridge_width 0.508)
		)
		(polygon
			(pts
				(xy 85.85 73.05) (xy 84.85 73.05) (xy 84.85 71.05) (xy 85.85 71.05)
			)
		)
	)
	(zone
		(net 0)
		(net_name "")
		(layer "In1.Cu")
		(hatch edge 0.508)
		(connect_pads
			(clearance 0)
		)
		(min_thickness 0.254)
		(filled_areas_thickness no)
		(keepout
			(tracks not_allowed)
			(vias not_allowed)
			(pads not_allowed)
			(copperpour not_allowed)
			(footprints allowed)
		)
		(fill
			(thermal_gap 0.508)
			(thermal_bridge_width 0.508)
		)
		(polygon
			(pts
				(xy 125.3 98.1) (xy 123.6 98.1) (xy 123.6 97.2) (xy 125.3 97.2)
			)
		)
	)
	(zone
		(net 0)
		(net_name "")
		(layer "In1.Cu")
		(hatch edge 0.508)
		(connect_pads
			(clearance 0)
		)
		(min_thickness 0.254)
		(filled_areas_thickness no)
		(keepout
			(tracks not_allowed)
			(vias not_allowed)
			(pads not_allowed)
			(copperpour not_allowed)
			(footprints allowed)
		)
		(fill
			(thermal_gap 0.508)
			(thermal_bridge_width 0.508)
		)
		(polygon
			(pts
				(xy 116.25 116.9) (xy 115.3 116.9) (xy 115.3 115.45) (xy 116.25 115.45)
			)
		)
	)
	(zone
		(net 1)
		(net_name "GND")
		(layer "In1.Cu")
		(hatch edge 0.508)
		(priority 105)
		(connect_pads yes
			(clearance 0.2)
		)
		(min_thickness 0.254)
		(filled_areas_thickness no)
		(fill yes
			(thermal_gap 0.508)
			(thermal_bridge_width 5)
		)
		(polygon
			(pts
				(xy 105.37 88.5) (xy 104.76 88.5) (xy 104.76 87.94) (xy 105.37 87.94)
			)
		)
	)
	(zone
		(net 0)
		(net_name "")
		(layer "In1.Cu")
		(hatch edge 0.508)
		(connect_pads
			(clearance 0)
		)
		(min_thickness 0.254)
		(filled_areas_thickness no)
		(keepout
			(tracks not_allowed)
			(vias not_allowed)
			(pads not_allowed)
			(copperpour not_allowed)
			(footprints allowed)
		)
		(fill
			(thermal_gap 0.508)
			(thermal_bridge_width 0.508)
		)
		(polygon
			(pts
				(xy 106.35 72.89) (xy 105.35 72.89) (xy 105.35 71) (xy 106.35 71)
			)
		)
	)
	(zone
		(net 0)
		(net_name "")
		(layer "In1.Cu")
		(hatch edge 0.508)
		(connect_pads
			(clearance 0)
		)
		(min_thickness 0.254)
		(filled_areas_thickness no)
		(keepout
			(tracks not_allowed)
			(vias not_allowed)
			(pads not_allowed)
			(copperpour not_allowed)
			(footprints allowed)
		)
		(fill
			(thermal_gap 0.508)
			(thermal_bridge_width 0.508)
		)
		(polygon
			(pts
				(xy 138.3 87.3) (xy 137.35 87.3) (xy 137.35 87.6) (xy 135.5 87.6) (xy 135.5 85.9) (xy 137.4 85.9)
				(xy 137.4 86.25) (xy 138.3 86.25)
			)
		)
	)
	(zone
		(net 0)
		(net_name "")
		(layer "In1.Cu")
		(hatch edge 0.508)
		(connect_pads
			(clearance 0)
		)
		(min_thickness 0.254)
		(filled_areas_thickness no)
		(keepout
			(tracks not_allowed)
			(vias not_allowed)
			(pads not_allowed)
			(copperpour not_allowed)
			(footprints allowed)
		)
		(fill
			(thermal_gap 0.508)
			(thermal_bridge_width 0.508)
		)
		(polygon
			(pts
				(xy 146.6 93.1) (xy 145.4 93.1) (xy 145.4 91.6) (xy 146.6 91.6)
			)
		)
	)
	(zone
		(net 0)
		(net_name "")
		(layer "In1.Cu")
		(hatch edge 0.508)
		(connect_pads
			(clearance 0)
		)
		(min_thickness 0.254)
		(filled_areas_thickness no)
		(keepout
			(tracks not_allowed)
			(vias not_allowed)
			(pads not_allowed)
			(copperpour not_allowed)
			(footprints allowed)
		)
		(fill
			(thermal_gap 0.508)
			(thermal_bridge_width 0.508)
		)
		(polygon
			(pts
				(xy 118.1 81.2) (xy 117.1 81.2) (xy 117.1 79.2) (xy 118.1 79.2)
			)
		)
	)
	(zone
		(net 0)
		(net_name "")
		(layer "In1.Cu")
		(hatch edge 0.508)
		(connect_pads
			(clearance 0)
		)
		(min_thickness 0.254)
		(filled_areas_thickness no)
		(keepout
			(tracks not_allowed)
			(vias not_allowed)
			(pads not_allowed)
			(copperpour not_allowed)
			(footprints allowed)
		)
		(fill
			(thermal_gap 0.508)
			(thermal_bridge_width 0.508)
		)
		(polygon
			(pts
				(xy 124.1 81.1) (xy 123.1 81.1) (xy 123.1 79.2) (xy 124.1 79.2)
			)
		)
	)
	(zone
		(net 0)
		(net_name "")
		(layer "In1.Cu")
		(hatch edge 0.508)
		(connect_pads
			(clearance 0)
		)
		(min_thickness 0.254)
		(filled_areas_thickness no)
		(keepout
			(tracks not_allowed)
			(vias not_allowed)
			(pads not_allowed)
			(copperpour not_allowed)
			(footprints allowed)
		)
		(fill
			(thermal_gap 0.508)
			(thermal_bridge_width 0.508)
		)
		(polygon
			(pts
				(xy 92.35 73) (xy 91.35 73) (xy 91.35 71) (xy 92.35 71)
			)
		)
	)
	(zone
		(net 0)
		(net_name "")
		(layer "In1.Cu")
		(hatch edge 0.508)
		(connect_pads
			(clearance 0)
		)
		(min_thickness 0.254)
		(filled_areas_thickness no)
		(keepout
			(tracks not_allowed)
			(vias not_allowed)
			(pads not_allowed)
			(copperpour not_allowed)
			(footprints allowed)
		)
		(fill
			(thermal_gap 0.508)
			(thermal_bridge_width 0.508)
		)
		(polygon
			(pts
				(xy 107.85 73) (xy 106.85 73) (xy 106.85 71) (xy 107.85 71)
			)
		)
	)
	(zone
		(net 0)
		(net_name "")
		(layer "In1.Cu")
		(hatch edge 0.508)
		(connect_pads
			(clearance 0)
		)
		(min_thickness 0.254)
		(filled_areas_thickness no)
		(keepout
			(tracks not_allowed)
			(vias not_allowed)
			(pads not_allowed)
			(copperpour not_allowed)
			(footprints allowed)
		)
		(fill
			(thermal_gap 0.508)
			(thermal_bridge_width 0.508)
		)
		(polygon
			(pts
				(xy 111.9 118.95) (xy 110.95 118.95) (xy 110.95 117.5) (xy 111.9 117.5)
			)
		)
	)
	(zone
		(net 0)
		(net_name "")
		(layer "In1.Cu")
		(hatch edge 0.508)
		(connect_pads
			(clearance 0)
		)
		(min_thickness 0.254)
		(filled_areas_thickness no)
		(keepout
			(tracks not_allowed)
			(vias not_allowed)
			(pads not_allowed)
			(copperpour not_allowed)
			(footprints allowed)
		)
		(fill
			(thermal_gap 0.508)
			(thermal_bridge_width 0.508)
		)
		(polygon
			(pts
				(xy 83.1 81.06) (xy 82.1 81.06) (xy 82.1 79.3) (xy 83.1 79.3)
			)
		)
	)
	(zone
		(net 0)
		(net_name "")
		(layer "In1.Cu")
		(hatch edge 0.508)
		(connect_pads
			(clearance 0)
		)
		(min_thickness 0.254)
		(filled_areas_thickness no)
		(keepout
			(tracks not_allowed)
			(vias not_allowed)
			(pads not_allowed)
			(copperpour not_allowed)
			(footprints allowed)
		)
		(fill
			(thermal_gap 0.508)
			(thermal_bridge_width 0.508)
		)
		(polygon
			(pts
				(xy 74.7 116.1) (xy 73.75 116.1) (xy 73.75 114.8) (xy 74.7 114.8)
			)
		)
	)
	(zone
		(net 0)
		(net_name "")
		(layer "In1.Cu")
		(hatch edge 0.508)
		(connect_pads
			(clearance 0)
		)
		(min_thickness 0.254)
		(filled_areas_thickness no)
		(keepout
			(tracks not_allowed)
			(vias not_allowed)
			(pads not_allowed)
			(copperpour not_allowed)
			(footprints allowed)
		)
		(fill
			(thermal_gap 0.508)
			(thermal_bridge_width 0.508)
		)
		(polygon
			(pts
				(xy 117.8 116.9) (xy 116.85 116.9) (xy 116.85 115.45) (xy 117.8 115.45)
			)
		)
	)
	(zone
		(net 1)
		(net_name "GND")
		(layer "In1.Cu")
		(hatch edge 0.508)
		(priority 105)
		(connect_pads yes
			(clearance 0.2)
		)
		(min_thickness 0.254)
		(filled_areas_thickness no)
		(fill yes
			(thermal_gap 0.508)
			(thermal_bridge_width 5)
		)
		(polygon
			(pts
				(xy 112.83 86.61) (xy 112.22 86.61) (xy 112.22 86.05) (xy 112.83 86.05)
			)
		)
	)
	(zone
		(net 0)
		(net_name "")
		(layer "In1.Cu")
		(hatch edge 0.508)
		(connect_pads
			(clearance 0)
		)
		(min_thickness 0.254)
		(filled_areas_thickness no)
		(keepout
			(tracks not_allowed)
			(vias not_allowed)
			(pads not_allowed)
			(copperpour not_allowed)
			(footprints allowed)
		)
		(fill
			(thermal_gap 0.508)
			(thermal_bridge_width 0.508)
		)
		(polygon
			(pts
				(xy 99.35 73.05) (xy 98.35 73.05) (xy 98.35 71.05) (xy 99.35 71.05)
			)
		)
	)
	(zone
		(net 0)
		(net_name "")
		(layer "In1.Cu")
		(hatch edge 0.508)
		(connect_pads
			(clearance 0)
		)
		(min_thickness 0.254)
		(filled_areas_thickness no)
		(keepout
			(tracks not_allowed)
			(vias not_allowed)
			(pads not_allowed)
			(copperpour not_allowed)
			(footprints allowed)
		)
		(fill
			(thermal_gap 0.508)
			(thermal_bridge_width 0.508)
		)
		(polygon
			(pts
				(xy 114.8 116.9) (xy 113.85 116.9) (xy 113.85 115.45) (xy 114.8 115.45)
			)
		)
	)
	(zone
		(net 0)
		(net_name "")
		(layer "In1.Cu")
		(hatch edge 0.508)
		(connect_pads
			(clearance 0)
		)
		(min_thickness 0.254)
		(filled_areas_thickness no)
		(keepout
			(tracks not_allowed)
			(vias not_allowed)
			(pads not_allowed)
			(copperpour not_allowed)
			(footprints allowed)
		)
		(fill
			(thermal_gap 0.508)
			(thermal_bridge_width 0.508)
		)
		(polygon
			(pts
				(xy 146.6 90.7) (xy 145.4 90.7) (xy 145.4 89.2) (xy 146.6 89.2)
			)
		)
	)
	(zone
		(net 1)
		(net_name "GND")
		(layer "In1.Cu")
		(hatch edge 0.508)
		(priority 105)
		(connect_pads yes
			(clearance 0.2)
		)
		(min_thickness 0.254)
		(filled_areas_thickness no)
		(fill yes
			(thermal_gap 0.508)
			(thermal_bridge_width 5)
		)
		(polygon
			(pts
				(xy 101.37 88.15) (xy 100.76 88.15) (xy 100.76 87.59) (xy 101.37 87.59)
			)
		)
	)
	(zone
		(net 0)
		(net_name "")
		(layer "In1.Cu")
		(hatch edge 0.508)
		(connect_pads
			(clearance 0)
		)
		(min_thickness 0.254)
		(filled_areas_thickness no)
		(keepout
			(tracks not_allowed)
			(vias not_allowed)
			(pads not_allowed)
			(copperpour not_allowed)
			(footprints allowed)
		)
		(fill
			(thermal_gap 0.508)
			(thermal_bridge_width 0.508)
		)
		(polygon
			(pts
				(xy 73.2 118.85) (xy 72.25 118.85) (xy 72.25 117.4) (xy 73.2 117.4)
			)
		)
	)
	(zone
		(net 0)
		(net_name "")
		(layer "In1.Cu")
		(hatch edge 0.508)
		(connect_pads
			(clearance 0)
		)
		(min_thickness 0.254)
		(filled_areas_thickness no)
		(keepout
			(tracks not_allowed)
			(vias not_allowed)
			(pads not_allowed)
			(copperpour not_allowed)
			(footprints allowed)
		)
		(fill
			(thermal_gap 0.508)
			(thermal_bridge_width 0.508)
		)
		(polygon
			(pts
				(xy 71.7 116.25) (xy 70.75 116.25) (xy 70.75 114.8) (xy 71.7 114.8)
			)
		)
	)
	(zone
		(net 0)
		(net_name "")
		(layer "In1.Cu")
		(hatch edge 0.508)
		(connect_pads
			(clearance 0)
		)
		(min_thickness 0.254)
		(filled_areas_thickness no)
		(keepout
			(tracks not_allowed)
			(vias not_allowed)
			(pads not_allowed)
			(copperpour not_allowed)
			(footprints allowed)
		)
		(fill
			(thermal_gap 0.508)
			(thermal_bridge_width 0.508)
		)
		(polygon
			(pts
				(xy 106 107.4) (xy 104.3 107.4) (xy 104.3 105.7) (xy 106 105.7)
			)
		)
	)
	(zone
		(net 0)
		(net_name "")
		(layer "In1.Cu")
		(hatch edge 0.508)
		(connect_pads
			(clearance 0)
		)
		(min_thickness 0.254)
		(filled_areas_thickness no)
		(keepout
			(tracks allowed)
			(vias allowed)
			(pads allowed)
			(copperpour not_allowed)
			(footprints allowed)
		)
		(fill
			(thermal_gap 0.508)
			(thermal_bridge_width 0.508)
		)
		(polygon
			(pts
				(xy 91.2 103.7) (xy 90.1 104.8) (xy 89.5 104.2) (xy 90.6 103.1)
			)
		)
	)
	(zone
		(net 0)
		(net_name "")
		(layer "In1.Cu")
		(hatch edge 0.508)
		(connect_pads
			(clearance 0)
		)
		(min_thickness 0.254)
		(filled_areas_thickness no)
		(keepout
			(tracks not_allowed)
			(vias not_allowed)
			(pads not_allowed)
			(copperpour not_allowed)
			(footprints allowed)
		)
		(fill
			(thermal_gap 0.508)
			(thermal_bridge_width 0.508)
		)
		(polygon
			(pts
				(xy 110.85 73) (xy 109.85 73) (xy 109.85 71) (xy 110.85 71)
			)
		)
	)
	(zone
		(net 0)
		(net_name "")
		(layer "In1.Cu")
		(hatch edge 0.508)
		(connect_pads
			(clearance 0)
		)
		(min_thickness 0.254)
		(filled_areas_thickness no)
		(keepout
			(tracks not_allowed)
			(vias not_allowed)
			(pads not_allowed)
			(copperpour not_allowed)
			(footprints allowed)
		)
		(fill
			(thermal_gap 0.508)
			(thermal_bridge_width 0.508)
		)
		(polygon
			(pts
				(xy 113.85 73) (xy 112.85 73) (xy 112.85 71) (xy 113.85 71)
			)
		)
	)
	(zone
		(net 0)
		(net_name "")
		(layer "In1.Cu")
		(hatch edge 0.508)
		(connect_pads
			(clearance 0)
		)
		(min_thickness 0.254)
		(filled_areas_thickness no)
		(keepout
			(tracks not_allowed)
			(vias not_allowed)
			(pads not_allowed)
			(copperpour not_allowed)
			(footprints allowed)
		)
		(fill
			(thermal_gap 0.508)
			(thermal_bridge_width 0.508)
		)
		(polygon
			(pts
				(xy 146.6 88.3) (xy 145.4 88.3) (xy 145.4 86.8) (xy 146.6 86.8)
			)
		)
	)
	(zone
		(net 0)
		(net_name "")
		(layer "In1.Cu")
		(hatch edge 0.508)
		(connect_pads
			(clearance 0)
		)
		(min_thickness 0.254)
		(filled_areas_thickness no)
		(keepout
			(tracks not_allowed)
			(vias not_allowed)
			(pads not_allowed)
			(copperpour not_allowed)
			(footprints allowed)
		)
		(fill
			(thermal_gap 0.508)
			(thermal_bridge_width 0.508)
		)
		(polygon
			(pts
				(xy 147.75 85.45) (xy 147.15 85.45) (xy 147.15 84.45) (xy 147.75 84.45)
			)
		)
	)
	(zone
		(net 0)
		(net_name "")
		(layer "In1.Cu")
		(hatch edge 0.508)
		(connect_pads
			(clearance 0)
		)
		(min_thickness 0.254)
		(filled_areas_thickness no)
		(keepout
			(tracks not_allowed)
			(vias not_allowed)
			(pads not_allowed)
			(copperpour not_allowed)
			(footprints allowed)
		)
		(fill
			(thermal_gap 0.508)
			(thermal_bridge_width 0.508)
		)
		(polygon
			(pts
				(xy 91.6 81.2) (xy 90.6 81.2) (xy 90.6 79.2) (xy 91.6 79.2)
			)
		)
	)
	(zone
		(net 0)
		(net_name "")
		(layer "In1.Cu")
		(hatch edge 0.508)
		(connect_pads
			(clearance 0)
		)
		(min_thickness 0.254)
		(filled_areas_thickness no)
		(keepout
			(tracks not_allowed)
			(vias not_allowed)
			(pads not_allowed)
			(copperpour not_allowed)
			(footprints allowed)
		)
		(fill
			(thermal_gap 0.508)
			(thermal_bridge_width 0.508)
		)
		(polygon
			(pts
				(xy 86.1 81.1) (xy 85.1 81.1) (xy 85.1 79.3) (xy 86.1 79.3)
			)
		)
	)
	(zone
		(net 115)
		(net_name "VCC")
		(layer "In1.Cu")
		(hatch edge 0.508)
		(priority 1)
		(connect_pads yes
			(clearance 0.2)
		)
		(min_thickness 0.254)
		(filled_areas_thickness no)
		(fill yes
			(thermal_gap 0.508)
			(thermal_bridge_width 5)
		)
		(polygon
			(pts
				(xy 55.1 76.8) (xy 63 84.25) (xy 74.319958 84.25) (xy 74.319132 88.75) (xy 67.55 88.75) (xy 65.1 91.25)
				(xy 65.1 94.421888) (xy 60.29 94.42) (xy 60.300339 90.222339) (xy 56.712576 86.75) (xy 52.3 86.75)
				(xy 52.3 81.1) (xy 52.13 80.93) (xy 50.7 80.93) (xy 50.7 76.8)
			)
		)
	)
	(zone
		(net 0)
		(net_name "")
		(layer "In1.Cu")
		(hatch edge 0.508)
		(connect_pads
			(clearance 0)
		)
		(min_thickness 0.254)
		(filled_areas_thickness no)
		(keepout
			(tracks not_allowed)
			(vias not_allowed)
			(pads not_allowed)
			(copperpour not_allowed)
			(footprints allowed)
		)
		(fill
			(thermal_gap 0.508)
			(thermal_bridge_width 0.508)
		)
		(polygon
			(pts
				(xy 125.3 96.6) (xy 123.6 96.6) (xy 123.6 95.7) (xy 125.3 95.7)
			)
		)
	)
	(zone
		(net 1)
		(net_name "GND")
		(layer "In1.Cu")
		(hatch edge 0.508)
		(priority 5)
		(connect_pads yes
			(clearance 0.125)
		)
		(min_thickness 0.254)
		(filled_areas_thickness no)
		(fill yes
			(thermal_gap 0.508)
			(thermal_bridge_width 0.508)
		)
		(polygon
			(pts
				(xy 74.984506 120.1) (xy 74.966655 120.010258) (xy 74.915821 119.934179) (xy 74.839742 119.883345)
				(xy 74.75 119.865494) (xy 74.660258 119.883345) (xy 74.584179 119.934179) (xy 74.533345 120.010258)
				(xy 74.515494 120.1) (xy 74.533345 120.189742) (xy 74.584179 120.265821) (xy 74.660258 120.316655)
				(xy 74.75 120.334506) (xy 74.839742 120.316655) (xy 74.915821 120.265821) (xy 74.966655 120.189742)
			)
		)
	)
	(zone
		(net 0)
		(net_name "")
		(layer "In1.Cu")
		(hatch edge 0.508)
		(connect_pads
			(clearance 0)
		)
		(min_thickness 0.254)
		(filled_areas_thickness no)
		(keepout
			(tracks not_allowed)
			(vias not_allowed)
			(pads not_allowed)
			(copperpour not_allowed)
			(footprints allowed)
		)
		(fill
			(thermal_gap 0.508)
			(thermal_bridge_width 0.508)
		)
		(polygon
			(pts
				(xy 93.1 81.2) (xy 92.1 81.2) (xy 92.1 79.2) (xy 93.1 79.2)
			)
		)
	)
	(zone
		(net 0)
		(net_name "")
		(layer "In1.Cu")
		(hatch edge 0.508)
		(connect_pads
			(clearance 0)
		)
		(min_thickness 0.254)
		(filled_areas_thickness no)
		(keepout
			(tracks not_allowed)
			(vias not_allowed)
			(pads not_allowed)
			(copperpour not_allowed)
			(footprints allowed)
		)
		(fill
			(thermal_gap 0.508)
			(thermal_bridge_width 0.508)
		)
		(polygon
			(pts
				(xy 93.85 73) (xy 92.85 73) (xy 92.85 71) (xy 93.85 71)
			)
		)
	)
	(zone
		(net 0)
		(net_name "")
		(layer "In1.Cu")
		(hatch edge 0.508)
		(connect_pads
			(clearance 0)
		)
		(min_thickness 0.254)
		(filled_areas_thickness no)
		(keepout
			(tracks not_allowed)
			(vias not_allowed)
			(pads not_allowed)
			(copperpour not_allowed)
			(footprints allowed)
		)
		(fill
			(thermal_gap 0.508)
			(thermal_bridge_width 0.508)
		)
		(polygon
			(pts
				(xy 75.25 118.85) (xy 74.3 118.85) (xy 74.3 117.4) (xy 75.25 117.4)
			)
		)
	)
	(zone
		(net 0)
		(net_name "")
		(layer "In1.Cu")
		(hatch edge 0.508)
		(connect_pads
			(clearance 0)
		)
		(min_thickness 0.254)
		(filled_areas_thickness no)
		(keepout
			(tracks not_allowed)
			(vias not_allowed)
			(pads not_allowed)
			(copperpour not_allowed)
			(footprints allowed)
		)
		(fill
			(thermal_gap 0.508)
			(thermal_bridge_width 0.508)
		)
		(polygon
			(pts
				(xy 81.35 73.05) (xy 80.35 73.05) (xy 80.35 71.05) (xy 81.35 71.05)
			)
		)
	)
	(zone
		(net 0)
		(net_name "")
		(layer "In1.Cu")
		(hatch edge 0.508)
		(connect_pads
			(clearance 0)
		)
		(min_thickness 0.254)
		(filled_areas_thickness no)
		(keepout
			(tracks not_allowed)
			(vias not_allowed)
			(pads not_allowed)
			(copperpour not_allowed)
			(footprints allowed)
		)
		(fill
			(thermal_gap 0.508)
			(thermal_bridge_width 0.508)
		)
		(polygon
			(pts
				(xy 84.6 81.1) (xy 83.6 81.1) (xy 83.6 79.3) (xy 84.6 79.3)
			)
		)
	)
	(zone
		(net 1)
		(net_name "GND")
		(layer "In1.Cu")
		(hatch edge 0.508)
		(priority 105)
		(connect_pads yes
			(clearance 0.2)
		)
		(min_thickness 0.254)
		(filled_areas_thickness no)
		(fill yes
			(thermal_gap 0.508)
			(thermal_bridge_width 5)
		)
		(polygon
			(pts
				(xy 132.81 108.97) (xy 132.2 108.97) (xy 132.2 108.41) (xy 132.81 108.41)
			)
		)
	)
	(zone
		(net 0)
		(net_name "")
		(layer "In1.Cu")
		(hatch edge 0.508)
		(connect_pads
			(clearance 0)
		)
		(min_thickness 0.254)
		(filled_areas_thickness no)
		(keepout
			(tracks not_allowed)
			(vias not_allowed)
			(pads not_allowed)
			(copperpour not_allowed)
			(footprints allowed)
		)
		(fill
			(thermal_gap 0.508)
			(thermal_bridge_width 0.508)
		)
		(polygon
			(pts
				(xy 122.85 73) (xy 121.85 73) (xy 121.85 71) (xy 122.85 71)
			)
		)
	)
	(zone
		(net 0)
		(net_name "")
		(layer "In1.Cu")
		(hatch edge 0.508)
		(connect_pads
			(clearance 0)
		)
		(min_thickness 0.254)
		(filled_areas_thickness no)
		(keepout
			(tracks not_allowed)
			(vias not_allowed)
			(pads not_allowed)
			(copperpour not_allowed)
			(footprints allowed)
		)
		(fill
			(thermal_gap 0.508)
			(thermal_bridge_width 0.508)
		)
		(polygon
			(pts
				(xy 111.75 116.9) (xy 110.8 116.9) (xy 110.8 115.45) (xy 111.75 115.45)
			)
		)
	)
	(zone
		(net 0)
		(net_name "")
		(layer "In1.Cu")
		(hatch edge 0.508)
		(connect_pads
			(clearance 0)
		)
		(min_thickness 0.254)
		(filled_areas_thickness no)
		(keepout
			(tracks not_allowed)
			(vias not_allowed)
			(pads not_allowed)
			(copperpour not_allowed)
			(footprints allowed)
		)
		(fill
			(thermal_gap 0.508)
			(thermal_bridge_width 0.508)
		)
		(polygon
			(pts
				(xy 110.6 81.2) (xy 109.6 81.2) (xy 109.6 79.2) (xy 110.6 79.2)
			)
		)
	)
	(zone
		(net 0)
		(net_name "")
		(layer "In1.Cu")
		(hatch edge 0.508)
		(connect_pads
			(clearance 0)
		)
		(min_thickness 0.254)
		(filled_areas_thickness no)
		(keepout
			(tracks not_allowed)
			(vias not_allowed)
			(pads not_allowed)
			(copperpour not_allowed)
			(footprints allowed)
		)
		(fill
			(thermal_gap 0.508)
			(thermal_bridge_width 0.508)
		)
		(polygon
			(pts
				(xy 125.3 95.1) (xy 123.6 95.1) (xy 123.6 94.2) (xy 125.3 94.2)
			)
		)
	)
	(zone
		(net 0)
		(net_name "")
		(layer "In1.Cu")
		(hatch edge 0.508)
		(connect_pads
			(clearance 0)
		)
		(min_thickness 0.254)
		(filled_areas_thickness no)
		(keepout
			(tracks allowed)
			(vias allowed)
			(pads allowed)
			(copperpour not_allowed)
			(footprints allowed)
		)
		(fill
			(thermal_gap 0.508)
			(thermal_bridge_width 0.508)
		)
		(polygon
			(pts
				(xy 94.1 104.5) (xy 93 105.6) (xy 92.4 105) (xy 93.5 103.9)
			)
		)
	)
	(zone
		(net 0)
		(net_name "")
		(layer "In1.Cu")
		(hatch edge 0.508)
		(connect_pads
			(clearance 0)
		)
		(min_thickness 0.254)
		(filled_areas_thickness no)
		(keepout
			(tracks not_allowed)
			(vias not_allowed)
			(pads not_allowed)
			(copperpour not_allowed)
			(footprints allowed)
		)
		(fill
			(thermal_gap 0.508)
			(thermal_bridge_width 0.508)
		)
		(polygon
			(pts
				(xy 115.35 73.05) (xy 114.35 73.05) (xy 114.35 71.05) (xy 115.35 71.05)
			)
		)
	)
	(zone
		(net 0)
		(net_name "")
		(layer "In1.Cu")
		(hatch edge 0.508)
		(connect_pads
			(clearance 0)
		)
		(min_thickness 0.254)
		(filled_areas_thickness no)
		(keepout
			(tracks not_allowed)
			(vias not_allowed)
			(pads not_allowed)
			(copperpour not_allowed)
			(footprints allowed)
		)
		(fill
			(thermal_gap 0.508)
			(thermal_bridge_width 0.508)
		)
		(polygon
			(pts
				(xy 113.6 81.2) (xy 112.6 81.2) (xy 112.6 79.31) (xy 113.6 79.31)
			)
		)
	)
	(zone
		(net 0)
		(net_name "")
		(layer "In1.Cu")
		(hatch edge 0.508)
		(connect_pads
			(clearance 0)
		)
		(min_thickness 0.254)
		(filled_areas_thickness no)
		(keepout
			(tracks not_allowed)
			(vias not_allowed)
			(pads not_allowed)
			(copperpour not_allowed)
			(footprints allowed)
		)
		(fill
			(thermal_gap 0.508)
			(thermal_bridge_width 0.508)
		)
		(polygon
			(pts
				(xy 115.1 81.2) (xy 114.1 81.2) (xy 114.1 79.2) (xy 115.1 79.2)
			)
		)
	)
	(zone
		(net 1)
		(net_name "GND")
		(layer "In1.Cu")
		(hatch edge 0.508)
		(priority 105)
		(connect_pads yes
			(clearance 0.2)
		)
		(min_thickness 0.254)
		(filled_areas_thickness no)
		(fill yes
			(thermal_gap 0.508)
			(thermal_bridge_width 5)
		)
		(polygon
			(pts
				(xy 44.5 128.38) (xy 43.58 128.38) (xy 43.58 107.73) (xy 44.5 107.73)
			)
		)
	)
	(zone
		(net 1)
		(net_name "GND")
		(layer "In1.Cu")
		(hatch edge 0.508)
		(priority 105)
		(connect_pads yes
			(clearance 0.2)
		)
		(min_thickness 0.254)
		(filled_areas_thickness no)
		(fill yes
			(thermal_gap 0.508)
			(thermal_bridge_width 5)
		)
		(polygon
			(pts
				(xy 116.03 89.79) (xy 115.42 89.79) (xy 115.42 89.23) (xy 116.03 89.23)
			)
		)
	)
	(zone
		(net 0)
		(net_name "")
		(layer "In1.Cu")
		(hatch edge 0.508)
		(connect_pads
			(clearance 0)
		)
		(min_thickness 0.254)
		(filled_areas_thickness no)
		(keepout
			(tracks not_allowed)
			(vias not_allowed)
			(pads not_allowed)
			(copperpour not_allowed)
			(footprints allowed)
		)
		(fill
			(thermal_gap 0.508)
			(thermal_bridge_width 0.508)
		)
		(polygon
			(pts
				(xy 84.35 73.05) (xy 83.35 73.05) (xy 83.35 71.05) (xy 84.35 71.05)
			)
		)
	)
	(zone
		(net 0)
		(net_name "")
		(layers "In1.Cu" "In2.Cu" "In3.Cu" "In4.Cu" "In5.Cu" "In6.Cu")
		(hatch edge 0.508)
		(connect_pads
			(clearance 0)
		)
		(min_thickness 0.254)
		(filled_areas_thickness no)
		(keepout
			(tracks allowed)
			(vias allowed)
			(pads allowed)
			(copperpour not_allowed)
			(footprints allowed)
		)
		(fill
			(thermal_gap 0.508)
			(thermal_bridge_width 0.508)
		)
		(polygon
			(pts
				(xy 36.114743 99.45) (xy 36.095917 99.173854) (xy 36.039788 98.902817) (xy 35.947395 98.641906)
				(xy 35.820446 98.395948) (xy 35.661292 98.169495) (xy 35.472877 97.966736) (xy 35.258688 97.791424)
				(xy 35.022688 97.646803) (xy 34.769245 97.535549) (xy 34.503047 97.459721) (xy 34.229021 97.420721)
				(xy 33.952237 97.419272) (xy 33.677818 97.4554) (xy 33.410841 97.528437) (xy 33.156246 97.637031)
				(xy 32.918745 97.779172) (xy 32.702731 97.952232) (xy 32.512204 98.153006) (xy 32.350687 98.37778)
				(xy 32.22117 98.622395) (xy 32.126049 98.882325) (xy 32.067085 99.152759) (xy 32.045369 99.428693)
				(xy 32.061302 99.705021) (xy 32.114589 99.97663) (xy 32.204245 100.238495) (xy 32.328611 100.485768)
				(xy 32.485385 100.713876) (xy 32.671667 100.918597) (xy 32.884008 101.096142) (xy 33.118481 101.243226)
				(xy 33.370745 101.357128) (xy 33.636135 101.43574) (xy 33.909737 101.477607) (xy 34.18649 101.481954)
				(xy 34.461273 101.448702) (xy 34.729 101.378465) (xy 34.984718 101.272543) (xy 35.223695 101.132896)
				(xy 35.441509 100.962109) (xy 35.634129 100.763341) (xy 35.79799 100.54027) (xy 35.930062 100.297024)
				(xy 36.027899 100.038105) (xy 36.089692 99.768304) (xy 36.114297 99.492612)
			)
		)
	)
	(zone
		(net 1)
		(net_name "GND")
		(layers "In1.Cu" "In2.Cu" "In4.Cu")
		(hatch edge 0.508)
		(priority 5)
		(connect_pads yes
			(clearance 0.125)
		)
		(min_thickness 0.254)
		(filled_areas_thickness no)
		(fill yes
			(thermal_gap 0.508)
			(thermal_bridge_width 0.508)
		)
		(polygon
			(pts
				(xy 74.984506 120.1) (xy 74.966655 120.010258) (xy 74.915821 119.934179) (xy 74.839742 119.883345)
				(xy 74.75 119.865494) (xy 74.660258 119.883345) (xy 74.584179 119.934179) (xy 74.533345 120.010258)
				(xy 74.515494 120.1) (xy 74.533345 120.189742) (xy 74.584179 120.265821) (xy 74.660258 120.316655)
				(xy 74.75 120.334506) (xy 74.839742 120.316655) (xy 74.915821 120.265821) (xy 74.966655 120.189742)
			)
		)
	)
	(zone
		(net 99)
		(net_name "+5V")
		(layer "In2.Cu")
		(hatch edge 0.508)
		(priority 4)
		(connect_pads yes
			(clearance 0.2)
		)
		(min_thickness 0.254)
		(filled_areas_thickness no)
		(fill yes
			(thermal_gap 0.508)
			(thermal_bridge_width 5)
		)
		(polygon
			(pts
				(xy 62.57 91.19) (xy 62.57 107.93) (xy 64.1 109.5) (xy 68.25 109.5) (xy 68.25 116.25) (xy 114 116.25)
				(xy 117.54 112.7) (xy 137.5 112.7) (xy 137.5 119) (xy 96.6 119) (xy 95.4 120.2) (xy 84.5 120.2)
				(xy 83.3 119) (xy 57.75 119) (xy 57.748547 98.19) (xy 57.31 97.81) (xy 57.32 91.65) (xy 57.77 91.19)
			)
		)
	)
	(zone
		(net 1)
		(net_name "GND")
		(layer "In2.Cu")
		(hatch edge 0.508)
		(priority 5)
		(connect_pads yes
			(clearance 0.125)
		)
		(min_thickness 0.254)
		(filled_areas_thickness no)
		(fill yes
			(thermal_gap 0.508)
			(thermal_bridge_width 0.508)
		)
		(polygon
			(pts
				(xy 78.114506 109.52) (xy 78.096655 109.430258) (xy 78.045821 109.354179) (xy 77.969742 109.303345)
				(xy 77.88 109.285494) (xy 77.790258 109.303345) (xy 77.714179 109.354179) (xy 77.663345 109.430258)
				(xy 77.645494 109.52) (xy 77.663345 109.609742) (xy 77.714179 109.685821) (xy 77.790258 109.736655)
				(xy 77.88 109.754506) (xy 77.969742 109.736655) (xy 78.045821 109.685821) (xy 78.096655 109.609742)
			)
		)
	)
	(zone
		(net 87)
		(net_name "+3V3")
		(layer "In2.Cu")
		(hatch edge 0.508)
		(priority 6)
		(connect_pads yes
			(clearance 0.125)
		)
		(min_thickness 0.254)
		(filled_areas_thickness no)
		(fill yes
			(thermal_gap 0.508)
			(thermal_bridge_width 0.508)
		)
		(polygon
			(pts
				(xy 78.644506 109.25) (xy 78.626655 109.160258) (xy 78.575821 109.084179) (xy 78.499742 109.033345)
				(xy 78.41 109.015494) (xy 78.320258 109.033345) (xy 78.244179 109.084179) (xy 78.193345 109.160258)
				(xy 78.175494 109.25) (xy 78.193345 109.339742) (xy 78.244179 109.415821) (xy 78.320258 109.466655)
				(xy 78.41 109.484506) (xy 78.499742 109.466655) (xy 78.575821 109.415821) (xy 78.626655 109.339742)
			)
		)
	)
	(zone
		(net 115)
		(net_name "VCC")
		(layer "In2.Cu")
		(hatch edge 0.508)
		(priority 1)
		(connect_pads yes
			(clearance 0.2)
		)
		(min_thickness 0.254)
		(filled_areas_thickness no)
		(fill yes
			(thermal_gap 0.508)
			(thermal_bridge_width 5)
		)
		(polygon
			(pts
				(xy 54.2 78.6) (xy 55.05 79.4) (xy 57.5 79.4) (xy 57.501256 89.871802) (xy 57.501857 95.672435)
				(xy 57.5 119.3) (xy 137.49955 119.25294) (xy 137.499975 117.549663) (xy 141.499975 117.55) (xy 141.5 124.6)
				(xy 108.63 124.6) (xy 107.2 126) (xy 82.1 126) (xy 80.7 124.6) (xy 51.75 124.6) (xy 51.75 97.675)
				(xy 49.277113 95.2) (xy 49.274821 83.129491) (xy 49.275 82.225) (xy 48.725 81.675) (xy 48.725 80.25)
				(xy 48.725 77) (xy 53.9 77) (xy 54.2 77.3)
			)
		)
	)
	(zone
		(net 87)
		(net_name "+3V3")
		(layer "In2.Cu")
		(hatch edge 0.508)
		(priority 3)
		(connect_pads yes
			(clearance 0.2)
		)
		(min_thickness 0.254)
		(filled_areas_thickness no)
		(fill yes
			(thermal_gap 0.508)
			(thermal_bridge_width 5)
		)
		(polygon
			(pts
				(xy 88 109.1) (xy 84.5 109.1) (xy 84.5 111.2) (xy 97.5 111.2) (xy 97.5 116) (xy 68.5 116) (xy 68.5 109.25)
				(xy 64.7 109.25) (xy 62.75 107.3) (xy 62.75 98.35) (xy 66.9 94.71) (xy 66.9 89.01) (xy 69.5 89.0113)
				(xy 69.5 92.854732) (xy 80 106.5) (xy 88 106.5)
			)
		)
	)
	(zone
		(net 1)
		(net_name "GND")
		(layer "In2.Cu")
		(hatch edge 0.508)
		(priority 4)
		(connect_pads yes
			(clearance 0.2)
		)
		(min_thickness 0.254)
		(filled_areas_thickness no)
		(fill yes
			(thermal_gap 0.508)
			(thermal_bridge_width 5)
		)
		(polygon
			(pts
				(xy 78 110.5) (xy 79 110.5) (xy 79 113.982531) (xy 75.75 113.982531) (xy 75.75 112.8) (xy 75.05 112.8)
				(xy 75.02 111.73) (xy 75.75 111.6) (xy 75.75 107.5) (xy 78 107.5)
			)
		)
	)
	(zone
		(net 1)
		(net_name "GND")
		(layer "In2.Cu")
		(hatch edge 0.508)
		(priority 5)
		(connect_pads yes
			(clearance 0.125)
		)
		(min_thickness 0.254)
		(filled_areas_thickness no)
		(fill yes
			(thermal_gap 0.508)
			(thermal_bridge_width 0.508)
		)
		(polygon
			(pts
				(xy 80.412425 106.263) (xy 80.391141 106.142293) (xy 80.329856 106.036144) (xy 80.235963 105.957358)
				(xy 80.120785 105.915437) (xy 79.998215 105.915437) (xy 79.883038 105.957358) (xy 79.789144 106.036144)
				(xy 79.727859 106.142293) (xy 79.706575 106.263) (xy 79.727859 106.383707) (xy 79.789144 106.489856)
				(xy 79.883037 106.568642) (xy 79.998215 106.610563) (xy 80.120785 106.610563) (xy 80.235963 106.568642)
				(xy 80.329856 106.489856) (xy 80.391141 106.383707)
			)
		)
	)
	(zone
		(net 1)
		(net_name "GND")
		(layers "In2.Cu" "In4.Cu" "In6.Cu")
		(hatch edge 0.508)
		(connect_pads yes
			(clearance 0.2)
		)
		(min_thickness 0.254)
		(filled_areas_thickness no)
		(fill yes
			(thermal_gap 0.508)
			(thermal_bridge_width 5)
		)
		(polygon
			(pts
				(xy 153.29 133.11) (xy 24.74 133.11) (xy 24.74 63.76) (xy 153.29 63.76)
			)
		)
	)
	(zone
		(net 1)
		(net_name "GND")
		(layer "In4.Cu")
		(hatch edge 0.508)
		(priority 5)
		(connect_pads yes
			(clearance 0.125)
		)
		(min_thickness 0.254)
		(filled_areas_thickness no)
		(fill yes
			(thermal_gap 0.508)
			(thermal_bridge_width 0.508)
		)
		(polygon
			(pts
				(xy 77.984506 117.1) (xy 77.966655 117.010258) (xy 77.915821 116.934179) (xy 77.839742 116.883345)
				(xy 77.75 116.865494) (xy 77.660258 116.883345) (xy 77.584179 116.934179) (xy 77.533345 117.010258)
				(xy 77.515494 117.1) (xy 77.533345 117.189742) (xy 77.584179 117.265821) (xy 77.660258 117.316655)
				(xy 77.75 117.334506) (xy 77.839742 117.316655) (xy 77.915821 117.265821) (xy 77.966655 117.189742)
			)
		)
	)
	(zone
		(net 99)
		(net_name "+5V")
		(layer "In4.Cu")
		(hatch edge 0.508)
		(priority 1)
		(connect_pads yes
			(clearance 0.2)
		)
		(min_thickness 0.254)
		(filled_areas_thickness no)
		(fill yes
			(thermal_gap 0.508)
			(thermal_bridge_width 5)
		)
		(polygon
			(pts
				(xy 137.25 117.2) (xy 137.25 128.25) (xy 68.55 128.75) (xy 68.55 117.1)
			)
		)
	)
	(zone
		(net 787)
		(net_name "+5V_SoM")
		(layer "In5.Cu")
		(hatch edge 0.5)
		(priority 28)
		(connect_pads
			(clearance 0)
		)
		(min_thickness 0.25)
		(filled_areas_thickness no)
		(fill yes
			(thermal_gap 0.5)
			(thermal_bridge_width 0.5)
		)
		(polygon
			(pts
				(xy 58.76 87.93) (xy 52.45 94.24) (xy 52.45 96.55) (xy 53.3 97.4) (xy 57.44 97.4) (xy 58.7 96.14)
				(xy 63.25 96.14) (xy 63.91 95.48) (xy 63.91 92.91) (xy 61.5 90.5) (xy 61.5 87.93)
			)
		)
	)
	(zone
		(net 0)
		(net_name "")
		(layers "In5.Cu" "In6.Cu")
		(hatch edge 0.508)
		(connect_pads
			(clearance 0)
		)
		(min_thickness 0.254)
		(filled_areas_thickness no)
		(keepout
			(tracks not_allowed)
			(vias not_allowed)
			(pads not_allowed)
			(copperpour not_allowed)
			(footprints allowed)
		)
		(fill
			(thermal_gap 0.508)
			(thermal_bridge_width 0.508)
		)
		(polygon
			(pts
				(xy 125.1 89.2) (xy 123.5 89.2) (xy 123.5 88.3) (xy 125.1 88.3)
			)
		)
	)
	(zone
		(net 0)
		(net_name "")
		(layers "In5.Cu" "In6.Cu")
		(hatch edge 0.508)
		(connect_pads
			(clearance 0)
		)
		(min_thickness 0.254)
		(filled_areas_thickness no)
		(keepout
			(tracks not_allowed)
			(vias not_allowed)
			(pads not_allowed)
			(copperpour not_allowed)
			(footprints allowed)
		)
		(fill
			(thermal_gap 0.508)
			(thermal_bridge_width 0.508)
		)
		(polygon
			(pts
				(xy 127.6 94.05) (xy 125.98 94.05) (xy 125.98 92.45) (xy 127.6 92.45)
			)
		)
	)
	(zone
		(net 0)
		(net_name "")
		(layers "In5.Cu" "In6.Cu")
		(hatch edge 0.508)
		(connect_pads
			(clearance 0)
		)
		(min_thickness 0.254)
		(filled_areas_thickness no)
		(keepout
			(tracks not_allowed)
			(vias not_allowed)
			(pads not_allowed)
			(copperpour not_allowed)
			(footprints allowed)
		)
		(fill
			(thermal_gap 0.508)
			(thermal_bridge_width 0.508)
		)
		(polygon
			(pts
				(xy 125.1 86.2) (xy 123.5 86.2) (xy 123.5 85.3) (xy 125.1 85.3)
			)
		)
	)
	(zone
		(net 0)
		(net_name "")
		(layers "In5.Cu" "In6.Cu")
		(hatch edge 0.508)
		(connect_pads
			(clearance 0)
		)
		(min_thickness 0.254)
		(filled_areas_thickness no)
		(keepout
			(tracks not_allowed)
			(vias not_allowed)
			(pads not_allowed)
			(copperpour not_allowed)
			(footprints allowed)
		)
		(fill
			(thermal_gap 0.508)
			(thermal_bridge_width 0.508)
		)
		(polygon
			(pts
				(xy 125.1 90.7) (xy 123.5 90.7) (xy 123.5 89.8) (xy 125.1 89.8)
			)
		)
	)
	(zone
		(net 0)
		(net_name "")
		(layers "In5.Cu" "In6.Cu")
		(hatch edge 0.508)
		(connect_pads
			(clearance 0)
		)
		(min_thickness 0.254)
		(filled_areas_thickness no)
		(keepout
			(tracks not_allowed)
			(vias not_allowed)
			(pads not_allowed)
			(copperpour not_allowed)
			(footprints allowed)
		)
		(fill
			(thermal_gap 0.508)
			(thermal_bridge_width 0.508)
		)
		(polygon
			(pts
				(xy 125.1 84.7) (xy 123.5 84.7) (xy 123.5 83.8) (xy 125.1 83.8)
			)
		)
	)
	(zone
		(net 0)
		(net_name "")
		(layers "In5.Cu" "In6.Cu")
		(hatch edge 0.508)
		(connect_pads
			(clearance 0)
		)
		(min_thickness 0.254)
		(filled_areas_thickness no)
		(keepout
			(tracks not_allowed)
			(vias not_allowed)
			(pads not_allowed)
			(copperpour not_allowed)
			(footprints allowed)
		)
		(fill
			(thermal_gap 0.508)
			(thermal_bridge_width 0.508)
		)
		(polygon
			(pts
				(xy 127.6 88.05) (xy 125.98 88.05) (xy 125.98 86.45) (xy 127.6 86.45)
			)
		)
	)
	(zone
		(net 0)
		(net_name "")
		(layers "In5.Cu" "In6.Cu")
		(hatch edge 0.508)
		(connect_pads
			(clearance 0)
		)
		(min_thickness 0.254)
		(filled_areas_thickness no)
		(keepout
			(tracks not_allowed)
			(vias not_allowed)
			(pads not_allowed)
			(copperpour not_allowed)
			(footprints allowed)
		)
		(fill
			(thermal_gap 0.508)
			(thermal_bridge_width 0.508)
		)
		(polygon
			(pts
				(xy 127.55 85.05) (xy 125.85 85.05) (xy 125.85 83.45) (xy 127.55 83.45)
			)
		)
	)
	(zone
		(net 0)
		(net_name "")
		(layers "In5.Cu" "In6.Cu")
		(hatch edge 0.508)
		(connect_pads
			(clearance 0)
		)
		(min_thickness 0.254)
		(filled_areas_thickness no)
		(keepout
			(tracks not_allowed)
			(vias not_allowed)
			(pads not_allowed)
			(copperpour not_allowed)
			(footprints allowed)
		)
		(fill
			(thermal_gap 0.508)
			(thermal_bridge_width 0.508)
		)
		(polygon
			(pts
				(xy 125.1 87.7) (xy 123.5 87.7) (xy 123.5 86.8) (xy 125.1 86.8)
			)
		)
	)
	(zone
		(net 0)
		(net_name "")
		(layers "In5.Cu" "In6.Cu")
		(hatch edge 0.508)
		(connect_pads
			(clearance 0)
		)
		(min_thickness 0.254)
		(filled_areas_thickness no)
		(keepout
			(tracks not_allowed)
			(vias not_allowed)
			(pads not_allowed)
			(copperpour not_allowed)
			(footprints allowed)
		)
		(fill
			(thermal_gap 0.508)
			(thermal_bridge_width 0.508)
		)
		(polygon
			(pts
				(xy 125.1 93.7) (xy 123.5 93.7) (xy 123.5 92.8) (xy 125.1 92.8)
			)
		)
	)
	(zone
		(net 0)
		(net_name "")
		(layers "In5.Cu" "In6.Cu")
		(hatch edge 0.508)
		(connect_pads
			(clearance 0)
		)
		(min_thickness 0.254)
		(filled_areas_thickness no)
		(keepout
			(tracks not_allowed)
			(vias not_allowed)
			(pads not_allowed)
			(copperpour not_allowed)
			(footprints allowed)
		)
		(fill
			(thermal_gap 0.508)
			(thermal_bridge_width 0.508)
		)
		(polygon
			(pts
				(xy 125.1 92.2) (xy 123.5 92.2) (xy 123.5 91.3) (xy 125.1 91.3)
			)
		)
	)
	(zone
		(net 0)
		(net_name "")
		(layers "In5.Cu" "In6.Cu")
		(hatch edge 0.508)
		(connect_pads
			(clearance 0)
		)
		(min_thickness 0.254)
		(filled_areas_thickness no)
		(keepout
			(tracks not_allowed)
			(vias not_allowed)
			(pads not_allowed)
			(copperpour not_allowed)
			(footprints allowed)
		)
		(fill
			(thermal_gap 0.508)
			(thermal_bridge_width 0.508)
		)
		(polygon
			(pts
				(xy 125.15 83.2) (xy 123.5 83.2) (xy 123.5 82.3) (xy 125.15 82.3)
			)
		)
	)
	(zone
		(net 0)
		(net_name "")
		(layers "In5.Cu" "In6.Cu")
		(hatch edge 0.508)
		(connect_pads
			(clearance 0)
		)
		(min_thickness 0.254)
		(filled_areas_thickness no)
		(keepout
			(tracks not_allowed)
			(vias not_allowed)
			(pads not_allowed)
			(copperpour not_allowed)
			(footprints allowed)
		)
		(fill
			(thermal_gap 0.508)
			(thermal_bridge_width 0.508)
		)
		(polygon
			(pts
				(xy 127.55 91.05) (xy 125.85 91.05) (xy 125.85 89.45) (xy 127.55 89.45)
			)
		)
	)
	(zone
		(net 0)
		(net_name "")
		(layers "In5.Cu" "In6.Cu")
		(hatch edge 0.508)
		(connect_pads
			(clearance 0)
		)
		(min_thickness 0.254)
		(filled_areas_thickness no)
		(keepout
			(tracks not_allowed)
			(vias not_allowed)
			(pads not_allowed)
			(copperpour not_allowed)
			(footprints allowed)
		)
		(fill
			(thermal_gap 0.508)
			(thermal_bridge_width 0.508)
		)
		(polygon
			(pts
				(xy 125.1 95.2) (xy 123.5 95.2) (xy 123.5 94.3) (xy 125.1 94.3)
			)
		)
	)
	(zone
		(net 149)
		(net_name "Net-(D12-Pad2)")
		(layer "B.Cu")
		(hatch edge 0.508)
		(priority 1)
		(connect_pads yes
			(clearance 0.125)
		)
		(min_thickness 0.254)
		(filled_areas_thickness no)
		(fill yes
			(thermal_gap 0.508)
			(thermal_bridge_width 0.508)
			(island_removal_mode 1)
			(island_area_min 0)
		)
		(polygon
			(pts
				(xy 55.32 95.49) (xy 53.42 95.49) (xy 53.42 94.09) (xy 53.82 93.69) (xy 55.32 93.6875)
			)
		)
	)
	(zone
		(net 261)
		(net_name "/USB Debug, DP/USBC0_VBUS")
		(layer "B.Cu")
		(hatch edge 0.508)
		(priority 1)
		(connect_pads yes
			(clearance 0.2)
		)
		(min_thickness 0.254)
		(filled_areas_thickness no)
		(fill yes
			(thermal_gap 0.508)
			(thermal_bridge_width 5)
		)
		(polygon
			(pts
				(xy 69.6 108.2) (xy 72 108.2) (xy 72 112) (xy 74.2 112) (xy 74.2 115.5) (xy 75.3 116.6) (xy 76.4 116.6)
				(xy 76.4 120.6) (xy 73.2 120.6) (xy 73.2 118.7) (xy 72 117.4) (xy 70.8 116.2) (xy 67.7 116.2) (xy 67.7 113.85)
				(xy 70.8 113.85) (xy 70.8 109.4) (xy 68.4 109.4) (xy 68.4 108.2) (xy 67.8 108.2) (xy 67.8 107.4)
				(xy 68.8 107.4)
			)
		)
	)
	(zone
		(net 1)
		(net_name "GND")
		(layer "B.Cu")
		(hatch edge 0.508)
		(connect_pads yes
			(clearance 0.125)
		)
		(min_thickness 0.254)
		(filled_areas_thickness no)
		(fill yes
			(thermal_gap 0.508)
			(thermal_bridge_width 0.508)
		)
		(polygon
			(pts
				(xy 74.53 83.7) (xy 71.14 87.09) (xy 69.14 87.09) (xy 69.14 86.47) (xy 69.76 86.47) (xy 70.1 86.12)
				(xy 70.1 83.5) (xy 72.25 81.35) (xy 74.53 81.35)
			)
		)
	)
	(zone
		(net 1)
		(net_name "GND")
		(layer "B.Cu")
		(hatch edge 0.508)
		(connect_pads yes
			(clearance 0.125)
		)
		(min_thickness 0.254)
		(filled_areas_thickness no)
		(fill yes
			(thermal_gap 0.508)
			(thermal_bridge_width 0.508)
			(island_removal_mode 1)
			(island_area_min 0)
		)
		(polygon
			(pts
				(xy 100.42 75.79) (xy 99.52 75.79) (xy 99.52 74.59) (xy 100.42 74.59)
			)
		)
	)
	(zone
		(net 115)
		(net_name "VCC")
		(layer "B.Cu")
		(hatch edge 0.508)
		(priority 1)
		(connect_pads yes
			(clearance 0.2)
		)
		(min_thickness 0.254)
		(filled_areas_thickness no)
		(fill yes
			(thermal_gap 0.508)
			(thermal_bridge_width 5)
		)
		(polygon
			(pts
				(xy 52.9 76.9) (xy 54 76.9) (xy 54 80.22) (xy 54.73 80.22) (xy 54.73 81.92) (xy 54 81.92) (xy 54 81)
				(xy 50.1 81) (xy 50.1 75.7) (xy 52.9 75.7)
			)
		)
	)
	(zone
		(net 1)
		(net_name "GND")
		(layer "B.Cu")
		(hatch edge 0.508)
		(priority 1)
		(connect_pads yes
			(clearance 0.125)
		)
		(min_thickness 0.254)
		(filled_areas_thickness no)
		(fill yes
			(thermal_gap 0.508)
			(thermal_bridge_width 0.508)
			(island_removal_mode 1)
			(island_area_min 0)
		)
		(polygon
			(pts
				(xy 114.42 78.79) (xy 113.12 78.79) (xy 113.12 77.29) (xy 114.42 77.29)
			)
		)
	)
	(zone
		(net 1)
		(net_name "GND")
		(layer "B.Cu")
		(hatch edge 0.508)
		(connect_pads yes
			(clearance 0.125)
		)
		(min_thickness 0.254)
		(filled_areas_thickness no)
		(fill yes
			(thermal_gap 0.508)
			(thermal_bridge_width 0.508)
			(island_removal_mode 1)
			(island_area_min 0)
		)
		(polygon
			(pts
				(xy 54.02 76.8) (xy 53.02 76.79) (xy 53.02 75.69) (xy 54.02 75.69)
			)
		)
	)
	(zone
		(net 148)
		(net_name "Net-(D12-Pad1)")
		(layer "B.Cu")
		(hatch edge 0.508)
		(connect_pads yes
			(clearance 0.125)
		)
		(min_thickness 0.254)
		(filled_areas_thickness no)
		(fill yes
			(thermal_gap 0.508)
			(thermal_bridge_width 0.508)
			(island_removal_mode 1)
			(island_area_min 0)
		)
		(polygon
			(pts
				(xy 48.82 95.69) (xy 47.02 95.69) (xy 47.02 93.79) (xy 48.82 93.79)
			)
		)
	)
	(zone
		(net 106)
		(net_name "GNDD")
		(layer "B.Cu")
		(hatch edge 0.508)
		(priority 1)
		(connect_pads yes
			(clearance 0.2)
		)
		(min_thickness 0.254)
		(filled_areas_thickness no)
		(fill yes
			(thermal_gap 0.508)
			(thermal_bridge_width 5)
		)
		(polygon
			(pts
				(xy 37.8 84.6) (xy 37.79 85.36) (xy 37.45 86.8) (xy 37.75 88.02) (xy 37.99 88.56) (xy 38.19 88.9)
				(xy 43.8 87.097904) (xy 43.8 84.4) (xy 50.8 84.4) (xy 50.8 85.8) (xy 45.9 85.8) (xy 45.90326 86.422276)
				(xy 45.9 89.35) (xy 45.9 95.5) (xy 48.2 97.8) (xy 50 97.8) (xy 51 98.8) (xy 51 100.2) (xy 50.2 101.3)
				(xy 47.3 101.3) (xy 46.5 102) (xy 46.05 104.14) (xy 45.3 105.95) (xy 43 105.95) (xy 43 98.55) (xy 42.4 98.4)
				(xy 34.2 98.4) (xy 34.2 80.9) (xy 37.8 80.9)
			)
		)
	)
	(zone
		(net 1)
		(net_name "GND")
		(layer "B.Cu")
		(hatch edge 0.508)
		(priority 1)
		(connect_pads yes
			(clearance 0.125)
		)
		(min_thickness 0.254)
		(filled_areas_thickness no)
		(fill yes
			(thermal_gap 0.508)
			(thermal_bridge_width 0.508)
			(island_removal_mode 1)
			(island_area_min 0)
		)
		(polygon
			(pts
				(xy 62.02 107.99) (xy 60.82 107.99) (xy 60.82 107.29) (xy 62.02 107.29)
			)
		)
	)
	(zone
		(net 500)
		(net_name "POE_OUTPUT")
		(layer "B.Cu")
		(hatch edge 0.508)
		(priority 1)
		(connect_pads yes
			(clearance 0.3)
		)
		(min_thickness 0.254)
		(filled_areas_thickness no)
		(fill yes
			(thermal_gap 0.508)
			(thermal_bridge_width 5)
		)
		(polygon
			(pts
				(xy 40.2 73.2) (xy 42.1 73.2) (xy 42.1 77.3) (xy 42.425 77.3) (xy 42.425 79.05) (xy 39.05 79.05)
				(xy 34 77) (xy 30.4 77) (xy 30.4 72.8) (xy 32.6 72.8) (xy 32.6 69) (xy 40.2 69)
			)
		)
	)
	(zone
		(net 1)
		(net_name "GND")
		(layer "B.Cu")
		(hatch edge 0.508)
		(connect_pads yes
			(clearance 0.125)
		)
		(min_thickness 0.254)
		(filled_areas_thickness no)
		(fill yes
			(thermal_gap 0.508)
			(thermal_bridge_width 0.508)
			(island_removal_mode 1)
			(island_area_min 0)
		)
		(polygon
			(pts
				(xy 114.52 95.79) (xy 113.22 95.79) (xy 113.22 94.29) (xy 114.52 94.29)
			)
		)
	)
	(zone
		(net 1)
		(net_name "GND")
		(layer "B.Cu")
		(hatch edge 0.508)
		(priority 1)
		(connect_pads yes
			(clearance 0.2)
		)
		(min_thickness 0.254)
		(filled_areas_thickness no)
		(fill yes
			(thermal_gap 0.508)
			(thermal_bridge_width 0.508)
			(island_removal_mode 1)
			(island_area_min 0)
		)
		(polygon
			(pts
				(xy 62.82 110.59) (xy 60.82 110.59) (xy 60.82 109.34) (xy 62.82 109.34)
			)
		)
	)
	(zone
		(net 105)
		(net_name "/Ethernet/VDD")
		(layer "B.Cu")
		(hatch edge 0.508)
		(priority 2)
		(connect_pads yes
			(clearance 0.3)
		)
		(min_thickness 0.254)
		(filled_areas_thickness no)
		(fill yes
			(thermal_gap 0.508)
			(thermal_bridge_width 5)
		)
		(polygon
			(pts
				(xy 33.3 98.1) (xy 35.5 98.1) (xy 35.5 99.6) (xy 40.3 99.6) (xy 40.3 105.98) (xy 30.3 105.98) (xy 30.3 80.9)
				(xy 33.3 80.9)
			)
		)
	)
	(zone
		(net 105)
		(net_name "/Ethernet/VDD")
		(layer "B.Cu")
		(hatch edge 0.508)
		(connect_pads yes
			(clearance 0.2)
		)
		(min_thickness 0.254)
		(filled_areas_thickness no)
		(fill yes
			(thermal_gap 0.508)
			(thermal_bridge_width 5)
		)
		(polygon
			(pts
				(xy 55.9 89.1) (xy 55.4 89.6) (xy 55.4 91.8) (xy 55.4 92.2) (xy 55.4 93.6) (xy 53.8 93.6) (xy 53 94.4)
				(xy 53 96.1) (xy 51.3 96.1) (xy 51.3 91.6) (xy 52.3 90.6) (xy 52.3 89.1) (xy 54.8 89.1) (xy 55.4 88.5)
				(xy 55.4 86.158955) (xy 55.9 86.158955)
			)
		)
	)
	(zone
		(net 480)
		(net_name "USBPD1_HV")
		(layer "B.Cu")
		(hatch edge 0.508)
		(connect_pads yes
			(clearance 0.2)
		)
		(min_thickness 0.254)
		(filled_areas_thickness no)
		(fill yes
			(thermal_gap 0.508)
			(thermal_bridge_width 5)
		)
		(polygon
			(pts
				(xy 65.1 107) (xy 64.8 107.4) (xy 64.8 109.5) (xy 61 109.5) (xy 61 108.1) (xy 62.1 108.1) (xy 62.1 107)
				(xy 64.3 107) (xy 64.3 105.9) (xy 65.1 105.9)
			)
		)
	)
	(zone
		(net 787)
		(net_name "+5V_SoM")
		(layer "B.Cu")
		(hatch edge 0.5)
		(priority 27)
		(connect_pads
			(clearance 0)
		)
		(min_thickness 0.25)
		(filled_areas_thickness no)
		(fill yes
			(thermal_gap 0.5)
			(thermal_bridge_width 0.5)
		)
		(polygon
			(pts
				(xy 57.36 87.77) (xy 58.36 87.77) (xy 58.39 87.8) (xy 58.39 88.98) (xy 57.44 89.93) (xy 57.44 91.65)
				(xy 57.06 92.03) (xy 57.06 93.37) (xy 56.13 93.37) (xy 56.07 93.31) (xy 56.07 90.15) (xy 56.5 89.72)
				(xy 56.5 88.63)
			)
		)
	)
	(zone
		(net 787)
		(net_name "+5V_SoM")
		(layer "B.Cu")
		(hatch edge 0.5)
		(priority 21)
		(connect_pads yes
			(clearance 0.125)
		)
		(min_thickness 0.25)
		(filled_areas_thickness no)
		(fill yes
			(thermal_gap 0.2)
			(thermal_bridge_width 0.5)
		)
		(polygon
			(pts
				(xy 58.5 90.7) (xy 59.1 90.05) (xy 60.725 90.05) (xy 60.735 91.66) (xy 58.5 91.66)
			)
		)
	)
	(zone
		(net 196)
		(net_name "/USB Debug, DP/USBC3_VBUS")
		(layer "B.Cu")
		(hatch edge 0.508)
		(connect_pads yes
			(clearance 0.2)
		)
		(min_thickness 0.254)
		(filled_areas_thickness no)
		(fill yes
			(thermal_gap 0.508)
			(thermal_bridge_width 5)
		)
		(polygon
			(pts
				(xy 56.5 124.1) (xy 51.1 124.1) (xy 51.1 121.9) (xy 50.9 121.7) (xy 50.9 120.5) (xy 51.5 120.5)
				(xy 51.5 121.7) (xy 55.6 121.7) (xy 55.6 121) (xy 56.5 121)
			)
		)
	)
	(zone
		(net 87)
		(net_name "+3V3")
		(layer "B.Cu")
		(hatch edge 0.508)
		(priority 2)
		(connect_pads yes
			(clearance 0.2)
		)
		(min_thickness 0.254)
		(filled_areas_thickness no)
		(fill yes
			(thermal_gap 0.508)
			(thermal_bridge_width 5)
		)
		(polygon
			(pts
				(xy 133.35 118) (xy 133.85 118) (xy 133.85 118.75) (xy 132.15 118.75) (xy 132.15 118) (xy 132.5 118)
				(xy 132.5 114.65) (xy 133.35 114.65)
			)
		)
	)
	(zone
		(net 328)
		(net_name "/Supply/VCC_IN")
		(layer "B.Cu")
		(hatch edge 0.508)
		(priority 7)
		(connect_pads yes
			(clearance 0.2)
		)
		(min_thickness 0.254)
		(filled_areas_thickness no)
		(fill yes
			(thermal_gap 0.508)
			(thermal_bridge_width 5)
		)
		(polygon
			(pts
				(xy 70.9 114) (xy 61.2 114) (xy 61.2 110.25) (xy 64.4 110.25) (xy 64.4 111.35) (xy 68.6 111.35)
				(xy 68.6 109.55) (xy 70.9 109.55)
			)
		)
	)
	(zone
		(net 87)
		(net_name "+3V3")
		(layer "B.Cu")
		(hatch edge 0.508)
		(connect_pads yes
			(clearance 0.2)
		)
		(min_thickness 0.254)
		(filled_areas_thickness no)
		(fill yes
			(thermal_gap 0.508)
			(thermal_bridge_width 5)
		)
		(polygon
			(pts
				(xy 120.5 104.3) (xy 118.5 104.25) (xy 118 104.25) (xy 118 101.75) (xy 118.75 101) (xy 118.75 100.25)
				(xy 120.5 100.25)
			)
		)
	)
	(zone
		(net 1)
		(net_name "GND")
		(layer "B.Cu")
		(hatch edge 0.5)
		(priority 9)
		(connect_pads yes
			(clearance 0)
		)
		(min_thickness 0.25)
		(filled_areas_thickness no)
		(fill yes
			(thermal_gap 0.5)
			(thermal_bridge_width 0.5)
			(smoothing fillet)
			(radius 0.2)
		)
		(polygon
			(pts
				(xy 63.14 94.15) (xy 66.4 94.15) (xy 67.1 93.45) (xy 70.01 93.45) (xy 70.58 94.02) (xy 70.58 97.356923)
				(xy 74.86 97.355428) (xy 74.867286 93.45) (xy 78.05 90.33) (xy 78.05 89) (xy 67.96 89) (xy 66.849217 87.9)
				(xy 66.124725 87.9) (xy 63.829099 85.63) (xy 63.14 85.63)
			)
		)
	)
	(zone
		(net 99)
		(net_name "+5V")
		(layer "B.Cu")
		(hatch edge 0.5)
		(priority 21)
		(connect_pads yes
			(clearance 0.125)
		)
		(min_thickness 0.25)
		(filled_areas_thickness no)
		(fill yes
			(thermal_gap 0.2)
			(thermal_bridge_width 0.5)
		)
		(polygon
			(pts
				(xy 58.425 91.94) (xy 60.2 91.94) (xy 60.2 93) (xy 59.4 93.65) (xy 58.425 93.65)
			)
		)
	)
	(zone
		(net 270)
		(net_name "/USB3/USBC1_VBUS")
		(layer "B.Cu")
		(hatch edge 0.508)
		(connect_pads yes
			(clearance 0.2)
		)
		(min_thickness 0.254)
		(filled_areas_thickness no)
		(fill yes
			(thermal_gap 0.508)
			(thermal_bridge_width 5)
		)
		(polygon
			(pts
				(xy 115.05 117.6) (xy 115.05 120.1) (xy 111.8 120.1) (xy 111.8 119) (xy 111.6 118.85) (xy 106.45 118.85)
				(xy 105 120.223684) (xy 105 121.8) (xy 104.5 122.3) (xy 101.65 122.3) (xy 101.65 121.3) (xy 102.55 120.5)
				(xy 102.55 117.2) (xy 103.2 116.6) (xy 112.5 116.6)
			)
		)
	)
	(zone
		(net 1)
		(net_name "GND")
		(layer "B.Cu")
		(hatch edge 0.508)
		(connect_pads yes
			(clearance 0.125)
		)
		(min_thickness 0.254)
		(filled_areas_thickness no)
		(fill yes
			(thermal_gap 0.508)
			(thermal_bridge_width 0.508)
			(island_removal_mode 1)
			(island_area_min 0)
		)
		(polygon
			(pts
				(xy 98.52 75.79) (xy 97.62 75.79) (xy 97.62 74.69) (xy 98.52 74.69)
			)
		)
	)
	(zone
		(net 788)
		(net_name "VDD_SoM")
		(layer "B.Cu")
		(hatch edge 0.5)
		(priority 26)
		(connect_pads yes
			(clearance 0.125)
		)
		(min_thickness 0.25)
		(filled_areas_thickness no)
		(fill yes
			(thermal_gap 0.5)
			(thermal_bridge_width 0.5)
		)
		(polygon
			(pts
				(xy 50.309243 82.99) (xy 51.55 82.99) (xy 51.55 81.84) (xy 51.81 81.58) (xy 54.12 81.58) (xy 54.12 81.17)
				(xy 49.93 81.17) (xy 49.93 82.612793)
			)
		)
	)
	(zone
		(net 1)
		(net_name "GND")
		(layer "B.Cu")
		(hatch edge 0.508)
		(connect_pads yes
			(clearance 0.125)
		)
		(min_thickness 0.254)
		(filled_areas_thickness no)
		(fill yes
			(thermal_gap 0.508)
			(thermal_bridge_width 0.508)
			(island_removal_mode 1)
			(island_area_min 0)
		)
		(polygon
			(pts
				(xy 114.52 93.69) (xy 112.22 93.69) (xy 112.22 90.39) (xy 114.52 90.39)
			)
		)
	)
	(zone
		(net 99)
		(net_name "+5V")
		(layer "B.Cu")
		(hatch edge 0.508)
		(priority 4)
		(connect_pads yes
			(clearance 0.125)
		)
		(min_thickness 0.125)
		(filled_areas_thickness no)
		(fill yes
			(thermal_gap 0.508)
			(thermal_bridge_width 0.508)
		)
		(polygon
			(pts
				(xy 96.35 85.8) (xy 97.45 85.8) (xy 97.45 86.9) (xy 95.65 86.9) (xy 95.65 84.45) (xy 96.15 83.95)
				(xy 96.15 82.37) (xy 96.9 82.37) (xy 96.9 84) (xy 96.35 84.7)
			)
		)
	)
	(zone
		(net 499)
		(net_name "/Ethernet/VSS")
		(layer "B.Cu")
		(hatch edge 0.508)
		(priority 2)
		(connect_pads yes
			(clearance 0.2)
		)
		(min_thickness 0.254)
		(filled_areas_thickness no)
		(fill yes
			(thermal_gap 0.508)
			(thermal_bridge_width 5)
		)
		(polygon
			(pts
				(xy 46.8 90.2) (xy 49.4 90.2) (xy 49.4 88.4) (xy 51.3 88.4) (xy 51.3 96.1) (xy 48.9 96.1) (xy 48.9 93.7)
				(xy 47 93.7) (xy 47 91.7) (xy 46.1 91.7) (xy 46.1 86.3) (xy 46.8 86.3)
			)
		)
	)
	(zone
		(net 635)
		(net_name "/M.2/3V3_M2")
		(layer "B.Cu")
		(hatch edge 0.508)
		(connect_pads
			(clearance 0.2)
		)
		(min_thickness 0.254)
		(filled_areas_thickness no)
		(fill yes
			(thermal_gap 0.254)
			(thermal_bridge_width 0.3)
		)
		(polygon
			(pts
				(xy 121.5 83.5) (xy 121.5 89.35) (xy 119.75 89.35) (xy 119.75 97.99) (xy 120.33 98.05) (xy 120.33 99.65)
				(xy 114.75 99.65) (xy 114.75 91) (xy 117.75 91) (xy 117.75 79) (xy 114.5 79) (xy 114.5 77.25) (xy 121.5 77.25)
			)
		)
	)
	(zone
		(net 481)
		(net_name "USBPD2_HV")
		(layer "B.Cu")
		(hatch edge 0.508)
		(connect_pads yes
			(clearance 0.2)
		)
		(min_thickness 0.254)
		(filled_areas_thickness no)
		(fill yes
			(thermal_gap 0.508)
			(thermal_bridge_width 5)
		)
		(polygon
			(pts
				(xy 69.9 106.8) (xy 73.4 106.8) (xy 73.4 111.9) (xy 72.1 111.9) (xy 72.1 108.1) (xy 69.7 108.1)
				(xy 68.8 107.2) (xy 68.3 107.2) (xy 68.3 106) (xy 69.9 106)
			)
		)
	)
	(zone
		(net 328)
		(net_name "/Supply/VCC_IN")
		(layer "B.Cu")
		(hatch edge 0.508)
		(priority 2)
		(connect_pads yes
			(clearance 0.2)
		)
		(min_thickness 0.254)
		(filled_areas_thickness no)
		(fill yes
			(thermal_gap 0.508)
			(thermal_bridge_width 5)
		)
		(polygon
			(pts
				(xy 49.375 80.2) (xy 45.72 80.2) (xy 45.72 82.7) (xy 43.55 82.7) (xy 43.55 78.2) (xy 45.675 78.2)
				(xy 45.675 76.96) (xy 49.375 76.96)
			)
		)
	)
	(zone
		(net 1)
		(net_name "GND")
		(layer "B.Cu")
		(hatch edge 0.508)
		(connect_pads
			(clearance 0.2)
		)
		(min_thickness 0.254)
		(filled_areas_thickness no)
		(fill yes
			(thermal_gap 0.254)
			(thermal_bridge_width 0.3)
		)
		(polygon
			(pts
				(xy 126.25 77.25) (xy 126.25 79.25) (xy 125.25 79.25) (xy 125.25 78.75) (xy 123.5 78.75) (xy 123.5 79.5)
				(xy 122.5 79.5) (xy 122.5 77.25) (xy 122 77.25) (xy 122 75.75) (xy 126.25 75.75)
			)
		)
	)
	(zone
		(net 87)
		(net_name "+3V3")
		(layer "B.Cu")
		(hatch edge 0.508)
		(priority 100)
		(connect_pads yes
			(clearance 0.125)
		)
		(min_thickness 0.125)
		(filled_areas_thickness no)
		(fill yes
			(thermal_gap 0.508)
			(thermal_bridge_width 5)
		)
		(polygon
			(pts
				(xy 93.35 84.95) (xy 95.6 84.95) (xy 95.6 86.3) (xy 94.5 86.3) (xy 94.5 85.75) (xy 92.5 85.75) (xy 92.5 82.4)
				(xy 93.35 82.4)
			)
		)
	)
	(zone
		(net 99)
		(net_name "+5V")
		(layer "B.Cu")
		(hatch edge 0.508)
		(priority 2)
		(connect_pads yes
			(clearance 0.2)
		)
		(min_thickness 0.254)
		(filled_areas_thickness no)
		(fill yes
			(thermal_gap 0.508)
			(thermal_bridge_width 5)
		)
		(polygon
			(pts
				(xy 136.75 118) (xy 137.15 118) (xy 137.15 118.8) (xy 134.85 118.8) (xy 134.85 118) (xy 135.75 118)
				(xy 135.75 114.7) (xy 136.75 114.7)
			)
		)
	)
	(zone
		(net 115)
		(net_name "VCC")
		(layer "B.Cu")
		(hatch edge 0.5)
		(priority 23)
		(connect_pads yes
			(clearance 0)
		)
		(min_thickness 0.25)
		(filled_areas_thickness no)
		(fill yes
			(thermal_gap 0.3)
			(thermal_bridge_width 0.5)
		)
		(polygon
			(pts
				(xy 63.05 92.2) (xy 64.03 91.22) (xy 64.86 91.22) (xy 64.86 94.16) (xy 63.66 94.16) (xy 63.05 93.55)
			)
		)
	)
	(zone
		(net 110)
		(net_name "/CSI/CSIB_3V3")
		(layer "B.Cu")
		(hatch edge 0.508)
		(priority 2)
		(connect_pads yes
			(clearance 0.2)
		)
		(min_thickness 0.254)
		(filled_areas_thickness no)
		(fill yes
			(thermal_gap 0.508)
			(thermal_bridge_width 5)
		)
		(polygon
			(pts
				(xy 100.25 74.6) (xy 99.55 75.2) (xy 99.5 75.7) (xy 98.55 75.7) (xy 98.55 74.2) (xy 99.3 74.2) (xy 99.3 72.85)
				(xy 100.25 72.85)
			)
		)
	)
	(zone
		(net 1)
		(net_name "GND")
		(layer "B.Cu")
		(hatch edge 0.5)
		(priority 22)
		(connect_pads yes
			(clearance 0)
		)
		(min_thickness 0.25)
		(filled_areas_thickness no)
		(fill yes
			(thermal_gap 0.2)
			(thermal_bridge_width 0.5)
		)
		(polygon
			(pts
				(xy 55.905 95.22) (xy 55.905 96.83) (xy 62.569071 96.83) (xy 62.566721 96.135663) (xy 63.044679 95.665392)
				(xy 63.702826 95.66643) (xy 63.684999 84.81) (xy 61.625 84.81) (xy 61.625 91.564701) (xy 57.829785 95.22)
			)
		)
	)
	(zone
		(net 1)
		(net_name "GND")
		(layer "B.Cu")
		(hatch edge 0.5)
		(priority 14)
		(connect_pads
			(clearance 0)
		)
		(min_thickness 0.25)
		(filled_areas_thickness no)
		(fill yes
			(thermal_gap 0.3)
			(thermal_bridge_width 0.5)
		)
		(polygon
			(pts
				(xy 59.76 86.63) (xy 59.88 86.5) (xy 59.88 84.58) (xy 60.88 84.58) (xy 61.63 85.28) (xy 63.47 85.28)
				(xy 63.68 85.07) (xy 63.68 83.63) (xy 63.32 83.5) (xy 62.3 84.45) (xy 61.77 84.45) (xy 60.465046 83.18)
				(xy 59.287523 83.18) (xy 58.11 83.18) (xy 58.11 81.93) (xy 57.3 81.93) (xy 56.49 82.74) (xy 56.49 85.88)
				(xy 58.04 85.88) (xy 58.04 84.49) (xy 59.3 84.49) (xy 59.3 86.49) (xy 59.43 86.63)
			)
		)
	)
	(zone
		(net 108)
		(net_name "/CSI/CSIA_3V3")
		(layer "B.Cu")
		(hatch edge 0.508)
		(priority 1)
		(connect_pads
			(clearance 0.2)
		)
		(min_thickness 0.254)
		(filled_areas_thickness no)
		(fill yes
			(thermal_gap 0.125)
			(thermal_bridge_width 0.3)
		)
		(polygon
			(pts
				(xy 143.75 106.15) (xy 143.75 106.25) (xy 135.95 106.25) (xy 135.9 112.05) (xy 133.3 112.05) (xy 133.3 113.3)
				(xy 132.6 113.3) (xy 132.6 110.75) (xy 134.75 110.75) (xy 134.75 105) (xy 143.75 105)
			)
		)
	)
	(zone
		(net 111)
		(net_name "/CSI/CSIB_5V")
		(layer "B.Cu")
		(hatch edge 0.508)
		(priority 3)
		(connect_pads yes
			(clearance 0.2)
		)
		(min_thickness 0.254)
		(filled_areas_thickness no)
		(fill yes
			(thermal_gap 0.508)
			(thermal_bridge_width 5)
		)
		(polygon
			(pts
				(xy 101.3 74.8) (xy 101.45 74.8) (xy 101.45 75.7) (xy 100.45 75.7) (xy 100.45 74.8) (xy 100.25 74.8)
				(xy 100.25 72.85) (xy 101.3 72.85)
			)
		)
	)
	(zone
		(net 109)
		(net_name "/CSI/CSIA_5V")
		(layer "B.Cu")
		(hatch edge 0.508)
		(priority 2)
		(connect_pads
			(clearance 0.2)
		)
		(min_thickness 0.254)
		(filled_areas_thickness no)
		(fill yes
			(thermal_gap 0.254)
			(thermal_bridge_width 0.3)
		)
		(polygon
			(pts
				(xy 143.75 107.45) (xy 137 107.45) (xy 137 113.3) (xy 136 113.3) (xy 136 106.325) (xy 143.75 106.325)
			)
		)
	)
	(zone
		(net 196)
		(net_name "/USB Debug, DP/USBC3_VBUS")
		(layer "B.Cu")
		(hatch edge 0.508)
		(priority 1)
		(connect_pads yes
			(clearance 0.2)
		)
		(min_thickness 0.254)
		(filled_areas_thickness no)
		(fill yes
			(thermal_gap 0.508)
			(thermal_bridge_width 5)
		)
		(polygon
			(pts
				(xy 64.4 107) (xy 60.6 107) (xy 60.6 119.6) (xy 56.7 119.6) (xy 56.7 120.1) (xy 56.4 120.4) (xy 56.4 121.8)
				(xy 55.6 121.8) (xy 55.6 120.3) (xy 55 119.7) (xy 55 117.2) (xy 56 116.2) (xy 56 114.1) (xy 58.3 114.1)
				(xy 58.7 113.7) (xy 58.7 105.9) (xy 64.4 105.9)
			)
		)
	)
	(zone
		(net 1)
		(net_name "GND")
		(layer "B.Cu")
		(hatch edge 0.508)
		(connect_pads yes
			(clearance 0.2)
		)
		(min_thickness 0.2)
		(filled_areas_thickness no)
		(fill yes
			(thermal_gap 0.508)
			(thermal_bridge_width 5)
		)
		(polygon
			(pts
				(xy 76.55 106.95) (xy 77.5 106.95) (xy 77.5 108.8) (xy 76.6 108.8) (xy 76.6 108.2) (xy 73.6 108.2)
				(xy 73.6 105.4) (xy 76.55 105.45)
			)
		)
	)
	(zone
		(net 136)
		(net_name "Net-(J6-P4)")
		(layer "B.Cu")
		(hatch edge 0.508)
		(connect_pads yes
			(clearance 0.2)
		)
		(min_thickness 0.254)
		(filled_areas_thickness no)
		(fill yes
			(thermal_gap 0.508)
			(thermal_bridge_width 5)
		)
		(polygon
			(pts
				(xy 39.3 109.6) (xy 38.8 110.1) (xy 38.8 111.6) (xy 38.8 112.1) (xy 38.8 112.85) (xy 36.3 112.85)
				(xy 36.3 110.6) (xy 37.3 109.6) (xy 37.3 108.6) (xy 38.3 107.6) (xy 39.3 107.6)
			)
		)
	)
	(zone
		(net 0)
		(net_name "")
		(layers "B.Cu" "B.SilkS")
		(name "allow_overlap")
		(hatch edge 0.5)
		(connect_pads
			(clearance 0)
		)
		(min_thickness 0.25)
		(filled_areas_thickness no)
		(keepout
			(tracks allowed)
			(vias allowed)
			(pads allowed)
			(copperpour allowed)
			(footprints allowed)
		)
		(fill
			(thermal_gap 0.5)
			(thermal_bridge_width 0.5)
		)
		(polygon
			(pts
				(xy 114.9 71.575) (xy 114.9 70.585) (xy 117.8 70.585) (xy 117.800001 71.575)
			)
		)
	)
	(zone
		(net 0)
		(net_name "")
		(layers "B.Cu" "B.SilkS")
		(name "allow_overlap")
		(hatch edge 0.5)
		(connect_pads
			(clearance 0)
		)
		(min_thickness 0.25)
		(filled_areas_thickness no)
		(keepout
			(tracks allowed)
			(vias allowed)
			(pads allowed)
			(copperpour allowed)
			(footprints allowed)
		)
		(fill
			(thermal_gap 0.5)
			(thermal_bridge_width 0.5)
		)
		(polygon
			(pts
				(xy 128.149999 95.275) (xy 128.149999 93.96) (xy 131.049999 93.96) (xy 131.05 95.275)
			)
		)
	)
	(zone
		(net 0)
		(net_name "")
		(layer "Cmts.User")
		(hatch edge 0.508)
		(connect_pads
			(clearance 0)
		)
		(min_thickness 0.254)
		(filled_areas_thickness no)
		(keepout
			(tracks allowed)
			(vias allowed)
			(pads allowed)
			(copperpour not_allowed)
			(footprints allowed)
		)
		(fill
			(thermal_gap 0.508)
			(thermal_bridge_width 0.508)
		)
		(polygon
			(pts
				(xy 43.28389 71.545694) (xy 43.264248 71.296115) (xy 43.205805 71.052682) (xy 43.11 70.821388) (xy 42.979192 70.607929)
				(xy 42.816602 70.417561) (xy 42.626234 70.254971) (xy 42.412775 70.124163) (xy 42.181481 70.028358)
				(xy 41.938048 69.969915) (xy 41.688469 69.950273) (xy 41.43889 69.969915) (xy 41.195457 70.028358)
				(xy 40.964163 70.124163) (xy 40.750704 70.254971) (xy 40.560336 70.417561) (xy 40.397746 70.607929)
				(xy 40.266938 70.821388) (xy 40.171133 71.052682) (xy 40.11269 71.296115) (xy 40.093048 71.545694)
				(xy 40.11269 71.795273) (xy 40.171133 72.038706) (xy 40.266938 72.27) (xy 40.397746 72.483459) (xy 40.560336 72.673827)
				(xy 40.750704 72.836417) (xy 40.964163 72.967225) (xy 41.195457 73.06303) (xy 41.43889 73.121473)
				(xy 41.688469 73.141115) (xy 41.938048 73.121473) (xy 42.181481 73.06303) (xy 42.412775 72.967225)
				(xy 42.626234 72.836417) (xy 42.816602 72.673827) (xy 42.979192 72.483459) (xy 43.11 72.27) (xy 43.205805 72.038706)
				(xy 43.264248 71.795273)
			)
		)
	)
	(zone
		(net 0)
		(net_name "")
		(layer "Cmts.User")
		(hatch edge 0.508)
		(connect_pads yes
			(clearance 0)
		)
		(min_thickness 0.254)
		(filled_areas_thickness no)
		(keepout
			(tracks allowed)
			(vias allowed)
			(pads allowed)
			(copperpour not_allowed)
			(footprints allowed)
		)
		(fill
			(thermal_gap 0.508)
			(thermal_bridge_width 5)
		)
		(polygon
			(pts
				(xy 40.621246 76.26698) (xy 40.601622 75.904625) (xy 40.542978 75.546509) (xy 40.446001 75.19682)
				(xy 40.311825 74.859651) (xy 40.142019 74.538945) (xy 39.938571 74.238453) (xy 39.70386 73.961691)
				(xy 39.440632 73.711897) (xy 39.151966 73.491992) (xy 38.841238 73.30455) (xy 38.512085 73.151761)
				(xy 38.168355 73.035415) (xy 37.814071 72.956873) (xy 37.453376 72.917051) (xy 37.09049 72.916418)
				(xy 36.729659 72.95498) (xy 36.375103 73.032286) (xy 36.030969 73.147431) (xy 35.701284 73.299069)
				(xy 35.389904 73.485426) (xy 35.100472 73.704322) (xy 34.836374 73.953196) (xy 34.600698 74.229137)
				(xy 34.396202 74.528916) (xy 34.225278 74.849028) (xy 34.089926 75.185727) (xy 33.991729 75.535075)
				(xy 33.931836 75.892984) (xy 33.910946 76.255268) (xy 33.929306 76.61769) (xy 33.986699 76.976009)
				(xy 34.082455 77.326033) (xy 34.215453 77.663669) (xy 34.384138 77.984966) (xy 34.586536 78.286166)
				(xy 34.82028 78.563745) (xy 35.082634 78.814457) (xy 35.370531 79.035368) (xy 35.680603 79.223894)
				(xy 36.009221 79.37783) (xy 36.352542 79.495375) (xy 36.70655 79.575154) (xy 37.067104 79.616234)
				(xy 37.429985 79.618134) (xy 37.790949 79.580832) (xy 38.145773 79.504765) (xy 38.490306 79.390821)
				(xy 38.820518 79.240335) (xy 39.132547 79.055066) (xy 39.422741 78.837182) (xy 39.687707 78.589231)
				(xy 39.924345 78.314115) (xy 40.129885 78.015051) (xy 40.301926 77.695538) (xy 40.438452 77.359313)
				(xy 40.537868 77.010311) (xy 40.599011 76.652613) (xy 40.621164 76.290403)
			)
		)
	)
)
